G04 ================== begin FILE IDENTIFICATION RECORD ==================*
G04 Layout Name:  9324_DA0F0TMBIJ0_F0T_Motherboard_J_v01_20230324_0910.brd*
G04 Film Name:    gnd5*
G04 File Format:  Gerber RS274X*
G04 File Origin:  Cadence Allegro 17.2-S081*
G04 Origin Date:  Sat Mar 25 08:45:09 2023*
G04 *
G04 Layer:  DRAWING FORMAT/TITLE_BLOCK_A*
G04 Layer:  PIN/SPECIAL_DRILL*
G04 Layer:  VIA CLASS/GND5*
G04 Layer:  PIN/GND5*
G04 Layer:  MANUFACTURING/PHOTOPLOT_OUTLINE*
G04 Layer:  ETCH/GND5*
G04 Layer:  DRAWING FORMAT/TITLE_BLOCK*
G04 Layer:  DRAWING FORMAT/TITLE_DATA_GND5*
G04 *
G04 Offset:    (0.00 0.00)*
G04 Mirror:    No*
G04 Mode:      Negative*
G04 Rotation:  0*
G04 FullContactRelief:  No*
G04 UndefLineWidth:     6.00*
G04 ================== end FILE IDENTIFICATION RECORD ====================*
%FSLAX25Y25*MOIN*%
%IR0*IPPOS*OFA0.00000B0.00000*MIA0B0*SFA1.00000B1.00000*%
%ADD15C,.03*%
%ADD31C,.06*%
%ADD46C,.061*%
%ADD27C,.07*%
%AMMACRO55*
4,1,36,0.0,.01,
-.001736,.009848,
-.00342,.009397,
-.005,.00866,
-.006428,.00766,
-.00766,.006428,
-.00866,.005,
-.009397,.00342,
-.009848,.001736,
-.01,0.0,
-.009848,-.001736,
-.009397,-.00342,
-.00866,-.005,
-.00766,-.006428,
-.006428,-.00766,
-.005,-.00866,
-.00342,-.009397,
-.001736,-.009848,
0.0,-.01,
.001736,-.009848,
.00342,-.009397,
.005,-.00866,
.006428,-.00766,
.00766,-.006428,
.00866,-.005,
.009397,-.00342,
.009848,-.001736,
.01,0.0,
.009848,.001736,
.009397,.00342,
.00866,.005,
.00766,.006428,
.006428,.00766,
.005,.00866,
.00342,.009397,
.001736,.009848,
0.0,.01,
0.0*
%
%ADD55MACRO55*%
%ADD52C,.071*%
%ADD29C,.062*%
%ADD17C,.026*%
%AMMACRO71*
4,1,36,.0025,0.0,
.002462,.000434,
.002349,.000855,
.002165,.00125,
.001915,.001607,
.001607,.001915,
.00125,.002165,
.000855,.002349,
.000434,.002462,
0.0,.0025,
-.000434,.002462,
-.000855,.002349,
-.00125,.002165,
-.001607,.001915,
-.001915,.001607,
-.002165,.00125,
-.002349,.000855,
-.002462,.000434,
-.0025,0.0,
-.002462,-.000434,
-.002349,-.000855,
-.002165,-.00125,
-.001915,-.001607,
-.001607,-.001915,
-.00125,-.002165,
-.000855,-.002349,
-.000434,-.002462,
0.0,-.0025,
.000434,-.002462,
.000855,-.002349,
.00125,-.002165,
.001607,-.001915,
.001915,-.001607,
.002165,-.00125,
.002349,-.000855,
.002462,-.000434,
.0025,0.0,
135.*
%
%ADD71MACRO71*%
%ADD67C,.064*%
%AMMACRO19*
4,1,36,.0025,0.0,
.002462,.000434,
.002349,.000855,
.002165,.00125,
.001915,.001607,
.001607,.001915,
.00125,.002165,
.000855,.002349,
.000434,.002462,
0.0,.0025,
-.000434,.002462,
-.000855,.002349,
-.00125,.002165,
-.001607,.001915,
-.001915,.001607,
-.002165,.00125,
-.002349,.000855,
-.002462,.000434,
-.0025,0.0,
-.002462,-.000434,
-.002349,-.000855,
-.002165,-.00125,
-.001915,-.001607,
-.001607,-.001915,
-.00125,-.002165,
-.000855,-.002349,
-.000434,-.002462,
0.0,-.0025,
.000434,-.002462,
.000855,-.002349,
.00125,-.002165,
.001607,-.001915,
.001915,-.001607,
.002165,-.00125,
.002349,-.000855,
.002462,-.000434,
.0025,0.0,
225.*
%
%ADD19MACRO19*%
%AMMACRO14*
4,1,36,.0025,0.0,
.002462,.000434,
.002349,.000855,
.002165,.00125,
.001915,.001607,
.001607,.001915,
.00125,.002165,
.000855,.002349,
.000434,.002462,
0.0,.0025,
-.000434,.002462,
-.000855,.002349,
-.00125,.002165,
-.001607,.001915,
-.001915,.001607,
-.002165,.00125,
-.002349,.000855,
-.002462,.000434,
-.0025,0.0,
-.002462,-.000434,
-.002349,-.000855,
-.002165,-.00125,
-.001915,-.001607,
-.001607,-.001915,
-.00125,-.002165,
-.000855,-.002349,
-.000434,-.002462,
0.0,-.0025,
.000434,-.002462,
.000855,-.002349,
.00125,-.002165,
.001607,-.001915,
.001915,-.001607,
.002165,-.00125,
.002349,-.000855,
.002462,-.000434,
.0025,0.0,
180.*
%
%ADD14MACRO14*%
%AMMACRO11*
4,1,36,.0025,0.0,
.002462,.000434,
.002349,.000855,
.002165,.00125,
.001915,.001607,
.001607,.001915,
.00125,.002165,
.000855,.002349,
.000434,.002462,
0.0,.0025,
-.000434,.002462,
-.000855,.002349,
-.00125,.002165,
-.001607,.001915,
-.001915,.001607,
-.002165,.00125,
-.002349,.000855,
-.002462,.000434,
-.0025,0.0,
-.002462,-.000434,
-.002349,-.000855,
-.002165,-.00125,
-.001915,-.001607,
-.001607,-.001915,
-.00125,-.002165,
-.000855,-.002349,
-.000434,-.002462,
0.0,-.0025,
.000434,-.002462,
.000855,-.002349,
.00125,-.002165,
.001607,-.001915,
.001915,-.001607,
.002165,-.00125,
.002349,-.000855,
.002462,-.000434,
.0025,0.0,
270.*
%
%ADD11MACRO11*%
%AMMACRO53*
4,1,36,-.0025,0.0,
-.002462,.000434,
-.002349,.000855,
-.002165,.00125,
-.001915,.001607,
-.001607,.001915,
-.00125,.002165,
-.000855,.002349,
-.000434,.002462,
0.0,.0025,
.000434,.002462,
.000855,.002349,
.00125,.002165,
.001607,.001915,
.001915,.001607,
.002165,.00125,
.002349,.000855,
.002462,.000434,
.0025,0.0,
.002462,-.000434,
.002349,-.000855,
.002165,-.00125,
.001915,-.001607,
.001607,-.001915,
.00125,-.002165,
.000855,-.002349,
.000434,-.002462,
0.0,-.0025,
-.000434,-.002462,
-.000855,-.002349,
-.00125,-.002165,
-.001607,-.001915,
-.001915,-.001607,
-.002165,-.00125,
-.002349,-.000855,
-.002462,-.000434,
-.0025,0.0,
180.*
%
%ADD53MACRO53*%
%AMMACRO44*
4,1,36,.003,0.0,
.002954,.000521,
.002819,.001026,
.002598,.0015,
.002298,.001928,
.001928,.002298,
.0015,.002598,
.001026,.002819,
.000521,.002954,
0.0,.003,
-.000521,.002954,
-.001026,.002819,
-.0015,.002598,
-.001928,.002298,
-.002298,.001928,
-.002598,.0015,
-.002819,.001026,
-.002954,.000521,
-.003,0.0,
-.002954,-.000521,
-.002819,-.001026,
-.002598,-.0015,
-.002298,-.001928,
-.001928,-.002298,
-.0015,-.002598,
-.001026,-.002819,
-.000521,-.002954,
0.0,-.003,
.000521,-.002954,
.001026,-.002819,
.0015,-.002598,
.001928,-.002298,
.002298,-.001928,
.002598,-.0015,
.002819,-.001026,
.002954,-.000521,
.003,0.0,
270.*
%
%ADD44MACRO44*%
%AMMACRO42*
4,1,36,.003,0.0,
.002954,.000521,
.002819,.001026,
.002598,.0015,
.002298,.001928,
.001928,.002298,
.0015,.002598,
.001026,.002819,
.000521,.002954,
0.0,.003,
-.000521,.002954,
-.001026,.002819,
-.0015,.002598,
-.001928,.002298,
-.002298,.001928,
-.002598,.0015,
-.002819,.001026,
-.002954,.000521,
-.003,0.0,
-.002954,-.000521,
-.002819,-.001026,
-.002598,-.0015,
-.002298,-.001928,
-.001928,-.002298,
-.0015,-.002598,
-.001026,-.002819,
-.000521,-.002954,
0.0,-.003,
.000521,-.002954,
.001026,-.002819,
.0015,-.002598,
.001928,-.002298,
.002298,-.001928,
.002598,-.0015,
.002819,-.001026,
.002954,-.000521,
.003,0.0,
180.*
%
%ADD42MACRO42*%
%ADD26C,.074*%
%AMMACRO74*
4,1,36,-.003,0.0,
-.002954,.000521,
-.002819,.001026,
-.002598,.0015,
-.002298,.001928,
-.001928,.002298,
-.0015,.002598,
-.001026,.002819,
-.000521,.002954,
0.0,.003,
.000521,.002954,
.001026,.002819,
.0015,.002598,
.001928,.002298,
.002298,.001928,
.002598,.0015,
.002819,.001026,
.002954,.000521,
.003,0.0,
.002954,-.000521,
.002819,-.001026,
.002598,-.0015,
.002298,-.001928,
.001928,-.002298,
.0015,-.002598,
.001026,-.002819,
.000521,-.002954,
0.0,-.003,
-.000521,-.002954,
-.001026,-.002819,
-.0015,-.002598,
-.001928,-.002298,
-.002298,-.001928,
-.002598,-.0015,
-.002819,-.001026,
-.002954,-.000521,
-.003,0.0,
270.*
%
%ADD74MACRO74*%
%ADD73C,.0435*%
%ADD63C,.06015*%
%ADD50C,.076*%
%ADD49C,.095*%
%ADD24C,.0257*%
%ADD76C,.087*%
%ADD35C,.03417*%
%ADD41C,.0259*%
%ADD22C,.0277*%
%AMMACRO40*
4,1,15,.06231,.03403,
.067273,.022693,
.070191,.010666,
.070977,-.001684,
.069606,-.013984,
.066121,-.025858,
.06231,-.03403,
.06745,-.03917,
.073227,-.026862,
.076779,-.013739,
.077998,-.000197,
.076848,.01335,
.073362,.026492,
.067647,.038828,
.06745,.03917,
.06231,.03403,
0.0*
4,1,15,.03403,-.06231,
.022693,-.067273,
.010666,-.070191,
-.001684,-.070977,
-.013984,-.069606,
-.025858,-.066121,
-.03403,-.06231,
-.03917,-.06745,
-.026862,-.073227,
-.013739,-.076779,
-.000197,-.077998,
.01335,-.076848,
.026492,-.073362,
.038828,-.067647,
.03917,-.06745,
.03403,-.06231,
0.0*
4,1,15,-.06231,-.03403,
-.067273,-.022693,
-.070191,-.010666,
-.070977,.001684,
-.069606,.013984,
-.066121,.025858,
-.06231,.03403,
-.06745,.03917,
-.073227,.026862,
-.076779,.013739,
-.077998,.000197,
-.076848,-.01335,
-.073362,-.026492,
-.067647,-.038828,
-.06745,-.03917,
-.06231,-.03403,
0.0*
4,1,15,-.03403,.06231,
-.022693,.067273,
-.010666,.070191,
.001684,.070977,
.013984,.069606,
.025858,.066121,
.03403,.06231,
.03917,.06745,
.026862,.073227,
.013739,.076779,
.000197,.077998,
-.01335,.076848,
-.026492,.073362,
-.038828,.067647,
-.03917,.06745,
-.03403,.06231,
0.0*
%
%ADD40MACRO40*%
%AMMACRO10*
4,1,18,.09673,.06845,
.107147,.050613,
.114308,.031238,
.117996,.010914,
.118098,-.009741,
.114613,-.030101,
.107644,-.049546,
.097406,-.067485,
.09673,-.06845,
.10175,-.07347,
.112962,-.054685,
.120742,-.034239,
.124853,-.012752,
.125171,.009122,
.121685,.030719,
.114502,.051383,
.10384,.070486,
.10175,.07347,
.09673,.06845,
0.0*
4,1,18,.06845,-.09673,
.050613,-.107147,
.031238,-.114308,
.010914,-.117996,
-.009741,-.118098,
-.030101,-.114613,
-.049546,-.107644,
-.067485,-.097406,
-.06845,-.09673,
-.07347,-.10175,
-.054685,-.112962,
-.034239,-.120742,
-.012752,-.124853,
.009122,-.125171,
.030719,-.121685,
.051383,-.114502,
.070486,-.10384,
.07347,-.10175,
.06845,-.09673,
0.0*
4,1,18,-.09673,-.06845,
-.107147,-.050613,
-.114308,-.031238,
-.117996,-.010914,
-.118098,.009741,
-.114613,.030101,
-.107644,.049546,
-.097406,.067485,
-.09673,.06845,
-.10175,.07347,
-.112962,.054685,
-.120742,.034239,
-.124853,.012752,
-.125171,-.009122,
-.121685,-.030719,
-.114502,-.051383,
-.10384,-.070486,
-.10175,-.07347,
-.09673,-.06845,
0.0*
4,1,18,-.06845,.09673,
-.050613,.107147,
-.031238,.114308,
-.010914,.117996,
.009741,.118098,
.030101,.114613,
.049546,.107644,
.067485,.097406,
.06845,.09673,
.07347,.10175,
.054685,.112962,
.034239,.120742,
.012752,.124853,
-.009122,.125171,
-.030719,.121685,
-.051383,.114502,
-.070486,.10384,
-.07347,.10175,
-.06845,.09673,
0.0*
%
%ADD10MACRO10*%
%ADD36C,.03187*%
%AMMACRO37*
4,1,16,.0711,.04282,
.077455,.029823,
.081457,.01592,
.082984,.001533,
.08199,-.0129,
.078504,-.026942,
.072633,-.040164,
.0711,-.04282,
.07619,-.04791,
.083352,-.033952,
.087981,-.018962,
.089937,-.003396,
.089161,.012273,
.085675,.027569,
.079586,.042027,
.07619,.04791,
.0711,.04282,
0.0*
4,1,16,.04282,-.0711,
.029823,-.077455,
.01592,-.081457,
.001533,-.082984,
-.0129,-.08199,
-.026942,-.078504,
-.040164,-.072633,
-.04282,-.0711,
-.04791,-.07619,
-.033952,-.083352,
-.018962,-.087981,
-.003396,-.089937,
.012273,-.089161,
.027569,-.085675,
.042027,-.079586,
.04791,-.07619,
.04282,-.0711,
0.0*
4,1,16,-.0711,-.04282,
-.077455,-.029823,
-.081457,-.01592,
-.082984,-.001533,
-.08199,.0129,
-.078504,.026942,
-.072633,.040164,
-.0711,.04282,
-.07619,.04791,
-.083352,.033952,
-.087981,.018962,
-.089937,.003396,
-.089161,-.012273,
-.085675,-.027569,
-.079586,-.042027,
-.07619,-.04791,
-.0711,-.04282,
0.0*
4,1,16,-.04282,.0711,
-.029823,.077455,
-.01592,.081457,
-.001533,.082984,
.0129,.08199,
.026942,.078504,
.040164,.072633,
.04282,.0711,
.04791,.07619,
.033952,.083352,
.018962,.087981,
.003396,.089937,
-.012273,.089161,
-.027569,.085675,
-.042027,.079586,
-.04791,.07619,
-.04282,.0711,
0.0*
%
%ADD37MACRO37*%
%AMMACRO32*
4,1,15,.02438,.01377,
.026401,.009327,
.027619,.004601,
.027999,-.000265,
.027527,-.005123,
.02622,-.009825,
.02438,-.01377,
.02948,-.01887,
.032309,-.013464,
.034156,-.007649,
.034965,-.001602,
.034712,.004494,
.033405,.010454,
.031082,.016095,
.02948,.01887,
.02438,.01377,
90.*
4,1,15,.01377,-.02438,
.009327,-.026401,
.004601,-.027619,
-.000265,-.027999,
-.005123,-.027527,
-.009825,-.02622,
-.01377,-.02438,
-.01887,-.02948,
-.013464,-.032309,
-.007649,-.034156,
-.001602,-.034965,
.004494,-.034712,
.010454,-.033405,
.016095,-.031082,
.01887,-.02948,
.01377,-.02438,
90.*
4,1,15,-.02438,-.01377,
-.026401,-.009327,
-.027619,-.004601,
-.027999,.000265,
-.027527,.005123,
-.02622,.009825,
-.02438,.01377,
-.02948,.01887,
-.032309,.013464,
-.034156,.007649,
-.034965,.001602,
-.034712,-.004494,
-.033405,-.010454,
-.031082,-.016095,
-.02948,-.01887,
-.02438,-.01377,
90.*
4,1,15,-.01377,.02438,
-.009327,.026401,
-.004601,.027619,
.000265,.027999,
.005123,.027527,
.009825,.02622,
.01377,.02438,
.01887,.02948,
.013464,.032309,
.007649,.034156,
.001602,.034965,
-.004494,.034712,
-.010454,.033405,
-.016095,.031082,
-.01887,.02948,
-.01377,.02438,
90.*
%
%ADD32MACRO32*%
%AMMACRO30*
4,1,15,.02438,.01377,
.026401,.009327,
.027619,.004601,
.027999,-.000265,
.027527,-.005123,
.02622,-.009825,
.02438,-.01377,
.02948,-.01887,
.032309,-.013464,
.034156,-.007649,
.034965,-.001602,
.034712,.004494,
.033405,.010454,
.031082,.016095,
.02948,.01887,
.02438,.01377,
0.0*
4,1,15,.01377,-.02438,
.009327,-.026401,
.004601,-.027619,
-.000265,-.027999,
-.005123,-.027527,
-.009825,-.02622,
-.01377,-.02438,
-.01887,-.02948,
-.013464,-.032309,
-.007649,-.034156,
-.001602,-.034965,
.004494,-.034712,
.010454,-.033405,
.016095,-.031082,
.01887,-.02948,
.01377,-.02438,
0.0*
4,1,15,-.02438,-.01377,
-.026401,-.009327,
-.027619,-.004601,
-.027999,.000265,
-.027527,.005123,
-.02622,.009825,
-.02438,.01377,
-.02948,.01887,
-.032309,.013464,
-.034156,.007649,
-.034965,.001602,
-.034712,-.004494,
-.033405,-.010454,
-.031082,-.016095,
-.02948,-.01887,
-.02438,-.01377,
0.0*
4,1,15,-.01377,.02438,
-.009327,.026401,
-.004601,.027619,
.000265,.027999,
.005123,.027527,
.009825,.02622,
.01377,.02438,
.01887,.02948,
.013464,.032309,
.007649,.034156,
.001602,.034965,
-.004494,.034712,
-.010454,.033405,
-.016095,.031082,
-.01887,.02948,
-.01377,.02438,
0.0*
%
%ADD30MACRO30*%
%AMMACRO48*
4,1,15,.02475,.01414,
.026829,.009627,
.028094,.004822,
.028504,-.000129,
.028049,-.005077,
.026741,-.009871,
.02475,-.01414,
.02984,-.01923,
.032726,-.013756,
.034617,-.007864,
.035457,-.001734,
.03522,.00445,
.033912,.010498,
.031574,.016227,
.02984,.01923,
.02475,.01414,
90.*
4,1,15,.01414,-.02475,
.009627,-.026829,
.004822,-.028094,
-.000129,-.028504,
-.005077,-.028049,
-.009871,-.026741,
-.01414,-.02475,
-.01923,-.02984,
-.013756,-.032726,
-.007864,-.034617,
-.001734,-.035457,
.00445,-.03522,
.010498,-.033912,
.016227,-.031574,
.01923,-.02984,
.01414,-.02475,
90.*
4,1,15,-.02475,-.01414,
-.026829,-.009627,
-.028094,-.004822,
-.028504,.000129,
-.028049,.005077,
-.026741,.009871,
-.02475,.01414,
-.02984,.01923,
-.032726,.013756,
-.034617,.007864,
-.035457,.001734,
-.03522,-.00445,
-.033912,-.010498,
-.031574,-.016227,
-.02984,-.01923,
-.02475,-.01414,
90.*
4,1,15,-.01414,.02475,
-.009627,.026829,
-.004822,.028094,
.000129,.028504,
.005077,.028049,
.009871,.026741,
.01414,.02475,
.01923,.02984,
.013756,.032726,
.007864,.034617,
.001734,.035457,
-.00445,.03522,
-.010498,.033912,
-.016227,.031574,
-.01923,.02984,
-.01414,.02475,
90.*
%
%ADD48MACRO48*%
%AMMACRO66*
4,1,18,.07103,.05689,
.07983,.043691,
.086204,.029165,
.089959,.013753,
.09098,-.002077,
.089237,-.017844,
.084783,-.033069,
.077753,-.047289,
.07103,-.05689,
.07601,-.06186,
.085597,-.047721,
.092583,-.032132,
.096757,-.015567,
.09799,.001471,
.096246,.018464,
.091577,.034897,
.084126,.050269,
.07601,.06186,
.07103,.05689,
0.0*
4,1,18,.05689,-.07103,
.043691,-.07983,
.029165,-.086204,
.013753,-.089959,
-.002077,-.09098,
-.017844,-.089237,
-.033069,-.084783,
-.047289,-.077753,
-.05689,-.07103,
-.06186,-.07601,
-.047721,-.085597,
-.032132,-.092583,
-.015567,-.096757,
.001471,-.09799,
.018464,-.096246,
.034897,-.091577,
.050269,-.084126,
.06186,-.07601,
.05689,-.07103,
0.0*
4,1,18,-.07103,-.05689,
-.07983,-.043691,
-.086204,-.029165,
-.089959,-.013753,
-.09098,.002077,
-.089237,.017844,
-.084783,.033069,
-.077753,.047289,
-.07103,.05689,
-.07601,.06186,
-.085597,.047721,
-.092583,.032132,
-.096757,.015567,
-.09799,-.001471,
-.096246,-.018464,
-.091577,-.034897,
-.084126,-.050269,
-.07601,-.06186,
-.07103,-.05689,
0.0*
4,1,18,-.05689,.07103,
-.043691,.07983,
-.029165,.086204,
-.013753,.089959,
.002077,.09098,
.017844,.089237,
.033069,.084783,
.047289,.077753,
.05689,.07103,
.06186,.07601,
.047721,.085597,
.032132,.092583,
.015567,.096757,
-.001471,.09799,
-.018464,.096246,
-.034897,.091577,
-.050269,.084126,
-.06186,.07601,
-.05689,.07103,
0.0*
%
%ADD66MACRO66*%
%AMMACRO51*
4,1,15,.02475,.01414,
.026829,.009627,
.028094,.004822,
.028504,-.000129,
.028049,-.005077,
.026741,-.009871,
.02475,-.01414,
.02984,-.01923,
.032726,-.013756,
.034617,-.007864,
.035457,-.001734,
.03522,.00445,
.033912,.010498,
.031574,.016227,
.02984,.01923,
.02475,.01414,
0.0*
4,1,15,.01414,-.02475,
.009627,-.026829,
.004822,-.028094,
-.000129,-.028504,
-.005077,-.028049,
-.009871,-.026741,
-.01414,-.02475,
-.01923,-.02984,
-.013756,-.032726,
-.007864,-.034617,
-.001734,-.035457,
.00445,-.03522,
.010498,-.033912,
.016227,-.031574,
.01923,-.02984,
.01414,-.02475,
0.0*
4,1,15,-.02475,-.01414,
-.026829,-.009627,
-.028094,-.004822,
-.028504,.000129,
-.028049,.005077,
-.026741,.009871,
-.02475,.01414,
-.02984,.01923,
-.032726,.013756,
-.034617,.007864,
-.035457,.001734,
-.03522,-.00445,
-.033912,-.010498,
-.031574,-.016227,
-.02984,-.01923,
-.02475,-.01414,
0.0*
4,1,15,-.01414,.02475,
-.009627,.026829,
-.004822,.028094,
.000129,.028504,
.005077,.028049,
.009871,.026741,
.01414,.02475,
.01923,.02984,
.013756,.032726,
.007864,.034617,
.001734,.035457,
-.00445,.03522,
-.010498,.033912,
-.016227,.031574,
-.01923,.02984,
-.01414,.02475,
0.0*
%
%ADD51MACRO51*%
%AMMACRO38*
4,1,16,.02511,.01451,
.027248,.009929,
.028558,.005047,
.029001,.000011,
.028562,-.005025,
.027256,-.009909,
.025121,-.014491,
.02511,-.01451,
.0302,-.01959,
.033143,-.014048,
.035079,-.00808,
.035949,-.001865,
.035727,.004405,
.034419,.010542,
.032065,.016359,
.0302,.01959,
.02511,.01451,
90.*
4,1,16,.01451,-.02511,
.009929,-.027248,
.005047,-.028558,
.000011,-.029001,
-.005025,-.028562,
-.009909,-.027256,
-.014491,-.025121,
-.01451,-.02511,
-.01959,-.0302,
-.014048,-.033143,
-.00808,-.035079,
-.001865,-.035949,
.004405,-.035727,
.010542,-.034419,
.016359,-.032065,
.01959,-.0302,
.01451,-.02511,
90.*
4,1,16,-.02511,-.01451,
-.027248,-.009929,
-.028558,-.005047,
-.029001,-.000011,
-.028562,.005025,
-.027256,.009909,
-.025121,.014491,
-.02511,.01451,
-.0302,.01959,
-.033143,.014048,
-.035079,.00808,
-.035949,.001865,
-.035727,-.004405,
-.034419,-.010542,
-.032065,-.016359,
-.0302,-.01959,
-.02511,-.01451,
90.*
4,1,16,-.01451,.02511,
-.009929,.027248,
-.005047,.028558,
-.000011,.029001,
.005025,.028562,
.009909,.027256,
.014491,.025121,
.01451,.02511,
.01959,.0302,
.014048,.033143,
.00808,.035079,
.001865,.035949,
-.004405,.035727,
-.010542,.034419,
-.016359,.032065,
-.01959,.0302,
-.01451,.02511,
90.*
%
%ADD38MACRO38*%
%AMMACRO28*
4,1,16,.02511,.01451,
.027248,.009929,
.028558,.005047,
.029001,.000011,
.028562,-.005025,
.027256,-.009909,
.025121,-.014491,
.02511,-.01451,
.0302,-.01959,
.033143,-.014048,
.035079,-.00808,
.035949,-.001865,
.035727,.004405,
.034419,.010542,
.032065,.016359,
.0302,.01959,
.02511,.01451,
0.0*
4,1,16,.01451,-.02511,
.009929,-.027248,
.005047,-.028558,
.000011,-.029001,
-.005025,-.028562,
-.009909,-.027256,
-.014491,-.025121,
-.01451,-.02511,
-.01959,-.0302,
-.014048,-.033143,
-.00808,-.035079,
-.001865,-.035949,
.004405,-.035727,
.010542,-.034419,
.016359,-.032065,
.01959,-.0302,
.01451,-.02511,
0.0*
4,1,16,-.02511,-.01451,
-.027248,-.009929,
-.028558,-.005047,
-.029001,-.000011,
-.028562,.005025,
-.027256,.009909,
-.025121,.014491,
-.02511,.01451,
-.0302,.01959,
-.033143,.014048,
-.035079,.00808,
-.035949,.001865,
-.035727,-.004405,
-.034419,-.010542,
-.032065,-.016359,
-.0302,-.01959,
-.02511,-.01451,
0.0*
4,1,16,-.01451,.02511,
-.009929,.027248,
-.005047,.028558,
-.000011,.029001,
.005025,.028562,
.009909,.027256,
.014491,.025121,
.01451,.02511,
.01959,.0302,
.014048,.033143,
.00808,.035079,
.001865,.035949,
-.004405,.035727,
-.010542,.034419,
-.016359,.032065,
-.01959,.0302,
-.01451,.02511,
0.0*
%
%ADD28MACRO28*%
%AMMACRO78*
4,1,15,.03682,.01914,
.039584,.012455,
.041146,.005393,
.041457,-.001834,
.040509,-.009005,
.03833,-.015903,
.03682,-.01914,
.04197,-.0243,
.045552,-.016643,
.04775,-.00848,
.048497,-.000059,
.047771,.008363,
.045593,.016531,
.042029,.024197,
.04197,.0243,
.03682,.01914,
0.0*
4,1,15,.01914,-.03682,
.012455,-.039584,
.005393,-.041146,
-.001834,-.041457,
-.009005,-.040509,
-.015903,-.03833,
-.01914,-.03682,
-.0243,-.04197,
-.016643,-.045552,
-.00848,-.04775,
-.000059,-.048497,
.008363,-.047771,
.016531,-.045593,
.024197,-.042029,
.0243,-.04197,
.01914,-.03682,
0.0*
4,1,15,-.03682,-.01914,
-.039584,-.012455,
-.041146,-.005393,
-.041457,.001834,
-.040509,.009005,
-.03833,.015903,
-.03682,.01914,
-.04197,.0243,
-.045552,.016643,
-.04775,.00848,
-.048497,.000059,
-.047771,-.008363,
-.045593,-.016531,
-.042029,-.024197,
-.04197,-.0243,
-.03682,-.01914,
0.0*
4,1,15,-.01914,.03682,
-.012455,.039584,
-.005393,.041146,
.001834,.041457,
.009005,.040509,
.015903,.03833,
.01914,.03682,
.0243,.04197,
.016643,.045552,
.00848,.04775,
.000059,.048497,
-.008363,.047771,
-.016531,.045593,
-.024197,.042029,
-.0243,.04197,
-.01914,.03682,
0.0*
%
%ADD78MACRO78*%
%AMMACRO75*
4,1,15,-.03682,.01914,
-.039584,.012455,
-.041146,.005393,
-.041457,-.001834,
-.040509,-.009005,
-.03833,-.015903,
-.03682,-.01914,
-.04197,-.0243,
-.045552,-.016643,
-.04775,-.00848,
-.048497,-.000059,
-.047771,.008363,
-.045593,.016531,
-.042029,.024197,
-.04197,.0243,
-.03682,.01914,
0.0*
4,1,15,-.01914,-.03682,
-.012455,-.039584,
-.005393,-.041146,
.001834,-.041457,
.009005,-.040509,
.015903,-.03833,
.01914,-.03682,
.0243,-.04197,
.016643,-.045552,
.00848,-.04775,
.000059,-.048497,
-.008363,-.047771,
-.016531,-.045593,
-.024197,-.042029,
-.0243,-.04197,
-.01914,-.03682,
0.0*
4,1,15,.03682,-.01914,
.039584,-.012455,
.041146,-.005393,
.041457,.001834,
.040509,.009005,
.03833,.015903,
.03682,.01914,
.04197,.0243,
.045552,.016643,
.04775,.00848,
.048497,.000059,
.047771,-.008363,
.045593,-.016531,
.042029,-.024197,
.04197,-.0243,
.03682,-.01914,
0.0*
4,1,15,.01914,.03682,
.012455,.039584,
.005393,.041146,
-.001834,.041457,
-.009005,.040509,
-.015903,.03833,
-.01914,.03682,
-.0243,.04197,
-.016643,.045552,
-.00848,.04775,
-.000059,.048497,
.008363,.047771,
.016531,.045593,
.024197,.042029,
.0243,.04197,
.01914,.03682,
0.0*
%
%ADD75MACRO75*%
%AMMACRO23*
4,1,25,-.0605,.00499,
-.05909,.011105,
-.05664,.016881,
-.053224,.022145,
-.048946,.026736,
-.043935,.030513,
-.038345,.033364,
-.032345,.0352,
-.02985,.03564,
-.025195,.035958,
-.02422,.03599,
-.005,.03599,
-.005,.03099,
-.02474,.03099,
-.026534,.030943,
-.028322,.030793,
-.02985,.03058,
-.035086,.029247,
-.040011,.027025,
-.044475,.023982,
-.048343,.020209,
-.051497,.015823,
-.053842,.010955,
-.055305,.005754,
-.05544,.00499,
-.0605,.00499,
0.0*
4,1,27,.005,.03599,
.02451,.03599,
.026071,.035998,
.027631,.035916,
.029183,.035743,
.02985,.03564,
.035965,.03423,
.041741,.03178,
.047005,.028364,
.051596,.024086,
.055373,.019075,
.058224,.013485,
.06006,.007485,
.0605,.00499,
.05544,.00499,
.054107,.010226,
.051885,.015151,
.048842,.019615,
.045069,.023483,
.040683,.026637,
.035815,.028982,
.030614,.030445,
.02985,.03058,
.0281,.030818,
.02634,.030955,
.02482,.03099,
.005,.03099,
.005,.03599,
0.0*
4,1,25,-.0605,-.00501,
-.05544,-.00501,
-.054107,-.010246,
-.051885,-.015171,
-.048842,-.019635,
-.045069,-.023503,
-.040683,-.026657,
-.035815,-.029002,
-.030614,-.030465,
-.02985,-.0306,
-.028079,-.03084,
-.026298,-.030976,
-.02487,-.03101,
-.005,-.03101,
-.005,-.03601,
-.02375,-.03601,
-.028562,-.035772,
-.02985,-.03566,
-.035965,-.03425,
-.041741,-.0318,
-.047005,-.028384,
-.051596,-.024106,
-.055373,-.019095,
-.058224,-.013505,
-.06006,-.007505,
-.0605,-.00501,
0.0*
4,1,27,.005,-.03101,
.02485,-.03101,
.02659,-.030963,
.028324,-.030815,
.02985,-.0306,
.035086,-.029267,
.040011,-.027045,
.044475,-.024002,
.048343,-.020229,
.051497,-.015843,
.053842,-.010975,
.055305,-.005774,
.05544,-.00501,
.0605,-.00501,
.05909,-.011125,
.05664,-.016901,
.053224,-.022165,
.048946,-.026756,
.043935,-.030533,
.038345,-.033384,
.032345,-.03522,
.02985,-.03566,
.028758,-.035841,
.027658,-.035958,
.026553,-.036011,
.02578,-.03601,
.005,-.03601,
.005,-.03101,
0.0*
%
%ADD23MACRO23*%
%ADD61R,.285X.23*%
%ADD68C,.142*%
%AMMACRO62*
4,1,36,0.0,.01,
-.001736,.009848,
-.00342,.009397,
-.005,.00866,
-.006428,.00766,
-.00766,.006428,
-.00866,.005,
-.009397,.00342,
-.009848,.001736,
-.01,0.0,
-.009848,-.001736,
-.009397,-.00342,
-.00866,-.005,
-.00766,-.006428,
-.006428,-.00766,
-.005,-.00866,
-.00342,-.009397,
-.001736,-.009848,
0.0,-.01,
.001736,-.009848,
.00342,-.009397,
.005,-.00866,
.006428,-.00766,
.00766,-.006428,
.00866,-.005,
.009397,-.00342,
.009848,-.001736,
.01,0.0,
.009848,.001736,
.009397,.00342,
.00866,.005,
.00766,.006428,
.006428,.00766,
.005,.00866,
.00342,.009397,
.001736,.009848,
0.0,.01,
180.*
%
%ADD62MACRO62*%
%ADD33O,.219X.156*%
%ADD13C,.125*%
%AMMACRO69*
4,1,36,.0025,0.0,
.002462,.000434,
.002349,.000855,
.002165,.00125,
.001915,.001607,
.001607,.001915,
.00125,.002165,
.000855,.002349,
.000434,.002462,
0.0,.0025,
-.000434,.002462,
-.000855,.002349,
-.00125,.002165,
-.001607,.001915,
-.001915,.001607,
-.002165,.00125,
-.002349,.000855,
-.002462,.000434,
-.0025,0.0,
-.002462,-.000434,
-.002349,-.000855,
-.002165,-.00125,
-.001915,-.001607,
-.001607,-.001915,
-.00125,-.002165,
-.000855,-.002349,
-.000434,-.002462,
0.0,-.0025,
.000434,-.002462,
.000855,-.002349,
.00125,-.002165,
.001607,-.001915,
.001915,-.001607,
.002165,-.00125,
.002349,-.000855,
.002462,-.000434,
.0025,0.0,
30.*
%
%ADD69MACRO69*%
%ADD18C,.424*%
%ADD21C,.155*%
%ADD54C,.291*%
%ADD39C,.165*%
%ADD56C,.247*%
%ADD45C,.256*%
%AMMACRO34*
4,1,36,0.0,.0085,
.001476,.008371,
.002907,.007987,
.00425,.007361,
.005464,.006511,
.006511,.005464,
.007361,.00425,
.007987,.002907,
.008371,.001476,
.0085,0.0,
.008371,-.001476,
.007987,-.002907,
.007361,-.00425,
.006511,-.005464,
.005464,-.006511,
.00425,-.007361,
.002907,-.007987,
.001476,-.008371,
0.0,-.0085,
-.001476,-.008371,
-.002907,-.007987,
-.00425,-.007361,
-.005464,-.006511,
-.006511,-.005464,
-.007361,-.00425,
-.007987,-.002907,
-.008371,-.001476,
-.0085,0.0,
-.008371,.001476,
-.007987,.002907,
-.007361,.00425,
-.006511,.005464,
-.005464,.006511,
-.00425,.007361,
-.002907,.007987,
-.001476,.008371,
0.0,.0085,
180.*
%
%ADD34MACRO34*%
%AMMACRO60*
4,1,20,-.0075,-.05555,
-.0075,-.06273,
-.013677,-.060878,
-.019439,-.057981,
-.024611,-.054127,
-.029034,-.049434,
-.032576,-.044045,
-.035127,-.038122,
-.036612,-.031846,
-.037,-.0265,
-.037,-.0075,
-.03,-.0075,
-.03,-.0265,
-.029544,-.03171,
-.028191,-.036762,
-.02598,-.041502,
-.022981,-.045786,
-.019282,-.049484,
-.014998,-.052484,
-.010258,-.054694,
-.0075,-.05555,
90.*
4,1,20,.0075,-.06273,
.0075,-.05555,
.01243,-.053806,
.016983,-.051232,
.02102,-.047906,
.024418,-.043931,
.027073,-.039425,
.028906,-.034527,
.029861,-.029385,
.03,-.0265,
.03,-.0075,
.037,-.0075,
.037,-.0265,
.036438,-.032925,
.034769,-.039154,
.032043,-.044999,
.028344,-.050282,
.023784,-.054842,
.018501,-.058541,
.012656,-.061266,
.0075,-.06273,
90.*
4,1,20,-.0075,.06273,
-.0075,.05555,
-.01243,.053806,
-.016983,.051232,
-.02102,.047906,
-.024418,.043931,
-.027073,.039425,
-.028906,.034527,
-.029861,.029385,
-.03,.0265,
-.03,.0075,
-.037,.0075,
-.037,.0265,
-.036438,.032925,
-.034769,.039154,
-.032043,.044999,
-.028344,.050282,
-.023784,.054842,
-.018501,.058541,
-.012656,.061266,
-.0075,.06273,
90.*
4,1,20,.0075,.05555,
.0075,.06273,
.013677,.060878,
.019439,.057981,
.024611,.054127,
.029034,.049434,
.032576,.044045,
.035127,.038122,
.036612,.031846,
.037,.0265,
.037,.0075,
.03,.0075,
.03,.0265,
.029544,.03171,
.028191,.036762,
.02598,.041502,
.022981,.045786,
.019282,.049484,
.014998,.052484,
.010258,.054694,
.0075,.05555,
90.*
%
%ADD60MACRO60*%
%AMMACRO20*
4,1,36,.0025,0.0,
.002462,.000434,
.002349,.000855,
.002165,.00125,
.001915,.001607,
.001607,.001915,
.00125,.002165,
.000855,.002349,
.000434,.002462,
0.0,.0025,
-.000434,.002462,
-.000855,.002349,
-.00125,.002165,
-.001607,.001915,
-.001915,.001607,
-.002165,.00125,
-.002349,.000855,
-.002462,.000434,
-.0025,0.0,
-.002462,-.000434,
-.002349,-.000855,
-.002165,-.00125,
-.001915,-.001607,
-.001607,-.001915,
-.00125,-.002165,
-.000855,-.002349,
-.000434,-.002462,
0.0,-.0025,
.000434,-.002462,
.000855,-.002349,
.00125,-.002165,
.001607,-.001915,
.001915,-.001607,
.002165,-.00125,
.002349,-.000855,
.002462,-.000434,
.0025,0.0,
90.*
%
%ADD20MACRO20*%
%AMMACRO57*
4,1,36,0.0,.019,
-.003299,.018711,
-.006498,.017854,
-.0095,.016454,
-.012213,.014555,
-.014555,.012213,
-.016454,.0095,
-.017854,.006498,
-.018711,.003299,
-.019,0.0,
-.018711,-.003299,
-.017854,-.006498,
-.016454,-.0095,
-.014555,-.012213,
-.012213,-.014555,
-.0095,-.016454,
-.006498,-.017854,
-.003299,-.018711,
0.0,-.019,
.003299,-.018711,
.006498,-.017854,
.0095,-.016454,
.012213,-.014555,
.014555,-.012213,
.016454,-.0095,
.017854,-.006498,
.018711,-.003299,
.019,0.0,
.018711,.003299,
.017854,.006498,
.016454,.0095,
.014555,.012213,
.012213,.014555,
.0095,.016454,
.006498,.017854,
.003299,.018711,
0.0,.019,
270.*
%
%ADD57MACRO57*%
%AMMACRO43*
4,1,36,.003,0.0,
.002954,.000521,
.002819,.001026,
.002598,.0015,
.002298,.001928,
.001928,.002298,
.0015,.002598,
.001026,.002819,
.000521,.002954,
0.0,.003,
-.000521,.002954,
-.001026,.002819,
-.0015,.002598,
-.001928,.002298,
-.002298,.001928,
-.002598,.0015,
-.002819,.001026,
-.002954,.000521,
-.003,0.0,
-.002954,-.000521,
-.002819,-.001026,
-.002598,-.0015,
-.002298,-.001928,
-.001928,-.002298,
-.0015,-.002598,
-.001026,-.002819,
-.000521,-.002954,
0.0,-.003,
.000521,-.002954,
.001026,-.002819,
.0015,-.002598,
.001928,-.002298,
.002298,-.001928,
.002598,-.0015,
.002819,-.001026,
.002954,-.000521,
.003,0.0,
90.*
%
%ADD43MACRO43*%
%AMMACRO12*
4,1,36,.0025,0.0,
.002462,.000434,
.002349,.000855,
.002165,.00125,
.001915,.001607,
.001607,.001915,
.00125,.002165,
.000855,.002349,
.000434,.002462,
0.0,.0025,
-.000434,.002462,
-.000855,.002349,
-.00125,.002165,
-.001607,.001915,
-.001915,.001607,
-.002165,.00125,
-.002349,.000855,
-.002462,.000434,
-.0025,0.0,
-.002462,-.000434,
-.002349,-.000855,
-.002165,-.00125,
-.001915,-.001607,
-.001607,-.001915,
-.00125,-.002165,
-.000855,-.002349,
-.000434,-.002462,
0.0,-.0025,
.000434,-.002462,
.000855,-.002349,
.00125,-.002165,
.001607,-.001915,
.001915,-.001607,
.002165,-.00125,
.002349,-.000855,
.002462,-.000434,
.0025,0.0,
0.0*
%
%ADD12MACRO12*%
%AMMACRO72*
4,1,36,-.003,0.0,
-.002954,.000521,
-.002819,.001026,
-.002598,.0015,
-.002298,.001928,
-.001928,.002298,
-.0015,.002598,
-.001026,.002819,
-.000521,.002954,
0.0,.003,
.000521,.002954,
.001026,.002819,
.0015,.002598,
.001928,.002298,
.002298,.001928,
.002598,.0015,
.002819,.001026,
.002954,.000521,
.003,0.0,
.002954,-.000521,
.002819,-.001026,
.002598,-.0015,
.002298,-.001928,
.001928,-.002298,
.0015,-.002598,
.001026,-.002819,
.000521,-.002954,
0.0,-.003,
-.000521,-.002954,
-.001026,-.002819,
-.0015,-.002598,
-.001928,-.002298,
-.002298,-.001928,
-.002598,-.0015,
-.002819,-.001026,
-.002954,-.000521,
-.003,0.0,
90.*
%
%ADD72MACRO72*%
%AMMACRO64*
4,1,36,-.0025,0.0,
-.002462,.000434,
-.002349,.000855,
-.002165,.00125,
-.001915,.001607,
-.001607,.001915,
-.00125,.002165,
-.000855,.002349,
-.000434,.002462,
0.0,.0025,
.000434,.002462,
.000855,.002349,
.00125,.002165,
.001607,.001915,
.001915,.001607,
.002165,.00125,
.002349,.000855,
.002462,.000434,
.0025,0.0,
.002462,-.000434,
.002349,-.000855,
.002165,-.00125,
.001915,-.001607,
.001607,-.001915,
.00125,-.002165,
.000855,-.002349,
.000434,-.002462,
0.0,-.0025,
-.000434,-.002462,
-.000855,-.002349,
-.00125,-.002165,
-.001607,-.001915,
-.001915,-.001607,
-.002165,-.00125,
-.002349,-.000855,
-.002462,-.000434,
-.0025,0.0,
0.0*
%
%ADD64MACRO64*%
%ADD58C,.188*%
%AMMACRO16*
4,1,36,.003,0.0,
.002954,.000521,
.002819,.001026,
.002598,.0015,
.002298,.001928,
.001928,.002298,
.0015,.002598,
.001026,.002819,
.000521,.002954,
0.0,.003,
-.000521,.002954,
-.001026,.002819,
-.0015,.002598,
-.001928,.002298,
-.002298,.001928,
-.002598,.0015,
-.002819,.001026,
-.002954,.000521,
-.003,0.0,
-.002954,-.000521,
-.002819,-.001026,
-.002598,-.0015,
-.002298,-.001928,
-.001928,-.002298,
-.0015,-.002598,
-.001026,-.002819,
-.000521,-.002954,
0.0,-.003,
.000521,-.002954,
.001026,-.002819,
.0015,-.002598,
.001928,-.002298,
.002298,-.001928,
.002598,-.0015,
.002819,-.001026,
.002954,-.000521,
.003,0.0,
0.0*
%
%ADD16MACRO16*%
%AMMACRO25*
4,1,16,.02584,.01524,
.028094,.010521,
.029494,.005483,
.029998,.000278,
.029591,-.004935,
.028284,-.009999,
.026118,-.014758,
.02584,-.01524,
.03092,-.02032,
.033979,-.014642,
.036005,-.008519,
.036938,-.002138,
.036748,.004309,
.035441,.010625,
.033058,.016618,
.03092,.02032,
.02584,.01524,
180.*
4,1,16,.01524,-.02584,
.010521,-.028094,
.005483,-.029494,
.000278,-.029998,
-.004935,-.029591,
-.009999,-.028284,
-.014758,-.026118,
-.01524,-.02584,
-.02032,-.03092,
-.014642,-.033979,
-.008519,-.036005,
-.002138,-.036938,
.004309,-.036748,
.010625,-.035441,
.016618,-.033058,
.02032,-.03092,
.01524,-.02584,
180.*
4,1,16,-.02584,-.01524,
-.028094,-.010521,
-.029494,-.005483,
-.029998,-.000278,
-.029591,.004935,
-.028284,.009999,
-.026118,.014758,
-.02584,.01524,
-.03092,.02032,
-.033979,.014642,
-.036005,.008519,
-.036938,.002138,
-.036748,-.004309,
-.035441,-.010625,
-.033058,-.016618,
-.03092,-.02032,
-.02584,-.01524,
180.*
4,1,16,-.01524,.02584,
-.010521,.028094,
-.005483,.029494,
-.000278,.029998,
.004935,.029591,
.009999,.028284,
.014758,.026118,
.01524,.02584,
.02032,.03092,
.014642,.033979,
.008519,.036005,
.002138,.036938,
-.004309,.036748,
-.010625,.035441,
-.016618,.033058,
-.02032,.03092,
-.01524,.02584,
180.*
%
%ADD25MACRO25*%
%AMMACRO65*
4,1,15,.02438,.01377,
.026401,.009327,
.027619,.004601,
.027999,-.000265,
.027527,-.005123,
.02622,-.009825,
.02438,-.01377,
.02948,-.01887,
.032309,-.013464,
.034156,-.007649,
.034965,-.001602,
.034712,.004494,
.033405,.010454,
.031082,.016095,
.02948,.01887,
.02438,.01377,
270.*
4,1,15,.01377,-.02438,
.009327,-.026401,
.004601,-.027619,
-.000265,-.027999,
-.005123,-.027527,
-.009825,-.02622,
-.01377,-.02438,
-.01887,-.02948,
-.013464,-.032309,
-.007649,-.034156,
-.001602,-.034965,
.004494,-.034712,
.010454,-.033405,
.016095,-.031082,
.01887,-.02948,
.01377,-.02438,
270.*
4,1,15,-.02438,-.01377,
-.026401,-.009327,
-.027619,-.004601,
-.027999,.000265,
-.027527,.005123,
-.02622,.009825,
-.02438,.01377,
-.02948,.01887,
-.032309,.013464,
-.034156,.007649,
-.034965,.001602,
-.034712,-.004494,
-.033405,-.010454,
-.031082,-.016095,
-.02948,-.01887,
-.02438,-.01377,
270.*
4,1,15,-.01377,.02438,
-.009327,.026401,
-.004601,.027619,
.000265,.027999,
.005123,.027527,
.009825,.02622,
.01377,.02438,
.01887,.02948,
.013464,.032309,
.007649,.034156,
.001602,.034965,
-.004494,.034712,
-.010454,.033405,
-.016095,.031082,
-.01887,.02948,
-.01377,.02438,
270.*
%
%ADD65MACRO65*%
%AMMACRO70*
4,1,15,.02475,.01414,
.026829,.009627,
.028094,.004822,
.028504,-.000129,
.028049,-.005077,
.026741,-.009871,
.02475,-.01414,
.02984,-.01923,
.032726,-.013756,
.034617,-.007864,
.035457,-.001734,
.03522,.00445,
.033912,.010498,
.031574,.016227,
.02984,.01923,
.02475,.01414,
180.*
4,1,15,.01414,-.02475,
.009627,-.026829,
.004822,-.028094,
-.000129,-.028504,
-.005077,-.028049,
-.009871,-.026741,
-.01414,-.02475,
-.01923,-.02984,
-.013756,-.032726,
-.007864,-.034617,
-.001734,-.035457,
.00445,-.03522,
.010498,-.033912,
.016227,-.031574,
.01923,-.02984,
.01414,-.02475,
180.*
4,1,15,-.02475,-.01414,
-.026829,-.009627,
-.028094,-.004822,
-.028504,.000129,
-.028049,.005077,
-.026741,.009871,
-.02475,.01414,
-.02984,.01923,
-.032726,.013756,
-.034617,.007864,
-.035457,.001734,
-.03522,-.00445,
-.033912,-.010498,
-.031574,-.016227,
-.02984,-.01923,
-.02475,-.01414,
180.*
4,1,15,-.01414,.02475,
-.009627,.026829,
-.004822,.028094,
.000129,.028504,
.005077,.028049,
.009871,.026741,
.01414,.02475,
.01923,.02984,
.013756,.032726,
.007864,.034617,
.001734,.035457,
-.00445,.03522,
-.010498,.033912,
-.016227,.031574,
-.01923,.02984,
-.01414,.02475,
180.*
%
%ADD70MACRO70*%
%AMMACRO47*
4,1,15,.02475,.01414,
.026829,.009627,
.028094,.004822,
.028504,-.000129,
.028049,-.005077,
.026741,-.009871,
.02475,-.01414,
.02984,-.01923,
.032726,-.013756,
.034617,-.007864,
.035457,-.001734,
.03522,.00445,
.033912,.010498,
.031574,.016227,
.02984,.01923,
.02475,.01414,
270.*
4,1,15,.01414,-.02475,
.009627,-.026829,
.004822,-.028094,
-.000129,-.028504,
-.005077,-.028049,
-.009871,-.026741,
-.01414,-.02475,
-.01923,-.02984,
-.013756,-.032726,
-.007864,-.034617,
-.001734,-.035457,
.00445,-.03522,
.010498,-.033912,
.016227,-.031574,
.01923,-.02984,
.01414,-.02475,
270.*
4,1,15,-.02475,-.01414,
-.026829,-.009627,
-.028094,-.004822,
-.028504,.000129,
-.028049,.005077,
-.026741,.009871,
-.02475,.01414,
-.02984,.01923,
-.032726,.013756,
-.034617,.007864,
-.035457,.001734,
-.03522,-.00445,
-.033912,-.010498,
-.031574,-.016227,
-.02984,-.01923,
-.02475,-.01414,
270.*
4,1,15,-.01414,.02475,
-.009627,.026829,
-.004822,.028094,
.000129,.028504,
.005077,.028049,
.009871,.026741,
.01414,.02475,
.01923,.02984,
.013756,.032726,
.007864,.034617,
.001734,.035457,
-.00445,.03522,
-.010498,.033912,
-.016227,.031574,
-.01923,.02984,
-.01414,.02475,
270.*
%
%ADD47MACRO47*%
%AMMACRO59*
4,1,15,.04124,.02356,
.044705,.016041,
.046811,.008034,
.047495,-.000216,
.046736,-.008461,
.044557,-.016448,
.04124,-.02356,
.04635,-.02867,
.050624,-.020186,
.05336,-.011088,
.054475,-.001654,
.053935,.007831,
.051756,.017077,
.048004,.025805,
.04635,.02867,
.04124,.02356,
0.0*
4,1,15,.02356,-.04124,
.016041,-.044705,
.008034,-.046811,
-.000216,-.047495,
-.008461,-.046736,
-.016448,-.044557,
-.02356,-.04124,
-.02867,-.04635,
-.020186,-.050624,
-.011088,-.05336,
-.001654,-.054475,
.007831,-.053935,
.017077,-.051756,
.025805,-.048004,
.02867,-.04635,
.02356,-.04124,
0.0*
4,1,15,-.04124,-.02356,
-.044705,-.016041,
-.046811,-.008034,
-.047495,.000216,
-.046736,.008461,
-.044557,.016448,
-.04124,.02356,
-.04635,.02867,
-.050624,.020186,
-.05336,.011088,
-.054475,.001654,
-.053935,-.007831,
-.051756,-.017077,
-.048004,-.025805,
-.04635,-.02867,
-.04124,-.02356,
0.0*
4,1,15,-.02356,.04124,
-.016041,.044705,
-.008034,.046811,
.000216,.047495,
.008461,.046736,
.016448,.044557,
.02356,.04124,
.02867,.04635,
.020186,.050624,
.011088,.05336,
.001654,.054475,
-.007831,.053935,
-.017077,.051756,
-.025805,.048004,
-.02867,.04635,
-.02356,.04124,
0.0*
%
%ADD59MACRO59*%
%AMMACRO79*
4,1,15,.03682,.01914,
.039584,.012455,
.041146,.005393,
.041457,-.001834,
.040509,-.009005,
.03833,-.015903,
.03682,-.01914,
.04197,-.0243,
.045552,-.016643,
.04775,-.00848,
.048497,-.000059,
.047771,.008363,
.045593,.016531,
.042029,.024197,
.04197,.0243,
.03682,.01914,
180.*
4,1,15,.01914,-.03682,
.012455,-.039584,
.005393,-.041146,
-.001834,-.041457,
-.009005,-.040509,
-.015903,-.03833,
-.01914,-.03682,
-.0243,-.04197,
-.016643,-.045552,
-.00848,-.04775,
-.000059,-.048497,
.008363,-.047771,
.016531,-.045593,
.024197,-.042029,
.0243,-.04197,
.01914,-.03682,
180.*
4,1,15,-.03682,-.01914,
-.039584,-.012455,
-.041146,-.005393,
-.041457,.001834,
-.040509,.009005,
-.03833,.015903,
-.03682,.01914,
-.04197,.0243,
-.045552,.016643,
-.04775,.00848,
-.048497,.000059,
-.047771,-.008363,
-.045593,-.016531,
-.042029,-.024197,
-.04197,-.0243,
-.03682,-.01914,
180.*
4,1,15,-.01914,.03682,
-.012455,.039584,
-.005393,.041146,
.001834,.041457,
.009005,.040509,
.015903,.03833,
.01914,.03682,
.0243,.04197,
.016643,.045552,
.00848,.04775,
.000059,.048497,
-.008363,.047771,
-.016531,.045593,
-.024197,.042029,
-.0243,.04197,
-.01914,.03682,
180.*
%
%ADD79MACRO79*%
%AMMACRO77*
4,1,15,-.03682,.01914,
-.039584,.012455,
-.041146,.005393,
-.041457,-.001834,
-.040509,-.009005,
-.03833,-.015903,
-.03682,-.01914,
-.04197,-.0243,
-.045552,-.016643,
-.04775,-.00848,
-.048497,-.000059,
-.047771,.008363,
-.045593,.016531,
-.042029,.024197,
-.04197,.0243,
-.03682,.01914,
180.*
4,1,15,-.01914,-.03682,
-.012455,-.039584,
-.005393,-.041146,
.001834,-.041457,
.009005,-.040509,
.015903,-.03833,
.01914,-.03682,
.0243,-.04197,
.016643,-.045552,
.00848,-.04775,
.000059,-.048497,
-.008363,-.047771,
-.016531,-.045593,
-.024197,-.042029,
-.0243,-.04197,
-.01914,-.03682,
180.*
4,1,15,.03682,-.01914,
.039584,-.012455,
.041146,-.005393,
.041457,.001834,
.040509,.009005,
.03833,.015903,
.03682,.01914,
.04197,.0243,
.045552,.016643,
.04775,.00848,
.048497,.000059,
.047771,-.008363,
.045593,-.016531,
.042029,-.024197,
.04197,-.0243,
.03682,-.01914,
180.*
4,1,15,.01914,.03682,
.012455,.039584,
.005393,.041146,
-.001834,.041457,
-.009005,.040509,
-.015903,.03833,
-.01914,.03682,
-.0243,.04197,
-.016643,.045552,
-.00848,.04775,
-.000059,.048497,
.008363,.047771,
.016531,.045593,
.024197,.042029,
.0243,.04197,
.01914,.03682,
180.*
%
%ADD77MACRO77*%
%ADD80C,.006*%
%ADD105C,.04006*%
%ADD102C,.03016*%
%ADD98C,.03018*%
%ADD103C,.07008*%
%ADD83C,.07306*%
%ADD90C,.07208*%
%ADD94C,.07308*%
%ADD95C,.07608*%
%ADD93C,.07808*%
%ADD92C,.09708*%
%ADD89O,.1621X.2251*%
%ADD85C,.311*%
%ADD100C,.1621*%
%ADD82O,.03004X.06404*%
%ADD101C,.16211*%
%ADD97C,.1751*%
%ADD81O,.03006X.06406*%
%ADD96C,.43406*%
%ADD84C,.16506*%
%ADD91C,.25806*%
%ADD99C,.43376*%
%ADD104C,.19786*%
%ADD88O,.43374X.77626*%
%ADD86O,.43374X.69752*%
%ADD87O,.43376X.69754*%
G75*
%LPD*%
G75*
G36*
G01X-984580Y-698988D02*
X5868320D01*
Y4193602D01*
X-984580D01*
Y-698988D01*
G37*
%LPC*%
G75*
G36*
G01X1828062Y36504D02*
X1828081Y36500D01*
G03X1828470Y36462I388J1962D01*
G03X1828859Y36500I1J2000D01*
G01X1828878Y36504D01*
X1849606D01*
G02X1855480Y30630I0J-5874D01*
G01Y-40945D01*
G02X1849606Y-46819I-5874J0D01*
G01X7874D01*
G02X2000Y-40945I0J5874D01*
G01Y30630D01*
G02X7874Y36504I5874J0D01*
G01X35835D01*
G02X41709Y30630I0J-5874D01*
G01Y-3937D01*
G03X51583Y-13811I9874J0D01*
G01X321661D01*
G03X331535Y-3937I0J9874D01*
G01Y30630D01*
G02X337409Y36504I5874J0D01*
G01X480717D01*
G02X486591Y30630I0J-5874D01*
G01Y16850D01*
G03X496465Y6976I9874J0D01*
G01X766543D01*
G03X776417Y16850I0J9874D01*
G01Y30630D01*
G02X782291Y36504I5874J0D01*
G01X879134D01*
G03X889008Y46378I0J9874D01*
G01Y122824D01*
X895188Y129004D01*
X1002542D01*
X1009024Y122522D01*
Y46378D01*
G03X1018898Y36504I9874J0D01*
G01X1510244D01*
G02X1516118Y30630I0J-5874D01*
G01Y-3937D01*
G03X1525992Y-13811I9874J0D01*
G01X1796071D01*
G03X1805945Y-3937I0J9874D01*
G01Y30630D01*
G02X1811819Y36504I5874J0D01*
G01X1828062D01*
G37*
G36*
G01X1829886Y1650538D02*
X1829890D01*
Y1650237D01*
X1829888Y1650228D01*
G03X1829820Y1649712I1932J-517D01*
G03X1829886Y1649203I2000J1D01*
G01Y1612316D01*
G03X1832779Y1605332I9877J0D01*
G01X1839978Y1598133D01*
G02X1841697Y1593983I-4151J-4151D01*
G01Y326095D01*
G03X1844590Y319111I9878J1D01*
G01X1853757Y309944D01*
G02X1855476Y305794I-4151J-4151D01*
G01Y54252D01*
G02X1849606Y48382I-5870J0D01*
G01X1829186D01*
Y48378D01*
X1827844D01*
Y48382D01*
X1803945D01*
G03X1794067Y38504I0J-9878D01*
G01Y3937D01*
G02X1792134Y2004I-1933J0D01*
G01X1529929D01*
G02X1527996Y3937I0J1933D01*
G01Y38504D01*
G03X1518118Y48382I-9878J0D01*
G01X1026772D01*
G02X1020902Y54252I0J5870D01*
G01Y131004D01*
G03X1011024Y140882I-9878J0D01*
G01X887008D01*
G03X877130Y131004I0J-9878D01*
G01Y54252D01*
G02X871260Y48382I-5870J0D01*
G01X774417D01*
G03X764539Y38504I0J-9878D01*
G01Y24724D01*
G02X762606Y22791I-1933J0D01*
G01X500402D01*
G02X498469Y24724I0J1933D01*
G01Y38504D01*
G03X488591Y48382I-9878J0D01*
G01X329535D01*
G03X319657Y38504I0J-9878D01*
G01Y3937D01*
G02X317724Y2004I-1933J0D01*
G01X55520D01*
G02X53587Y3937I0J1933D01*
G01Y38504D01*
G03X43709Y48382I-9878J0D01*
G01X7874D01*
G02X2004Y54252I0J5870D01*
G01Y305794D01*
G02X3723Y309944I5870J-1D01*
G01X6985Y313206D01*
G03X9878Y320190I-6984J6984D01*
G01Y1588078D01*
G02X11597Y1592228I5870J-1D01*
G01X24701Y1605332D01*
G03X27595Y1612316I-6983J6985D01*
G01Y1732244D01*
G02X33465Y1738114I5870J0D01*
G01X765732D01*
Y1736890D01*
G03X769705Y1732917I3973J0D01*
G01X1087854D01*
G03X1091827Y1736890I0J3973D01*
G01Y1738114D01*
X1824016D01*
G02X1829886Y1732244I0J-5870D01*
G01Y1650538D01*
G37*
G36*
G01X1867354Y305795D02*
G03X1862156Y318343I-17746J-1D01*
G01X1855296Y325203D01*
G02X1853575Y329357I4153J4154D01*
G01Y1593984D01*
G03X1848377Y1606532I-17746J-1D01*
G01X1843484Y1611425D01*
G02X1841764Y1615579I4156J4154D01*
G01Y1732244D01*
G02X1847638Y1738118I5874J0D01*
G01X1857480D01*
G03X1867354Y1747992I0J9874D01*
G01Y1815072D01*
G02X1873228Y1820946I5874J0D01*
G01X2093700D01*
G02X2099574Y1815072I0J-5874D01*
G01Y1791450D01*
G02X2093700Y1785576I-5874J0D01*
G01X2031574D01*
G03X2021700Y1775702I0J-9874D01*
G01Y1229954D01*
G03X2031574Y1220080I9874J0D01*
G01X2093700D01*
G02X2099574Y1214206I0J-5874D01*
G01Y-40945D01*
G02X2093700Y-46819I-5874J0D01*
G01X1873228D01*
G02X1867354Y-40945I0J5874D01*
G01Y305795D01*
G37*
%LPD*%
G75*
G36*
G01X1758669Y52153D02*
G02X1760173Y50649I0J-1504D01*
G01Y50648D01*
G02X1760172Y50593I-1504J0D01*
G02X1758669Y49100I-1503J10D01*
G01X1755269D01*
G02X1753766Y50593I0J1503D01*
G02X1753765Y50648I1503J55D01*
G01Y50649D01*
G02X1755269Y52153I1504J0D01*
G02X1755620Y52112I2J-1504D01*
G01X1755643Y52106D01*
X1758295D01*
X1758318Y52112D01*
G02X1758669Y52153I349J-1463D01*
G37*
G36*
G01X1394374Y172851D02*
G02X1395334Y173198I960J-1154D01*
G01X1398734D01*
G02X1400236Y171696I0J-1502D01*
G02X1398743Y170194I-1502J0D01*
G02X1398182Y170076I-561J1276D01*
G02X1397656Y170179I0J1394D01*
G01X1397620Y170194D01*
X1395334D01*
G02X1394882Y170264I1J1502D01*
G02X1394184Y170076I-699J1206D01*
G01X1394182D01*
G02Y172864I0J1394D01*
G02X1394374Y172851I2J-1394D01*
G37*
G36*
G01X880168Y504762D02*
Y508162D01*
G02X881670Y509664I1502J0D01*
G02X882945Y508955I0J-1501D01*
G02X883184Y508142I-1265J-813D01*
G01Y508141D01*
G02X883173Y507963I-1504J4D01*
G01X883172Y507952D01*
Y504897D01*
X883173Y504888D01*
G02X883180Y504743I-1493J-145D01*
G01Y504742D01*
G02X881680Y503242I-1500J0D01*
G02X880398Y503963I0J1500D01*
G02X880168Y504762I1273J799D01*
G37*
G36*
G01X963269Y1556947D02*
G03X963539I135J148D01*
G02X965904Y1557866I2365J-2584D01*
G02X969115Y1555762I0J-3502D01*
G02X970504Y1554262I-115J-1500D01*
G02X969016Y1552758I-1504J0D01*
G02X965904Y1550862I-3112J1606D01*
G02X963539Y1551781I0J3503D01*
G03X963269I-135J-148D01*
G02X960904Y1550862I-2365J2584D01*
G02Y1557866I0J3502D01*
G02X963269Y1556947I0J-3503D01*
G37*
G36*
G01X1010001D02*
G03X1010271I135J148D01*
G02X1012636Y1557866I2365J-2584D01*
G02X1015849Y1555757I0J-3502D01*
G02X1016012Y1555766I164J-1495D01*
G02Y1552758I0J-1504D01*
G02X1015759Y1552779I-3J1504D01*
G02X1012636Y1550862I-3123J1585D01*
G02X1010271Y1551781I0J3503D01*
G03X1010001I-135J-148D01*
G02X1007636Y1550862I-2365J2584D01*
G02Y1557866I0J3502D01*
G02X1010001Y1556947I0J-3503D01*
G37*
G36*
G01X1056733D02*
G03X1057003I135J148D01*
G02X1059368Y1557866I2365J-2584D01*
G02X1062579Y1555762I0J-3502D01*
G02X1063968Y1554262I-115J-1500D01*
G02X1062480Y1552758I-1504J0D01*
G02X1059368Y1550862I-3112J1606D01*
G02X1057003Y1551781I0J3503D01*
G03X1056733I-135J-148D01*
G02X1054368Y1550862I-2365J2584D01*
G02Y1557866I0J3502D01*
G02X1056733Y1556947I0J-3503D01*
G37*
G36*
G01X1080099D02*
G03X1080369I135J148D01*
G02X1082734Y1557866I2365J-2584D01*
G02X1085945Y1555762I0J-3502D01*
G02X1087334Y1554262I-115J-1500D01*
G02X1085846Y1552758I-1504J0D01*
G02X1082734Y1550862I-3112J1606D01*
G02X1080369Y1551781I0J3503D01*
G03X1080099I-135J-148D01*
G02X1077734Y1550862I-2365J2584D01*
G02Y1557866I0J3502D01*
G02X1080099Y1556947I0J-3503D01*
G37*
G36*
G01X986635D02*
G03X986905I135J148D01*
G02X989270Y1557866I2365J-2584D01*
G02X992481Y1555762I0J-3502D01*
G02X993966Y1554262I-15J-1500D01*
G02X992466Y1552762I-1500J0D01*
G02X992385Y1552764I-3J1500D01*
G02X989270Y1550862I-3115J1600D01*
G02X986905Y1551781I0J3503D01*
G03X986635I-135J-148D01*
G02X984270Y1550862I-2365J2584D01*
G02Y1557866I0J3502D01*
G02X986635Y1556947I0J-3503D01*
G37*
G36*
G01X1033367D02*
G03X1033637I135J148D01*
G02X1036002Y1557866I2365J-2584D01*
G02X1039214Y1555760I0J-3502D01*
G02X1039298Y1555762I78J-1498D01*
G02Y1552762I0J-1500D01*
G02X1039121Y1552772I-4J1500D01*
G02X1036002Y1550862I-3119J1592D01*
G02X1033637Y1551781I0J3503D01*
G03X1033367I-135J-148D01*
G02X1031002Y1550862I-2365J2584D01*
G02Y1557866I0J3502D01*
G02X1033367Y1556947I0J-3503D01*
G37*
G36*
G01X229206Y1656840D02*
X232906D01*
G02X233208Y1656537I-1J-303D01*
G01Y1646531D01*
G02X232906Y1646228I-302J-1D01*
G01X229206D01*
G02X228904Y1646531I1J303D01*
G01Y1648936D01*
G02X228890Y1649173I2002J237D01*
G02X228904Y1649410I2016J0D01*
G01Y1653660D01*
G02X228890Y1653897I2002J237D01*
G02X228904Y1654134I2016J0D01*
G01Y1656537D01*
G02X229206Y1656840I302J1D01*
G37*
G36*
G01X276450D02*
X280150D01*
G02X280452Y1656537I-1J-303D01*
G01Y1646531D01*
G02X280150Y1646228I-302J-1D01*
G01X276450D01*
G02X276148Y1646531I1J303D01*
G01Y1648936D01*
G02X276134Y1649173I2002J237D01*
G02X276148Y1649410I2016J0D01*
G01Y1653660D01*
G02X276134Y1653897I2002J237D01*
G02X276148Y1654134I2016J0D01*
G01Y1656537D01*
G02X276450Y1656840I302J1D01*
G37*
G36*
G01X237080Y1660776D02*
X240780D01*
G02X241082Y1660474I0J-302D01*
G01Y1650468D01*
G02X240780Y1650166I-302J0D01*
G01X237080D01*
G02X236778Y1650468I0J302D01*
G01Y1652873D01*
G02X236764Y1653110I2002J237D01*
G02X236778Y1653347I2016J0D01*
G01Y1657597D01*
G02X236764Y1657834I2002J237D01*
G02X236778Y1658071I2016J0D01*
G01Y1660474D01*
G02X237080Y1660776I302J0D01*
G37*
G36*
G01X268576D02*
X272276D01*
G02X272578Y1660474I0J-302D01*
G01Y1650468D01*
G02X272276Y1650166I-302J0D01*
G01X268576D01*
G02X268274Y1650468I0J302D01*
G01Y1652873D01*
G02X268260Y1653110I2002J237D01*
G02X268274Y1653347I2016J0D01*
G01Y1657597D01*
G02X268260Y1657834I2002J237D01*
G02X268274Y1658071I2016J0D01*
G01Y1660474D01*
G02X268576Y1660776I302J0D01*
G37*
G36*
G01X284324D02*
X288024D01*
G02X288326Y1660474I0J-302D01*
G01Y1650468D01*
G02X288024Y1650166I-302J0D01*
G01X284324D01*
G02X284022Y1650468I0J302D01*
G01Y1652873D01*
G02X284008Y1653110I2002J237D01*
G02X284022Y1653347I2016J0D01*
G01Y1657597D01*
G02X284008Y1657834I2002J237D01*
G02X284022Y1658071I2016J0D01*
G01Y1660474D01*
G02X284324Y1660776I302J0D01*
G37*
G36*
G01X229206Y1671014D02*
X232906D01*
G02X233208Y1670711I-1J-303D01*
G01Y1660705D01*
G02X232906Y1660402I-302J-1D01*
G01X229206D01*
G02X228904Y1660705I1J303D01*
G01Y1663109D01*
G02X228890Y1663346I2002J237D01*
G02X228904Y1663583I2016J0D01*
G01Y1667833D01*
G02X228890Y1668070I2002J237D01*
G02X228904Y1668307I2016J0D01*
G01Y1670711D01*
G02X229206Y1671014I302J1D01*
G37*
G36*
G01X244954D02*
X248654D01*
G02X248956Y1670711I-1J-303D01*
G01Y1660705D01*
G02X248654Y1660402I-302J-1D01*
G01X244954D01*
G02X244652Y1660705I1J303D01*
G01Y1663109D01*
G02X244638Y1663346I2002J237D01*
G02X244652Y1663583I2016J0D01*
G01Y1667833D01*
G02X244638Y1668070I2002J237D01*
G02X244652Y1668307I2016J0D01*
G01Y1670711D01*
G02X244954Y1671014I302J1D01*
G37*
G36*
G01X276450D02*
X280150D01*
G02X280452Y1670711I-1J-303D01*
G01Y1660705D01*
G02X280150Y1660402I-302J-1D01*
G01X276450D01*
G02X276148Y1660705I1J303D01*
G01Y1663109D01*
G02X276134Y1663346I2002J237D01*
G02X276148Y1663583I2016J0D01*
G01Y1667833D01*
G02X276134Y1668070I2002J237D01*
G02X276148Y1668307I2016J0D01*
G01Y1670711D01*
G02X276450Y1671014I302J1D01*
G37*
G36*
G01X252828Y1674950D02*
X256528D01*
G02X256830Y1674648I0J-302D01*
G01Y1664642D01*
G02X256528Y1664340I-302J0D01*
G01X252828D01*
G02X252526Y1664642I0J302D01*
G01Y1667046D01*
G02X252512Y1667283I2002J237D01*
G02X252526Y1667520I2016J0D01*
G01Y1671770D01*
G02X252512Y1672007I2002J237D01*
G02X252526Y1672244I2016J0D01*
G01Y1674648D01*
G02X252828Y1674950I302J0D01*
G37*
G36*
G01X268576D02*
X272276D01*
G02X272578Y1674648I0J-302D01*
G01Y1664642D01*
G02X272276Y1664340I-302J0D01*
G01X268576D01*
G02X268274Y1664642I0J302D01*
G01Y1667046D01*
G02X268260Y1667283I2002J237D01*
G02X268274Y1667520I2016J0D01*
G01Y1671770D01*
G02X268260Y1672007I2002J237D01*
G02X268274Y1672244I2016J0D01*
G01Y1674648D01*
G02X268576Y1674950I302J0D01*
G37*
G36*
G01X284324D02*
X288024D01*
G02X288326Y1674648I0J-302D01*
G01Y1664642D01*
G02X288024Y1664340I-302J0D01*
G01X284324D01*
G02X284022Y1664642I0J302D01*
G01Y1667046D01*
G02X284008Y1667283I2002J237D01*
G02X284022Y1667520I2016J0D01*
G01Y1671770D01*
G02X284008Y1672007I2002J237D01*
G02X284022Y1672244I2016J0D01*
G01Y1674648D01*
G02X284324Y1674950I302J0D01*
G37*
G36*
G01X229206Y1685186D02*
X232906D01*
G02X233208Y1684884I0J-302D01*
G01Y1674878D01*
G02X232906Y1674576I-302J0D01*
G01X229206D01*
G02X228904Y1674878I0J302D01*
G01Y1677282D01*
G02X228890Y1677519I2002J237D01*
G02X228904Y1677756I2016J0D01*
G01Y1682007D01*
G02X228890Y1682244I2002J237D01*
G02X228904Y1682481I2016J0D01*
G01Y1684884D01*
G02X229206Y1685186I302J0D01*
G37*
G36*
G01X244954D02*
X248654D01*
G02X248956Y1684884I0J-302D01*
G01Y1674878D01*
G02X248654Y1674576I-302J0D01*
G01X244954D01*
G02X244652Y1674878I0J302D01*
G01Y1677282D01*
G02X244638Y1677519I2002J237D01*
G02X244652Y1677756I2016J0D01*
G01Y1682007D01*
G02X244638Y1682244I2002J237D01*
G02X244652Y1682481I2016J0D01*
G01Y1684884D01*
G02X244954Y1685186I302J0D01*
G37*
G36*
G01X260702D02*
X264402D01*
G02X264704Y1684884I0J-302D01*
G01Y1674878D01*
G02X264402Y1674576I-302J0D01*
G01X260702D01*
G02X260400Y1674878I0J302D01*
G01Y1677282D01*
G02X260386Y1677519I2002J237D01*
G02X260400Y1677756I2016J0D01*
G01Y1682007D01*
G02X260386Y1682244I2002J237D01*
G02X260400Y1682481I2016J0D01*
G01Y1684884D01*
G02X260702Y1685186I302J0D01*
G37*
G36*
G01X276450D02*
X280150D01*
G02X280452Y1684884I0J-302D01*
G01Y1674878D01*
G02X280150Y1674576I-302J0D01*
G01X276450D01*
G02X276148Y1674878I0J302D01*
G01Y1677282D01*
G02X276134Y1677519I2002J237D01*
G02X276148Y1677756I2016J0D01*
G01Y1682007D01*
G02X276134Y1682244I2002J237D01*
G02X276148Y1682481I2016J0D01*
G01Y1684884D01*
G02X276450Y1685186I302J0D01*
G37*
G36*
G01X560308D02*
X564008D01*
G02X564310Y1684884I0J-302D01*
G01Y1674878D01*
G02X564008Y1674576I-302J0D01*
G01X560308D01*
G02X560006Y1674878I0J302D01*
G01Y1676909D01*
G02X559915Y1677519I2002J610D01*
G02X560637Y1679101I2094J0D01*
G01X560956Y1679751D01*
G03Y1680013I-267J131D01*
G01X560638Y1680662D01*
G02X559915Y1682244I1369J1582D01*
G02X560006Y1682854I2093J0D01*
G01Y1684884D01*
G02X560308Y1685186I302J0D01*
G37*
G36*
G01X576056D02*
X579756D01*
G02X580058Y1684884I0J-302D01*
G01Y1674878D01*
G02X579756Y1674576I-302J0D01*
G01X576056D01*
G02X575754Y1674878I0J302D01*
G01Y1676909D01*
G02X575663Y1677519I2002J610D01*
G02X576385Y1679101I2094J0D01*
G01X576704Y1679751D01*
G03Y1680013I-267J131D01*
G01X576386Y1680662D01*
G02X575663Y1682244I1369J1582D01*
G02X575754Y1682854I2093J0D01*
G01Y1684884D01*
G02X576056Y1685186I302J0D01*
G37*
G36*
G01X591804D02*
X595504D01*
G02X595806Y1684884I0J-302D01*
G01Y1674878D01*
G02X595504Y1674576I-302J0D01*
G01X591804D01*
G02X591502Y1674878I0J302D01*
G01Y1676909D01*
G02X591411Y1677519I2002J610D01*
G02X592133Y1679101I2094J0D01*
G01X592452Y1679751D01*
G03Y1680013I-267J131D01*
G01X592134Y1680662D01*
G02X591411Y1682244I1369J1582D01*
G02X591502Y1682854I2093J0D01*
G01Y1684884D01*
G02X591804Y1685186I302J0D01*
G37*
G36*
G01X607552D02*
X611252D01*
G02X611554Y1684884I0J-302D01*
G01Y1674878D01*
G02X611252Y1674576I-302J0D01*
G01X607552D01*
G02X607250Y1674878I0J302D01*
G01Y1676909D01*
G02X607159Y1677519I2002J610D01*
G02X607881Y1679101I2094J0D01*
G01X608200Y1679751D01*
G03Y1680013I-267J131D01*
G01X607882Y1680662D01*
G02X607159Y1682244I1369J1582D01*
G02X607250Y1682854I2093J0D01*
G01Y1684884D01*
G02X607552Y1685186I302J0D01*
G37*
G36*
G01X1237080D02*
X1240780D01*
G02X1241082Y1684884I0J-302D01*
G01Y1674878D01*
G02X1240780Y1674576I-302J0D01*
G01X1237080D01*
G02X1236778Y1674878I0J302D01*
G01Y1677282D01*
G02X1236764Y1677519I2002J237D01*
G02X1236778Y1677756I2016J0D01*
G01Y1682007D01*
G02X1236764Y1682244I2002J237D01*
G02X1236778Y1682481I2016J0D01*
G01Y1684884D01*
G02X1237080Y1685186I302J0D01*
G37*
G36*
G01X1252828D02*
X1256528D01*
G02X1256830Y1684884I0J-302D01*
G01Y1674878D01*
G02X1256528Y1674576I-302J0D01*
G01X1252828D01*
G02X1252526Y1674878I0J302D01*
G01Y1677282D01*
G02X1252512Y1677519I2002J237D01*
G02X1252526Y1677756I2016J0D01*
G01Y1682007D01*
G02X1252512Y1682244I2002J237D01*
G02X1252526Y1682481I2016J0D01*
G01Y1684884D01*
G02X1252828Y1685186I302J0D01*
G37*
G36*
G01X1268576D02*
X1272276D01*
G02X1272578Y1684884I0J-302D01*
G01Y1674878D01*
G02X1272276Y1674576I-302J0D01*
G01X1268576D01*
G02X1268274Y1674878I0J302D01*
G01Y1677282D01*
G02X1268260Y1677519I2002J237D01*
G02X1268274Y1677756I2016J0D01*
G01Y1682007D01*
G02X1268260Y1682244I2002J237D01*
G02X1268274Y1682481I2016J0D01*
G01Y1684884D01*
G02X1268576Y1685186I302J0D01*
G37*
G36*
G01X1284324D02*
X1288024D01*
G02X1288326Y1684884I0J-302D01*
G01Y1674878D01*
G02X1288024Y1674576I-302J0D01*
G01X1284324D01*
G02X1284022Y1674878I0J302D01*
G01Y1677282D01*
G02X1284008Y1677519I2002J237D01*
G02X1284022Y1677756I2016J0D01*
G01Y1682007D01*
G02X1284008Y1682244I2002J237D01*
G02X1284022Y1682481I2016J0D01*
G01Y1684884D01*
G02X1284324Y1685186I302J0D01*
G37*
G36*
G01X1568182D02*
X1571882D01*
G02X1572184Y1684884I0J-302D01*
G01Y1674878D01*
G02X1571882Y1674576I-302J0D01*
G01X1568182D01*
G02X1567880Y1674878I0J302D01*
G01Y1676909D01*
G02X1567789Y1677519I2002J610D01*
G02X1568511Y1679101I2094J0D01*
G01X1568830Y1679751D01*
G03Y1680013I-267J131D01*
G01X1568512Y1680662D01*
G02X1567789Y1682244I1369J1582D01*
G02X1567880Y1682854I2093J0D01*
G01Y1684884D01*
G02X1568182Y1685186I302J0D01*
G37*
G36*
G01X1583930D02*
X1587630D01*
G02X1587932Y1684884I0J-302D01*
G01Y1674878D01*
G02X1587630Y1674576I-302J0D01*
G01X1583930D01*
G02X1583628Y1674878I0J302D01*
G01Y1676909D01*
G02X1583537Y1677519I2002J610D01*
G02X1584259Y1679101I2094J0D01*
G01X1584578Y1679751D01*
G03Y1680013I-267J131D01*
G01X1584260Y1680662D01*
G02X1583537Y1682244I1369J1582D01*
G02X1583628Y1682854I2093J0D01*
G01Y1684884D01*
G02X1583930Y1685186I302J0D01*
G37*
G36*
G01X1599678D02*
X1603378D01*
G02X1603680Y1684884I0J-302D01*
G01Y1674878D01*
G02X1603378Y1674576I-302J0D01*
G01X1599678D01*
G02X1599376Y1674878I0J302D01*
G01Y1676909D01*
G02X1599285Y1677519I2002J610D01*
G02X1600007Y1679101I2094J0D01*
G01X1600326Y1679751D01*
G03Y1680013I-267J131D01*
G01X1600008Y1680662D01*
G02X1599285Y1682244I1369J1582D01*
G02X1599376Y1682854I2093J0D01*
G01Y1684884D01*
G02X1599678Y1685186I302J0D01*
G37*
G36*
G01X1615426D02*
X1619126D01*
G02X1619428Y1684884I0J-302D01*
G01Y1674878D01*
G02X1619126Y1674576I-302J0D01*
G01X1615426D01*
G02X1615124Y1674878I0J302D01*
G01Y1676909D01*
G02X1615033Y1677519I2002J610D01*
G02X1615755Y1679101I2094J0D01*
G01X1616074Y1679751D01*
G03Y1680013I-267J131D01*
G01X1615756Y1680662D01*
G02X1615033Y1682244I1369J1582D01*
G02X1615124Y1682854I2093J0D01*
G01Y1684884D01*
G02X1615426Y1685186I302J0D01*
G37*
G36*
G01X296135D02*
X299835D01*
G02X300138Y1684884I1J-302D01*
G01Y1674878D01*
G02X299835Y1674576I-303J1D01*
G01X296135D01*
G02X295832Y1674878I-1J302D01*
G01Y1677290D01*
G02X295819Y1677519I2003J229D01*
G02X295832Y1677748I2016J0D01*
G01Y1682015D01*
G02X295819Y1682244I2003J229D01*
G02X295832Y1682473I2016J0D01*
G01Y1684884D01*
G02X296135Y1685186I303J-1D01*
G37*
G36*
G01X311883D02*
X315583D01*
G02X315886Y1684884I1J-302D01*
G01Y1674878D01*
G02X315583Y1674576I-303J1D01*
G01X311883D01*
G02X311580Y1674878I-1J302D01*
G01Y1677290D01*
G02X311567Y1677519I2003J229D01*
G02X311580Y1677748I2016J0D01*
G01Y1682015D01*
G02X311567Y1682244I2003J229D01*
G02X311580Y1682473I2016J0D01*
G01Y1684884D01*
G02X311883Y1685186I303J-1D01*
G37*
G36*
G01X327631D02*
X331331D01*
G02X331634Y1684884I1J-302D01*
G01Y1674878D01*
G02X331331Y1674576I-303J1D01*
G01X327631D01*
G02X327328Y1674878I-1J302D01*
G01Y1677290D01*
G02X327315Y1677519I2003J229D01*
G02X327328Y1677748I2016J0D01*
G01Y1682015D01*
G02X327315Y1682244I2003J229D01*
G02X327328Y1682473I2016J0D01*
G01Y1684884D01*
G02X327631Y1685186I303J-1D01*
G37*
G36*
G01X343379D02*
X347079D01*
G02X347382Y1684884I1J-302D01*
G01Y1674878D01*
G02X347079Y1674576I-303J1D01*
G01X343379D01*
G02X343076Y1674878I-1J302D01*
G01Y1677290D01*
G02X343063Y1677519I2003J229D01*
G02X343076Y1677748I2016J0D01*
G01Y1682015D01*
G02X343063Y1682244I2003J229D01*
G02X343076Y1682473I2016J0D01*
G01Y1684884D01*
G02X343379Y1685186I303J-1D01*
G37*
G36*
G01X493379D02*
X497079D01*
G02X497382Y1684884I1J-302D01*
G01Y1674878D01*
G02X497079Y1674576I-303J1D01*
G01X493379D01*
G02X493076Y1674878I-1J302D01*
G01Y1676912D01*
G02X492986Y1677519I2002J607D01*
G02X493708Y1679101I2094J0D01*
G01X494027Y1679751D01*
G03Y1680013I-267J131D01*
G01X493709Y1680662D01*
G02X492986Y1682244I1369J1582D01*
G02X493076Y1682851I2092J0D01*
G01Y1684884D01*
G02X493379Y1685186I303J-1D01*
G37*
G36*
G01X509127D02*
X512827D01*
G02X513130Y1684884I1J-302D01*
G01Y1674878D01*
G02X512827Y1674576I-303J1D01*
G01X509127D01*
G02X508824Y1674878I-1J302D01*
G01Y1676912D01*
G02X508734Y1677519I2002J607D01*
G02X509456Y1679101I2094J0D01*
G01X509775Y1679751D01*
G03Y1680013I-267J131D01*
G01X509457Y1680662D01*
G02X508734Y1682244I1369J1582D01*
G02X508824Y1682851I2092J0D01*
G01Y1684884D01*
G02X509127Y1685186I303J-1D01*
G37*
G36*
G01X524875D02*
X528575D01*
G02X528878Y1684884I1J-302D01*
G01Y1674878D01*
G02X528575Y1674576I-303J1D01*
G01X524875D01*
G02X524572Y1674878I-1J302D01*
G01Y1676912D01*
G02X524482Y1677519I2002J607D01*
G02X525204Y1679101I2094J0D01*
G01X525523Y1679751D01*
G03Y1680013I-267J131D01*
G01X525205Y1680662D01*
G02X524482Y1682244I1369J1582D01*
G02X524572Y1682851I2092J0D01*
G01Y1684884D01*
G02X524875Y1685186I303J-1D01*
G37*
G36*
G01X540623D02*
X544323D01*
G02X544626Y1684884I1J-302D01*
G01Y1674878D01*
G02X544323Y1674576I-303J1D01*
G01X540623D01*
G02X540320Y1674878I-1J302D01*
G01Y1676912D01*
G02X540230Y1677519I2002J607D01*
G02X540952Y1679101I2094J0D01*
G01X541271Y1679751D01*
G03Y1680013I-267J131D01*
G01X540953Y1680662D01*
G02X540230Y1682244I1369J1582D01*
G02X540320Y1682851I2092J0D01*
G01Y1684884D01*
G02X540623Y1685186I303J-1D01*
G37*
G36*
G01X1304009D02*
X1307709D01*
G02X1308012Y1684884I1J-302D01*
G01Y1674878D01*
G02X1307709Y1674576I-303J1D01*
G01X1304009D01*
G02X1303706Y1674878I-1J302D01*
G01Y1677290D01*
G02X1303693Y1677519I2003J229D01*
G02X1303706Y1677748I2016J0D01*
G01Y1682015D01*
G02X1303693Y1682244I2003J229D01*
G02X1303706Y1682473I2016J0D01*
G01Y1684884D01*
G02X1304009Y1685186I303J-1D01*
G37*
G36*
G01X1319757D02*
X1323457D01*
G02X1323760Y1684884I1J-302D01*
G01Y1674878D01*
G02X1323457Y1674576I-303J1D01*
G01X1319757D01*
G02X1319454Y1674878I-1J302D01*
G01Y1677290D01*
G02X1319441Y1677519I2003J229D01*
G02X1319454Y1677748I2016J0D01*
G01Y1682015D01*
G02X1319441Y1682244I2003J229D01*
G02X1319454Y1682473I2016J0D01*
G01Y1684884D01*
G02X1319757Y1685186I303J-1D01*
G37*
G36*
G01X1335505D02*
X1339205D01*
G02X1339508Y1684884I1J-302D01*
G01Y1674878D01*
G02X1339205Y1674576I-303J1D01*
G01X1335505D01*
G02X1335202Y1674878I-1J302D01*
G01Y1677290D01*
G02X1335189Y1677519I2003J229D01*
G02X1335202Y1677748I2016J0D01*
G01Y1682015D01*
G02X1335189Y1682244I2003J229D01*
G02X1335202Y1682473I2016J0D01*
G01Y1684884D01*
G02X1335505Y1685186I303J-1D01*
G37*
G36*
G01X1351253D02*
X1354953D01*
G02X1355256Y1684884I1J-302D01*
G01Y1674878D01*
G02X1354953Y1674576I-303J1D01*
G01X1351253D01*
G02X1350950Y1674878I-1J302D01*
G01Y1677290D01*
G02X1350937Y1677519I2003J229D01*
G02X1350950Y1677748I2016J0D01*
G01Y1682015D01*
G02X1350937Y1682244I2003J229D01*
G02X1350950Y1682473I2016J0D01*
G01Y1684884D01*
G02X1351253Y1685186I303J-1D01*
G37*
G36*
G01X1501253D02*
X1504953D01*
G02X1505256Y1684884I1J-302D01*
G01Y1674878D01*
G02X1504953Y1674576I-303J1D01*
G01X1501253D01*
G02X1500950Y1674878I-1J302D01*
G01Y1676912D01*
G02X1500860Y1677519I2002J607D01*
G02X1501582Y1679101I2094J0D01*
G01X1501901Y1679751D01*
G03Y1680013I-267J131D01*
G01X1501583Y1680662D01*
G02X1500860Y1682244I1369J1582D01*
G02X1500950Y1682851I2092J0D01*
G01Y1684884D01*
G02X1501253Y1685186I303J-1D01*
G37*
G36*
G01X1517001D02*
X1520701D01*
G02X1521004Y1684884I1J-302D01*
G01Y1674878D01*
G02X1520701Y1674576I-303J1D01*
G01X1517001D01*
G02X1516698Y1674878I-1J302D01*
G01Y1676912D01*
G02X1516608Y1677519I2002J607D01*
G02X1517330Y1679101I2094J0D01*
G01X1517649Y1679751D01*
G03Y1680013I-267J131D01*
G01X1517331Y1680662D01*
G02X1516608Y1682244I1369J1582D01*
G02X1516698Y1682851I2092J0D01*
G01Y1684884D01*
G02X1517001Y1685186I303J-1D01*
G37*
G36*
G01X1532749D02*
X1536449D01*
G02X1536752Y1684884I1J-302D01*
G01Y1674878D01*
G02X1536449Y1674576I-303J1D01*
G01X1532749D01*
G02X1532446Y1674878I-1J302D01*
G01Y1676912D01*
G02X1532356Y1677519I2002J607D01*
G02X1533078Y1679101I2094J0D01*
G01X1533397Y1679751D01*
G03Y1680013I-267J131D01*
G01X1533079Y1680662D01*
G02X1532356Y1682244I1369J1582D01*
G02X1532446Y1682851I2092J0D01*
G01Y1684884D01*
G02X1532749Y1685186I303J-1D01*
G37*
G36*
G01X1548497D02*
X1552197D01*
G02X1552500Y1684884I1J-302D01*
G01Y1674878D01*
G02X1552197Y1674576I-303J1D01*
G01X1548497D01*
G02X1548194Y1674878I-1J302D01*
G01Y1676912D01*
G02X1548104Y1677519I2002J607D01*
G02X1548826Y1679101I2094J0D01*
G01X1549145Y1679751D01*
G03Y1680013I-267J131D01*
G01X1548827Y1680662D01*
G02X1548104Y1682244I1369J1582D01*
G02X1548194Y1682851I2092J0D01*
G01Y1684884D01*
G02X1548497Y1685186I303J-1D01*
G37*
G36*
G01X237080Y1689124D02*
X240780D01*
G02X241082Y1688821I-1J-303D01*
G01Y1678815D01*
G02X240780Y1678512I-302J-1D01*
G01X237080D01*
G02X236778Y1678815I1J303D01*
G01Y1681219D01*
G02X236764Y1681456I2002J237D01*
G02X236778Y1681693I2016J0D01*
G01Y1685943D01*
G02X236764Y1686180I2002J237D01*
G02X236778Y1686417I2016J0D01*
G01Y1688821D01*
G02X237080Y1689124I302J1D01*
G37*
G36*
G01X252828D02*
X256528D01*
G02X256830Y1688821I-1J-303D01*
G01Y1678815D01*
G02X256528Y1678512I-302J-1D01*
G01X252828D01*
G02X252526Y1678815I1J303D01*
G01Y1681219D01*
G02X252512Y1681456I2002J237D01*
G02X252526Y1681693I2016J0D01*
G01Y1685943D01*
G02X252512Y1686180I2002J237D01*
G02X252526Y1686417I2016J0D01*
G01Y1688821D01*
G02X252828Y1689124I302J1D01*
G37*
G36*
G01X268576D02*
X272276D01*
G02X272578Y1688821I-1J-303D01*
G01Y1678815D01*
G02X272276Y1678512I-302J-1D01*
G01X268576D01*
G02X268274Y1678815I1J303D01*
G01Y1681219D01*
G02X268260Y1681456I2002J237D01*
G02X268274Y1681693I2016J0D01*
G01Y1685943D01*
G02X268260Y1686180I2002J237D01*
G02X268274Y1686417I2016J0D01*
G01Y1688821D01*
G02X268576Y1689124I302J1D01*
G37*
G36*
G01X284324D02*
X288024D01*
G02X288326Y1688821I-1J-303D01*
G01Y1678815D01*
G02X288024Y1678512I-302J-1D01*
G01X284324D01*
G02X284022Y1678815I1J303D01*
G01Y1681219D01*
G02X284008Y1681456I2002J237D01*
G02X284022Y1681693I2016J0D01*
G01Y1685943D01*
G02X284008Y1686180I2002J237D01*
G02X284022Y1686417I2016J0D01*
G01Y1688821D01*
G02X284324Y1689124I302J1D01*
G37*
G36*
G01X304009D02*
X307709D01*
G02X308012Y1688821I0J-303D01*
G01Y1678815D01*
G02X307709Y1678512I-303J0D01*
G01X304009D01*
G02X303706Y1678815I0J303D01*
G01Y1681227D01*
G02X303693Y1681456I2003J229D01*
G02X303706Y1681685I2016J0D01*
G01Y1685951D01*
G02X303693Y1686180I2003J229D01*
G02X303706Y1686409I2016J0D01*
G01Y1688821D01*
G02X304009Y1689124I303J0D01*
G37*
G36*
G01X319757D02*
X323457D01*
G02X323760Y1688821I0J-303D01*
G01Y1678815D01*
G02X323457Y1678512I-303J0D01*
G01X319757D01*
G02X319454Y1678815I0J303D01*
G01Y1681227D01*
G02X319441Y1681456I2003J229D01*
G02X319454Y1681685I2016J0D01*
G01Y1685951D01*
G02X319441Y1686180I2003J229D01*
G02X319454Y1686409I2016J0D01*
G01Y1688821D01*
G02X319757Y1689124I303J0D01*
G37*
G36*
G01X335505D02*
X339205D01*
G02X339508Y1688821I0J-303D01*
G01Y1678815D01*
G02X339205Y1678512I-303J0D01*
G01X335505D01*
G02X335202Y1678815I0J303D01*
G01Y1681227D01*
G02X335189Y1681456I2003J229D01*
G02X335202Y1681685I2016J0D01*
G01Y1685951D01*
G02X335189Y1686180I2003J229D01*
G02X335202Y1686409I2016J0D01*
G01Y1688821D01*
G02X335505Y1689124I303J0D01*
G37*
G36*
G01X351253D02*
X354953D01*
G02X355256Y1688821I0J-303D01*
G01Y1678815D01*
G02X354953Y1678512I-303J0D01*
G01X351253D01*
G02X350950Y1678815I0J303D01*
G01Y1681227D01*
G02X350937Y1681456I2003J229D01*
G02X350950Y1681685I2016J0D01*
G01Y1685951D01*
G02X350937Y1686180I2003J229D01*
G02X350950Y1686409I2016J0D01*
G01Y1688821D01*
G02X351253Y1689124I303J0D01*
G37*
G36*
G01X501253D02*
X504953D01*
G02X505256Y1688821I0J-303D01*
G01Y1678815D01*
G02X504953Y1678512I-303J0D01*
G01X501253D01*
G02X500950Y1678815I0J303D01*
G01Y1680849D01*
G02X500860Y1681456I2002J607D01*
G02X501582Y1683038I2094J0D01*
G01X501901Y1683688D01*
G03Y1683950I-267J131D01*
G01X501584Y1684597D01*
G02X500860Y1686180I1369J1583D01*
G02X500950Y1686787I2092J0D01*
G01Y1688821D01*
G02X501253Y1689124I303J0D01*
G37*
G36*
G01X517001D02*
X520701D01*
G02X521004Y1688821I0J-303D01*
G01Y1678815D01*
G02X520701Y1678512I-303J0D01*
G01X517001D01*
G02X516698Y1678815I0J303D01*
G01Y1680849D01*
G02X516608Y1681456I2002J607D01*
G02X517330Y1683038I2094J0D01*
G01X517649Y1683688D01*
G03Y1683950I-267J131D01*
G01X517332Y1684597D01*
G02X516608Y1686180I1369J1583D01*
G02X516698Y1686787I2092J0D01*
G01Y1688821D01*
G02X517001Y1689124I303J0D01*
G37*
G36*
G01X532749D02*
X536449D01*
G02X536752Y1688821I0J-303D01*
G01Y1678815D01*
G02X536449Y1678512I-303J0D01*
G01X532749D01*
G02X532446Y1678815I0J303D01*
G01Y1680849D01*
G02X532356Y1681456I2002J607D01*
G02X533078Y1683038I2094J0D01*
G01X533397Y1683688D01*
G03Y1683950I-267J131D01*
G01X533080Y1684597D01*
G02X532356Y1686180I1369J1583D01*
G02X532446Y1686787I2092J0D01*
G01Y1688821D01*
G02X532749Y1689124I303J0D01*
G37*
G36*
G01X548497D02*
X552197D01*
G02X552500Y1688821I0J-303D01*
G01Y1678815D01*
G02X552197Y1678512I-303J0D01*
G01X548497D01*
G02X548194Y1678815I0J303D01*
G01Y1680849D01*
G02X548104Y1681456I2002J607D01*
G02X548826Y1683038I2094J0D01*
G01X549145Y1683688D01*
G03Y1683950I-267J131D01*
G01X548828Y1684597D01*
G02X548104Y1686180I1369J1583D01*
G02X548194Y1686787I2092J0D01*
G01Y1688821D01*
G02X548497Y1689124I303J0D01*
G37*
G36*
G01X568182D02*
X571882D01*
G02X572184Y1688821I-1J-303D01*
G01Y1678815D01*
G02X571882Y1678512I-302J-1D01*
G01X568182D01*
G02X567880Y1678815I1J303D01*
G01Y1680846D01*
G02X567789Y1681456I2002J610D01*
G02X568511Y1683038I2094J0D01*
G01X568830Y1683688D01*
G03Y1683950I-267J131D01*
G01X568513Y1684597D01*
G02X567789Y1686180I1369J1583D01*
G02X567880Y1686790I2093J0D01*
G01Y1688821D01*
G02X568182Y1689124I302J1D01*
G37*
G36*
G01X583930D02*
X587630D01*
G02X587932Y1688821I-1J-303D01*
G01Y1678815D01*
G02X587630Y1678512I-302J-1D01*
G01X583930D01*
G02X583628Y1678815I1J303D01*
G01Y1680846D01*
G02X583537Y1681456I2002J610D01*
G02X584259Y1683038I2094J0D01*
G01X584578Y1683688D01*
G03Y1683950I-267J131D01*
G01X584261Y1684597D01*
G02X583537Y1686180I1369J1583D01*
G02X583628Y1686790I2093J0D01*
G01Y1688821D01*
G02X583930Y1689124I302J1D01*
G37*
G36*
G01X599678D02*
X603378D01*
G02X603680Y1688821I-1J-303D01*
G01Y1678815D01*
G02X603378Y1678512I-302J-1D01*
G01X599678D01*
G02X599376Y1678815I1J303D01*
G01Y1680846D01*
G02X599285Y1681456I2002J610D01*
G02X600007Y1683038I2094J0D01*
G01X600326Y1683688D01*
G03Y1683950I-267J131D01*
G01X600009Y1684597D01*
G02X599285Y1686180I1369J1583D01*
G02X599376Y1686790I2093J0D01*
G01Y1688821D01*
G02X599678Y1689124I302J1D01*
G37*
G36*
G01X615426D02*
X619126D01*
G02X619428Y1688821I-1J-303D01*
G01Y1678815D01*
G02X619126Y1678512I-302J-1D01*
G01X615426D01*
G02X615124Y1678815I1J303D01*
G01Y1680846D01*
G02X615033Y1681456I2002J610D01*
G02X615755Y1683038I2094J0D01*
G01X616074Y1683688D01*
G03Y1683950I-267J131D01*
G01X615757Y1684597D01*
G02X615033Y1686180I1369J1583D01*
G02X615124Y1686790I2093J0D01*
G01Y1688821D01*
G02X615426Y1689124I302J1D01*
G37*
G36*
G01X1244954D02*
X1248654D01*
G02X1248956Y1688821I-1J-303D01*
G01Y1678815D01*
G02X1248654Y1678512I-302J-1D01*
G01X1244954D01*
G02X1244652Y1678815I1J303D01*
G01Y1681219D01*
G02X1244638Y1681456I2002J237D01*
G02X1244652Y1681693I2016J0D01*
G01Y1685943D01*
G02X1244638Y1686180I2002J237D01*
G02X1244652Y1686417I2016J0D01*
G01Y1688821D01*
G02X1244954Y1689124I302J1D01*
G37*
G36*
G01X1260702D02*
X1264402D01*
G02X1264704Y1688821I-1J-303D01*
G01Y1678815D01*
G02X1264402Y1678512I-302J-1D01*
G01X1260702D01*
G02X1260400Y1678815I1J303D01*
G01Y1681219D01*
G02X1260386Y1681456I2002J237D01*
G02X1260400Y1681693I2016J0D01*
G01Y1685943D01*
G02X1260386Y1686180I2002J237D01*
G02X1260400Y1686417I2016J0D01*
G01Y1688821D01*
G02X1260702Y1689124I302J1D01*
G37*
G36*
G01X1276450D02*
X1280150D01*
G02X1280452Y1688821I-1J-303D01*
G01Y1678815D01*
G02X1280150Y1678512I-302J-1D01*
G01X1276450D01*
G02X1276148Y1678815I1J303D01*
G01Y1681219D01*
G02X1276134Y1681456I2002J237D01*
G02X1276148Y1681693I2016J0D01*
G01Y1685943D01*
G02X1276134Y1686180I2002J237D01*
G02X1276148Y1686417I2016J0D01*
G01Y1688821D01*
G02X1276450Y1689124I302J1D01*
G37*
G36*
G01X1292198D02*
X1295898D01*
G02X1296200Y1688821I-1J-303D01*
G01Y1678815D01*
G02X1295898Y1678512I-302J-1D01*
G01X1292198D01*
G02X1291896Y1678815I1J303D01*
G01Y1681219D01*
G02X1291882Y1681456I2002J237D01*
G02X1291896Y1681693I2016J0D01*
G01Y1685943D01*
G02X1291882Y1686180I2002J237D01*
G02X1291896Y1686417I2016J0D01*
G01Y1688821D01*
G02X1292198Y1689124I302J1D01*
G37*
G36*
G01X1311883D02*
X1315583D01*
G02X1315886Y1688821I0J-303D01*
G01Y1678815D01*
G02X1315583Y1678512I-303J0D01*
G01X1311883D01*
G02X1311580Y1678815I0J303D01*
G01Y1681227D01*
G02X1311567Y1681456I2003J229D01*
G02X1311580Y1681685I2016J0D01*
G01Y1685951D01*
G02X1311567Y1686180I2003J229D01*
G02X1311580Y1686409I2016J0D01*
G01Y1688821D01*
G02X1311883Y1689124I303J0D01*
G37*
G36*
G01X1327631D02*
X1331331D01*
G02X1331634Y1688821I0J-303D01*
G01Y1678815D01*
G02X1331331Y1678512I-303J0D01*
G01X1327631D01*
G02X1327328Y1678815I0J303D01*
G01Y1681227D01*
G02X1327315Y1681456I2003J229D01*
G02X1327328Y1681685I2016J0D01*
G01Y1685951D01*
G02X1327315Y1686180I2003J229D01*
G02X1327328Y1686409I2016J0D01*
G01Y1688821D01*
G02X1327631Y1689124I303J0D01*
G37*
G36*
G01X1343379D02*
X1347079D01*
G02X1347382Y1688821I0J-303D01*
G01Y1678815D01*
G02X1347079Y1678512I-303J0D01*
G01X1343379D01*
G02X1343076Y1678815I0J303D01*
G01Y1681227D01*
G02X1343063Y1681456I2003J229D01*
G02X1343076Y1681685I2016J0D01*
G01Y1685951D01*
G02X1343063Y1686180I2003J229D01*
G02X1343076Y1686409I2016J0D01*
G01Y1688821D01*
G02X1343379Y1689124I303J0D01*
G37*
G36*
G01X1359127D02*
X1362827D01*
G02X1363130Y1688821I0J-303D01*
G01Y1678815D01*
G02X1362827Y1678512I-303J0D01*
G01X1359127D01*
G02X1358824Y1678815I0J303D01*
G01Y1681227D01*
G02X1358811Y1681456I2003J229D01*
G02X1358824Y1681685I2016J0D01*
G01Y1685951D01*
G02X1358811Y1686180I2003J229D01*
G02X1358824Y1686409I2016J0D01*
G01Y1688821D01*
G02X1359127Y1689124I303J0D01*
G37*
G36*
G01X1509127D02*
X1512827D01*
G02X1513130Y1688821I0J-303D01*
G01Y1678815D01*
G02X1512827Y1678512I-303J0D01*
G01X1509127D01*
G02X1508824Y1678815I0J303D01*
G01Y1680849D01*
G02X1508734Y1681456I2002J607D01*
G02X1509456Y1683038I2094J0D01*
G01X1509775Y1683688D01*
G03Y1683950I-267J131D01*
G01X1509458Y1684597D01*
G02X1508734Y1686180I1369J1583D01*
G02X1508824Y1686787I2092J0D01*
G01Y1688821D01*
G02X1509127Y1689124I303J0D01*
G37*
G36*
G01X1524875D02*
X1528575D01*
G02X1528878Y1688821I0J-303D01*
G01Y1678815D01*
G02X1528575Y1678512I-303J0D01*
G01X1524875D01*
G02X1524572Y1678815I0J303D01*
G01Y1680849D01*
G02X1524482Y1681456I2002J607D01*
G02X1525204Y1683038I2094J0D01*
G01X1525523Y1683688D01*
G03Y1683950I-267J131D01*
G01X1525206Y1684597D01*
G02X1524482Y1686180I1369J1583D01*
G02X1524572Y1686787I2092J0D01*
G01Y1688821D01*
G02X1524875Y1689124I303J0D01*
G37*
G36*
G01X1540623D02*
X1544323D01*
G02X1544626Y1688821I0J-303D01*
G01Y1678815D01*
G02X1544323Y1678512I-303J0D01*
G01X1540623D01*
G02X1540320Y1678815I0J303D01*
G01Y1680849D01*
G02X1540230Y1681456I2002J607D01*
G02X1540952Y1683038I2094J0D01*
G01X1541271Y1683688D01*
G03Y1683950I-267J131D01*
G01X1540954Y1684597D01*
G02X1540230Y1686180I1369J1583D01*
G02X1540320Y1686787I2092J0D01*
G01Y1688821D01*
G02X1540623Y1689124I303J0D01*
G37*
G36*
G01X1556371D02*
X1560071D01*
G02X1560374Y1688821I0J-303D01*
G01Y1678815D01*
G02X1560071Y1678512I-303J0D01*
G01X1556371D01*
G02X1556068Y1678815I0J303D01*
G01Y1680849D01*
G02X1555978Y1681456I2002J607D01*
G02X1556700Y1683038I2094J0D01*
G01X1557019Y1683688D01*
G03Y1683950I-267J131D01*
G01X1556702Y1684597D01*
G02X1555978Y1686180I1369J1583D01*
G02X1556068Y1686787I2092J0D01*
G01Y1688821D01*
G02X1556371Y1689124I303J0D01*
G37*
G36*
G01X1576056D02*
X1579756D01*
G02X1580058Y1688821I-1J-303D01*
G01Y1678815D01*
G02X1579756Y1678512I-302J-1D01*
G01X1576056D01*
G02X1575754Y1678815I1J303D01*
G01Y1680846D01*
G02X1575663Y1681456I2002J610D01*
G02X1576385Y1683038I2094J0D01*
G01X1576704Y1683688D01*
G03Y1683950I-267J131D01*
G01X1576387Y1684597D01*
G02X1575663Y1686180I1369J1583D01*
G02X1575754Y1686790I2093J0D01*
G01Y1688821D01*
G02X1576056Y1689124I302J1D01*
G37*
G36*
G01X1591804D02*
X1595504D01*
G02X1595806Y1688821I-1J-303D01*
G01Y1678815D01*
G02X1595504Y1678512I-302J-1D01*
G01X1591804D01*
G02X1591502Y1678815I1J303D01*
G01Y1680846D01*
G02X1591411Y1681456I2002J610D01*
G02X1592133Y1683038I2094J0D01*
G01X1592452Y1683688D01*
G03Y1683950I-267J131D01*
G01X1592135Y1684597D01*
G02X1591411Y1686180I1369J1583D01*
G02X1591502Y1686790I2093J0D01*
G01Y1688821D01*
G02X1591804Y1689124I302J1D01*
G37*
G36*
G01X1607552D02*
X1611252D01*
G02X1611554Y1688821I-1J-303D01*
G01Y1678815D01*
G02X1611252Y1678512I-302J-1D01*
G01X1607552D01*
G02X1607250Y1678815I1J303D01*
G01Y1680846D01*
G02X1607159Y1681456I2002J610D01*
G02X1607881Y1683038I2094J0D01*
G01X1608200Y1683688D01*
G03Y1683950I-267J131D01*
G01X1607883Y1684597D01*
G02X1607159Y1686180I1369J1583D01*
G02X1607250Y1686790I2093J0D01*
G01Y1688821D01*
G02X1607552Y1689124I302J1D01*
G37*
G36*
G01X1623300D02*
X1627000D01*
G02X1627302Y1688821I-1J-303D01*
G01Y1678815D01*
G02X1627000Y1678512I-302J-1D01*
G01X1623300D01*
G02X1622998Y1678815I1J303D01*
G01Y1680846D01*
G02X1622907Y1681456I2002J610D01*
G02X1623629Y1683038I2094J0D01*
G01X1623948Y1683688D01*
G03Y1683950I-267J131D01*
G01X1623631Y1684597D01*
G02X1622907Y1686180I1369J1583D01*
G02X1622998Y1686790I2093J0D01*
G01Y1688821D01*
G02X1623300Y1689124I302J1D01*
G37*
G36*
G01X229206Y1699360D02*
X232906D01*
G02X233208Y1699057I-1J-303D01*
G01Y1689051D01*
G02X232906Y1688748I-302J-1D01*
G01X229206D01*
G02X228904Y1689051I1J303D01*
G01Y1691082D01*
G02X228813Y1691692I2002J610D01*
G02X229535Y1693274I2094J0D01*
G01X229854Y1693924D01*
G03Y1694186I-267J131D01*
G01X229536Y1694835D01*
G02X228813Y1696417I1369J1582D01*
G02X228904Y1697027I2093J0D01*
G01Y1699057D01*
G02X229206Y1699360I302J1D01*
G37*
G36*
G01X244954D02*
X248654D01*
G02X248956Y1699057I-1J-303D01*
G01Y1689051D01*
G02X248654Y1688748I-302J-1D01*
G01X244954D01*
G02X244652Y1689051I1J303D01*
G01Y1691082D01*
G02X244561Y1691692I2002J610D01*
G02X245283Y1693274I2094J0D01*
G01X245602Y1693924D01*
G03Y1694186I-267J131D01*
G01X245284Y1694835D01*
G02X244561Y1696417I1369J1582D01*
G02X244652Y1697027I2093J0D01*
G01Y1699057D01*
G02X244954Y1699360I302J1D01*
G37*
G36*
G01X260702D02*
X264402D01*
G02X264704Y1699057I-1J-303D01*
G01Y1689051D01*
G02X264402Y1688748I-302J-1D01*
G01X260702D01*
G02X260400Y1689051I1J303D01*
G01Y1691082D01*
G02X260309Y1691692I2002J610D01*
G02X261031Y1693274I2094J0D01*
G01X261350Y1693924D01*
G03Y1694186I-267J131D01*
G01X261032Y1694835D01*
G02X260309Y1696417I1369J1582D01*
G02X260400Y1697027I2093J0D01*
G01Y1699057D01*
G02X260702Y1699360I302J1D01*
G37*
G36*
G01X276450D02*
X280150D01*
G02X280452Y1699057I-1J-303D01*
G01Y1689051D01*
G02X280150Y1688748I-302J-1D01*
G01X276450D01*
G02X276148Y1689051I1J303D01*
G01Y1691082D01*
G02X276057Y1691692I2002J610D01*
G02X276779Y1693274I2094J0D01*
G01X277098Y1693924D01*
G03Y1694186I-267J131D01*
G01X276780Y1694835D01*
G02X276057Y1696417I1369J1582D01*
G02X276148Y1697027I2093J0D01*
G01Y1699057D01*
G02X276450Y1699360I302J1D01*
G37*
G36*
G01X296135D02*
X299835D01*
G02X300138Y1699057I0J-303D01*
G01Y1689051D01*
G02X299835Y1688748I-303J0D01*
G01X296135D01*
G02X295832Y1689051I0J303D01*
G01Y1691085D01*
G02X295742Y1691692I2002J607D01*
G02X296464Y1693274I2094J0D01*
G01X296783Y1693924D01*
G03Y1694186I-267J131D01*
G01X296465Y1694835D01*
G02X295742Y1696417I1369J1582D01*
G02X295832Y1697024I2092J0D01*
G01Y1699057D01*
G02X296135Y1699360I303J0D01*
G37*
G36*
G01X311883D02*
X315583D01*
G02X315886Y1699057I0J-303D01*
G01Y1689051D01*
G02X315583Y1688748I-303J0D01*
G01X311883D01*
G02X311580Y1689051I0J303D01*
G01Y1691085D01*
G02X311490Y1691692I2002J607D01*
G02X312212Y1693274I2094J0D01*
G01X312531Y1693924D01*
G03Y1694186I-267J131D01*
G01X312213Y1694835D01*
G02X311490Y1696417I1369J1582D01*
G02X311580Y1697024I2092J0D01*
G01Y1699057D01*
G02X311883Y1699360I303J0D01*
G37*
G36*
G01X327631D02*
X331331D01*
G02X331634Y1699057I0J-303D01*
G01Y1689051D01*
G02X331331Y1688748I-303J0D01*
G01X327631D01*
G02X327328Y1689051I0J303D01*
G01Y1691085D01*
G02X327238Y1691692I2002J607D01*
G02X327960Y1693274I2094J0D01*
G01X328279Y1693924D01*
G03Y1694186I-267J131D01*
G01X327961Y1694835D01*
G02X327238Y1696417I1369J1582D01*
G02X327328Y1697024I2092J0D01*
G01Y1699057D01*
G02X327631Y1699360I303J0D01*
G37*
G36*
G01X343379D02*
X347079D01*
G02X347382Y1699057I0J-303D01*
G01Y1689051D01*
G02X347079Y1688748I-303J0D01*
G01X343379D01*
G02X343076Y1689051I0J303D01*
G01Y1691085D01*
G02X342986Y1691692I2002J607D01*
G02X343708Y1693274I2094J0D01*
G01X344027Y1693924D01*
G03Y1694186I-267J131D01*
G01X343709Y1694835D01*
G02X342986Y1696417I1369J1582D01*
G02X343076Y1697024I2092J0D01*
G01Y1699057D01*
G02X343379Y1699360I303J0D01*
G37*
G36*
G01X493379D02*
X497079D01*
G02X497382Y1699057I0J-303D01*
G01Y1689051D01*
G02X497079Y1688748I-303J0D01*
G01X493379D01*
G02X493076Y1689051I0J303D01*
G01Y1691463D01*
G02X493063Y1691692I2003J229D01*
G02X493076Y1691921I2016J0D01*
G01Y1696188D01*
G02X493063Y1696417I2003J229D01*
G02X493076Y1696646I2016J0D01*
G01Y1699057D01*
G02X493379Y1699360I303J0D01*
G37*
G36*
G01X509127D02*
X512827D01*
G02X513130Y1699057I0J-303D01*
G01Y1689051D01*
G02X512827Y1688748I-303J0D01*
G01X509127D01*
G02X508824Y1689051I0J303D01*
G01Y1691463D01*
G02X508811Y1691692I2003J229D01*
G02X508824Y1691921I2016J0D01*
G01Y1696188D01*
G02X508811Y1696417I2003J229D01*
G02X508824Y1696646I2016J0D01*
G01Y1699057D01*
G02X509127Y1699360I303J0D01*
G37*
G36*
G01X524875D02*
X528575D01*
G02X528878Y1699057I0J-303D01*
G01Y1689051D01*
G02X528575Y1688748I-303J0D01*
G01X524875D01*
G02X524572Y1689051I0J303D01*
G01Y1691463D01*
G02X524559Y1691692I2003J229D01*
G02X524572Y1691921I2016J0D01*
G01Y1696188D01*
G02X524559Y1696417I2003J229D01*
G02X524572Y1696646I2016J0D01*
G01Y1699057D01*
G02X524875Y1699360I303J0D01*
G37*
G36*
G01X540623D02*
X544323D01*
G02X544626Y1699057I0J-303D01*
G01Y1689051D01*
G02X544323Y1688748I-303J0D01*
G01X540623D01*
G02X540320Y1689051I0J303D01*
G01Y1691463D01*
G02X540307Y1691692I2003J229D01*
G02X540320Y1691921I2016J0D01*
G01Y1696188D01*
G02X540307Y1696417I2003J229D01*
G02X540320Y1696646I2016J0D01*
G01Y1699057D01*
G02X540623Y1699360I303J0D01*
G37*
G36*
G01X560308D02*
X564008D01*
G02X564310Y1699057I-1J-303D01*
G01Y1689051D01*
G02X564008Y1688748I-302J-1D01*
G01X560308D01*
G02X560006Y1689051I1J303D01*
G01Y1691455D01*
G02X559992Y1691692I2002J237D01*
G02X560006Y1691929I2016J0D01*
G01Y1696180D01*
G02X559992Y1696417I2002J237D01*
G02X560006Y1696654I2016J0D01*
G01Y1699057D01*
G02X560308Y1699360I302J1D01*
G37*
G36*
G01X576056D02*
X579756D01*
G02X580058Y1699057I-1J-303D01*
G01Y1689051D01*
G02X579756Y1688748I-302J-1D01*
G01X576056D01*
G02X575754Y1689051I1J303D01*
G01Y1691455D01*
G02X575740Y1691692I2002J237D01*
G02X575754Y1691929I2016J0D01*
G01Y1696180D01*
G02X575740Y1696417I2002J237D01*
G02X575754Y1696654I2016J0D01*
G01Y1699057D01*
G02X576056Y1699360I302J1D01*
G37*
G36*
G01X591804D02*
X595504D01*
G02X595806Y1699057I-1J-303D01*
G01Y1689051D01*
G02X595504Y1688748I-302J-1D01*
G01X591804D01*
G02X591502Y1689051I1J303D01*
G01Y1691455D01*
G02X591488Y1691692I2002J237D01*
G02X591502Y1691929I2016J0D01*
G01Y1696180D01*
G02X591488Y1696417I2002J237D01*
G02X591502Y1696654I2016J0D01*
G01Y1699057D01*
G02X591804Y1699360I302J1D01*
G37*
G36*
G01X607552D02*
X611252D01*
G02X611554Y1699057I-1J-303D01*
G01Y1689051D01*
G02X611252Y1688748I-302J-1D01*
G01X607552D01*
G02X607250Y1689051I1J303D01*
G01Y1691455D01*
G02X607236Y1691692I2002J237D01*
G02X607250Y1691929I2016J0D01*
G01Y1696180D01*
G02X607236Y1696417I2002J237D01*
G02X607250Y1696654I2016J0D01*
G01Y1699057D01*
G02X607552Y1699360I302J1D01*
G37*
G36*
G01X1237080D02*
X1240780D01*
G02X1241082Y1699057I-1J-303D01*
G01Y1689051D01*
G02X1240780Y1688748I-302J-1D01*
G01X1237080D01*
G02X1236778Y1689051I1J303D01*
G01Y1691082D01*
G02X1236687Y1691692I2002J610D01*
G02X1237409Y1693274I2094J0D01*
G01X1237728Y1693924D01*
G03Y1694186I-267J131D01*
G01X1237410Y1694835D01*
G02X1236687Y1696417I1369J1582D01*
G02X1236778Y1697027I2093J0D01*
G01Y1699057D01*
G02X1237080Y1699360I302J1D01*
G37*
G36*
G01X1252828D02*
X1256528D01*
G02X1256830Y1699057I-1J-303D01*
G01Y1689051D01*
G02X1256528Y1688748I-302J-1D01*
G01X1252828D01*
G02X1252526Y1689051I1J303D01*
G01Y1691082D01*
G02X1252435Y1691692I2002J610D01*
G02X1253157Y1693274I2094J0D01*
G01X1253476Y1693924D01*
G03Y1694186I-267J131D01*
G01X1253158Y1694835D01*
G02X1252435Y1696417I1369J1582D01*
G02X1252526Y1697027I2093J0D01*
G01Y1699057D01*
G02X1252828Y1699360I302J1D01*
G37*
G36*
G01X1268576D02*
X1272276D01*
G02X1272578Y1699057I-1J-303D01*
G01Y1689051D01*
G02X1272276Y1688748I-302J-1D01*
G01X1268576D01*
G02X1268274Y1689051I1J303D01*
G01Y1691082D01*
G02X1268183Y1691692I2002J610D01*
G02X1268905Y1693274I2094J0D01*
G01X1269224Y1693924D01*
G03Y1694186I-267J131D01*
G01X1268906Y1694835D01*
G02X1268183Y1696417I1369J1582D01*
G02X1268274Y1697027I2093J0D01*
G01Y1699057D01*
G02X1268576Y1699360I302J1D01*
G37*
G36*
G01X1284324D02*
X1288024D01*
G02X1288326Y1699057I-1J-303D01*
G01Y1689051D01*
G02X1288024Y1688748I-302J-1D01*
G01X1284324D01*
G02X1284022Y1689051I1J303D01*
G01Y1691082D01*
G02X1283931Y1691692I2002J610D01*
G02X1284653Y1693274I2094J0D01*
G01X1284972Y1693924D01*
G03Y1694186I-267J131D01*
G01X1284654Y1694835D01*
G02X1283931Y1696417I1369J1582D01*
G02X1284022Y1697027I2093J0D01*
G01Y1699057D01*
G02X1284324Y1699360I302J1D01*
G37*
G36*
G01X1304009D02*
X1307709D01*
G02X1308012Y1699057I0J-303D01*
G01Y1689051D01*
G02X1307709Y1688748I-303J0D01*
G01X1304009D01*
G02X1303706Y1689051I0J303D01*
G01Y1691085D01*
G02X1303616Y1691692I2002J607D01*
G02X1304338Y1693274I2094J0D01*
G01X1304657Y1693924D01*
G03Y1694186I-267J131D01*
G01X1304339Y1694835D01*
G02X1303616Y1696417I1369J1582D01*
G02X1303706Y1697024I2092J0D01*
G01Y1699057D01*
G02X1304009Y1699360I303J0D01*
G37*
G36*
G01X1319757D02*
X1323457D01*
G02X1323760Y1699057I0J-303D01*
G01Y1689051D01*
G02X1323457Y1688748I-303J0D01*
G01X1319757D01*
G02X1319454Y1689051I0J303D01*
G01Y1691085D01*
G02X1319364Y1691692I2002J607D01*
G02X1320086Y1693274I2094J0D01*
G01X1320405Y1693924D01*
G03Y1694186I-267J131D01*
G01X1320087Y1694835D01*
G02X1319364Y1696417I1369J1582D01*
G02X1319454Y1697024I2092J0D01*
G01Y1699057D01*
G02X1319757Y1699360I303J0D01*
G37*
G36*
G01X1335505D02*
X1339205D01*
G02X1339508Y1699057I0J-303D01*
G01Y1689051D01*
G02X1339205Y1688748I-303J0D01*
G01X1335505D01*
G02X1335202Y1689051I0J303D01*
G01Y1691085D01*
G02X1335112Y1691692I2002J607D01*
G02X1335834Y1693274I2094J0D01*
G01X1336153Y1693924D01*
G03Y1694186I-267J131D01*
G01X1335835Y1694835D01*
G02X1335112Y1696417I1369J1582D01*
G02X1335202Y1697024I2092J0D01*
G01Y1699057D01*
G02X1335505Y1699360I303J0D01*
G37*
G36*
G01X1351253D02*
X1354953D01*
G02X1355256Y1699057I0J-303D01*
G01Y1689051D01*
G02X1354953Y1688748I-303J0D01*
G01X1351253D01*
G02X1350950Y1689051I0J303D01*
G01Y1691085D01*
G02X1350860Y1691692I2002J607D01*
G02X1351582Y1693274I2094J0D01*
G01X1351901Y1693924D01*
G03Y1694186I-267J131D01*
G01X1351583Y1694835D01*
G02X1350860Y1696417I1369J1582D01*
G02X1350950Y1697024I2092J0D01*
G01Y1699057D01*
G02X1351253Y1699360I303J0D01*
G37*
G36*
G01X1501253D02*
X1504953D01*
G02X1505256Y1699057I0J-303D01*
G01Y1689051D01*
G02X1504953Y1688748I-303J0D01*
G01X1501253D01*
G02X1500950Y1689051I0J303D01*
G01Y1691463D01*
G02X1500937Y1691692I2003J229D01*
G02X1500950Y1691921I2016J0D01*
G01Y1696188D01*
G02X1500937Y1696417I2003J229D01*
G02X1500950Y1696646I2016J0D01*
G01Y1699057D01*
G02X1501253Y1699360I303J0D01*
G37*
G36*
G01X1517001D02*
X1520701D01*
G02X1521004Y1699057I0J-303D01*
G01Y1689051D01*
G02X1520701Y1688748I-303J0D01*
G01X1517001D01*
G02X1516698Y1689051I0J303D01*
G01Y1691463D01*
G02X1516685Y1691692I2003J229D01*
G02X1516698Y1691921I2016J0D01*
G01Y1696188D01*
G02X1516685Y1696417I2003J229D01*
G02X1516698Y1696646I2016J0D01*
G01Y1699057D01*
G02X1517001Y1699360I303J0D01*
G37*
G36*
G01X1532749D02*
X1536449D01*
G02X1536752Y1699057I0J-303D01*
G01Y1689051D01*
G02X1536449Y1688748I-303J0D01*
G01X1532749D01*
G02X1532446Y1689051I0J303D01*
G01Y1691463D01*
G02X1532433Y1691692I2003J229D01*
G02X1532446Y1691921I2016J0D01*
G01Y1696188D01*
G02X1532433Y1696417I2003J229D01*
G02X1532446Y1696646I2016J0D01*
G01Y1699057D01*
G02X1532749Y1699360I303J0D01*
G37*
G36*
G01X1548497D02*
X1552197D01*
G02X1552500Y1699057I0J-303D01*
G01Y1689051D01*
G02X1552197Y1688748I-303J0D01*
G01X1548497D01*
G02X1548194Y1689051I0J303D01*
G01Y1691463D01*
G02X1548181Y1691692I2003J229D01*
G02X1548194Y1691921I2016J0D01*
G01Y1696188D01*
G02X1548181Y1696417I2003J229D01*
G02X1548194Y1696646I2016J0D01*
G01Y1699057D01*
G02X1548497Y1699360I303J0D01*
G37*
G36*
G01X1568182D02*
X1571882D01*
G02X1572184Y1699057I-1J-303D01*
G01Y1689051D01*
G02X1571882Y1688748I-302J-1D01*
G01X1568182D01*
G02X1567880Y1689051I1J303D01*
G01Y1691455D01*
G02X1567866Y1691692I2002J237D01*
G02X1567880Y1691929I2016J0D01*
G01Y1696180D01*
G02X1567866Y1696417I2002J237D01*
G02X1567880Y1696654I2016J0D01*
G01Y1699057D01*
G02X1568182Y1699360I302J1D01*
G37*
G36*
G01X1583930D02*
X1587630D01*
G02X1587932Y1699057I-1J-303D01*
G01Y1689051D01*
G02X1587630Y1688748I-302J-1D01*
G01X1583930D01*
G02X1583628Y1689051I1J303D01*
G01Y1691455D01*
G02X1583614Y1691692I2002J237D01*
G02X1583628Y1691929I2016J0D01*
G01Y1696180D01*
G02X1583614Y1696417I2002J237D01*
G02X1583628Y1696654I2016J0D01*
G01Y1699057D01*
G02X1583930Y1699360I302J1D01*
G37*
G36*
G01X1599678D02*
X1603378D01*
G02X1603680Y1699057I-1J-303D01*
G01Y1689051D01*
G02X1603378Y1688748I-302J-1D01*
G01X1599678D01*
G02X1599376Y1689051I1J303D01*
G01Y1691455D01*
G02X1599362Y1691692I2002J237D01*
G02X1599376Y1691929I2016J0D01*
G01Y1696180D01*
G02X1599362Y1696417I2002J237D01*
G02X1599376Y1696654I2016J0D01*
G01Y1699057D01*
G02X1599678Y1699360I302J1D01*
G37*
G36*
G01X1615426D02*
X1619126D01*
G02X1619428Y1699057I-1J-303D01*
G01Y1689051D01*
G02X1619126Y1688748I-302J-1D01*
G01X1615426D01*
G02X1615124Y1689051I1J303D01*
G01Y1691455D01*
G02X1615110Y1691692I2002J237D01*
G02X1615124Y1691929I2016J0D01*
G01Y1696180D01*
G02X1615110Y1696417I2002J237D01*
G02X1615124Y1696654I2016J0D01*
G01Y1699057D01*
G02X1615426Y1699360I302J1D01*
G37*
G36*
G01X237080Y1703296D02*
X240780D01*
G02X241082Y1702994I0J-302D01*
G01Y1692988D01*
G02X240780Y1692686I-302J0D01*
G01X237080D01*
G02X236778Y1692988I0J302D01*
G01Y1695019D01*
G02X236687Y1695629I2002J610D01*
G02X237409Y1697211I2094J0D01*
G01X237728Y1697861D01*
G03Y1698123I-267J131D01*
G01X237410Y1698772D01*
G02X236687Y1700354I1369J1582D01*
G02X236778Y1700964I2093J0D01*
G01Y1702994D01*
G02X237080Y1703296I302J0D01*
G37*
G36*
G01X252828D02*
X256528D01*
G02X256830Y1702994I0J-302D01*
G01Y1692988D01*
G02X256528Y1692686I-302J0D01*
G01X252828D01*
G02X252526Y1692988I0J302D01*
G01Y1695019D01*
G02X252435Y1695629I2002J610D01*
G02X253157Y1697211I2094J0D01*
G01X253476Y1697861D01*
G03Y1698123I-267J131D01*
G01X253158Y1698772D01*
G02X252435Y1700354I1369J1582D01*
G02X252526Y1700964I2093J0D01*
G01Y1702994D01*
G02X252828Y1703296I302J0D01*
G37*
G36*
G01X268576D02*
X272276D01*
G02X272578Y1702994I0J-302D01*
G01Y1692988D01*
G02X272276Y1692686I-302J0D01*
G01X268576D01*
G02X268274Y1692988I0J302D01*
G01Y1695019D01*
G02X268183Y1695629I2002J610D01*
G02X268905Y1697211I2094J0D01*
G01X269224Y1697861D01*
G03Y1698123I-267J131D01*
G01X268906Y1698772D01*
G02X268183Y1700354I1369J1582D01*
G02X268274Y1700964I2093J0D01*
G01Y1702994D01*
G02X268576Y1703296I302J0D01*
G37*
G36*
G01X284324D02*
X288024D01*
G02X288326Y1702994I0J-302D01*
G01Y1692988D01*
G02X288024Y1692686I-302J0D01*
G01X284324D01*
G02X284022Y1692988I0J302D01*
G01Y1695019D01*
G02X283931Y1695629I2002J610D01*
G02X284653Y1697211I2094J0D01*
G01X284972Y1697861D01*
G03Y1698123I-267J131D01*
G01X284654Y1698772D01*
G02X283931Y1700354I1369J1582D01*
G02X284022Y1700964I2093J0D01*
G01Y1702994D01*
G02X284324Y1703296I302J0D01*
G37*
G36*
G01X568182D02*
X571882D01*
G02X572184Y1702994I0J-302D01*
G01Y1692988D01*
G02X571882Y1692686I-302J0D01*
G01X568182D01*
G02X567880Y1692988I0J302D01*
G01Y1695392D01*
G02X567866Y1695629I2002J237D01*
G02X567880Y1695866I2016J0D01*
G01Y1700117D01*
G02X567866Y1700354I2002J237D01*
G02X567880Y1700591I2016J0D01*
G01Y1702994D01*
G02X568182Y1703296I302J0D01*
G37*
G36*
G01X583930D02*
X587630D01*
G02X587932Y1702994I0J-302D01*
G01Y1692988D01*
G02X587630Y1692686I-302J0D01*
G01X583930D01*
G02X583628Y1692988I0J302D01*
G01Y1695392D01*
G02X583614Y1695629I2002J237D01*
G02X583628Y1695866I2016J0D01*
G01Y1700117D01*
G02X583614Y1700354I2002J237D01*
G02X583628Y1700591I2016J0D01*
G01Y1702994D01*
G02X583930Y1703296I302J0D01*
G37*
G36*
G01X599678D02*
X603378D01*
G02X603680Y1702994I0J-302D01*
G01Y1692988D01*
G02X603378Y1692686I-302J0D01*
G01X599678D01*
G02X599376Y1692988I0J302D01*
G01Y1695392D01*
G02X599362Y1695629I2002J237D01*
G02X599376Y1695866I2016J0D01*
G01Y1700117D01*
G02X599362Y1700354I2002J237D01*
G02X599376Y1700591I2016J0D01*
G01Y1702994D01*
G02X599678Y1703296I302J0D01*
G37*
G36*
G01X615426D02*
X619126D01*
G02X619428Y1702994I0J-302D01*
G01Y1692988D01*
G02X619126Y1692686I-302J0D01*
G01X615426D01*
G02X615124Y1692988I0J302D01*
G01Y1695392D01*
G02X615110Y1695629I2002J237D01*
G02X615124Y1695866I2016J0D01*
G01Y1700117D01*
G02X615110Y1700354I2002J237D01*
G02X615124Y1700591I2016J0D01*
G01Y1702994D01*
G02X615426Y1703296I302J0D01*
G37*
G36*
G01X1244954D02*
X1248654D01*
G02X1248956Y1702994I0J-302D01*
G01Y1692988D01*
G02X1248654Y1692686I-302J0D01*
G01X1244954D01*
G02X1244652Y1692988I0J302D01*
G01Y1695019D01*
G02X1244561Y1695629I2002J610D01*
G02X1245283Y1697211I2094J0D01*
G01X1245602Y1697861D01*
G03Y1698123I-267J131D01*
G01X1245284Y1698772D01*
G02X1244561Y1700354I1369J1582D01*
G02X1244652Y1700964I2093J0D01*
G01Y1702994D01*
G02X1244954Y1703296I302J0D01*
G37*
G36*
G01X1260702D02*
X1264402D01*
G02X1264704Y1702994I0J-302D01*
G01Y1692988D01*
G02X1264402Y1692686I-302J0D01*
G01X1260702D01*
G02X1260400Y1692988I0J302D01*
G01Y1695019D01*
G02X1260309Y1695629I2002J610D01*
G02X1261031Y1697211I2094J0D01*
G01X1261350Y1697861D01*
G03Y1698123I-267J131D01*
G01X1261032Y1698772D01*
G02X1260309Y1700354I1369J1582D01*
G02X1260400Y1700964I2093J0D01*
G01Y1702994D01*
G02X1260702Y1703296I302J0D01*
G37*
G36*
G01X1276450D02*
X1280150D01*
G02X1280452Y1702994I0J-302D01*
G01Y1692988D01*
G02X1280150Y1692686I-302J0D01*
G01X1276450D01*
G02X1276148Y1692988I0J302D01*
G01Y1695019D01*
G02X1276057Y1695629I2002J610D01*
G02X1276779Y1697211I2094J0D01*
G01X1277098Y1697861D01*
G03Y1698123I-267J131D01*
G01X1276780Y1698772D01*
G02X1276057Y1700354I1369J1582D01*
G02X1276148Y1700964I2093J0D01*
G01Y1702994D01*
G02X1276450Y1703296I302J0D01*
G37*
G36*
G01X1292198D02*
X1295898D01*
G02X1296200Y1702994I0J-302D01*
G01Y1692988D01*
G02X1295898Y1692686I-302J0D01*
G01X1292198D01*
G02X1291896Y1692988I0J302D01*
G01Y1695019D01*
G02X1291805Y1695629I2002J610D01*
G02X1292527Y1697211I2094J0D01*
G01X1292846Y1697861D01*
G03Y1698123I-267J131D01*
G01X1292528Y1698772D01*
G02X1291805Y1700354I1369J1582D01*
G02X1291896Y1700964I2093J0D01*
G01Y1702994D01*
G02X1292198Y1703296I302J0D01*
G37*
G36*
G01X1576056D02*
X1579756D01*
G02X1580058Y1702994I0J-302D01*
G01Y1692988D01*
G02X1579756Y1692686I-302J0D01*
G01X1576056D01*
G02X1575754Y1692988I0J302D01*
G01Y1695392D01*
G02X1575740Y1695629I2002J237D01*
G02X1575754Y1695866I2016J0D01*
G01Y1700117D01*
G02X1575740Y1700354I2002J237D01*
G02X1575754Y1700591I2016J0D01*
G01Y1702994D01*
G02X1576056Y1703296I302J0D01*
G37*
G36*
G01X1591804D02*
X1595504D01*
G02X1595806Y1702994I0J-302D01*
G01Y1692988D01*
G02X1595504Y1692686I-302J0D01*
G01X1591804D01*
G02X1591502Y1692988I0J302D01*
G01Y1695392D01*
G02X1591488Y1695629I2002J237D01*
G02X1591502Y1695866I2016J0D01*
G01Y1700117D01*
G02X1591488Y1700354I2002J237D01*
G02X1591502Y1700591I2016J0D01*
G01Y1702994D01*
G02X1591804Y1703296I302J0D01*
G37*
G36*
G01X1607552D02*
X1611252D01*
G02X1611554Y1702994I0J-302D01*
G01Y1692988D01*
G02X1611252Y1692686I-302J0D01*
G01X1607552D01*
G02X1607250Y1692988I0J302D01*
G01Y1695392D01*
G02X1607236Y1695629I2002J237D01*
G02X1607250Y1695866I2016J0D01*
G01Y1700117D01*
G02X1607236Y1700354I2002J237D01*
G02X1607250Y1700591I2016J0D01*
G01Y1702994D01*
G02X1607552Y1703296I302J0D01*
G37*
G36*
G01X1623300D02*
X1627000D01*
G02X1627302Y1702994I0J-302D01*
G01Y1692988D01*
G02X1627000Y1692686I-302J0D01*
G01X1623300D01*
G02X1622998Y1692988I0J302D01*
G01Y1695392D01*
G02X1622984Y1695629I2002J237D01*
G02X1622998Y1695866I2016J0D01*
G01Y1700117D01*
G02X1622984Y1700354I2002J237D01*
G02X1622998Y1700591I2016J0D01*
G01Y1702994D01*
G02X1623300Y1703296I302J0D01*
G37*
G36*
G01X304009D02*
X307709D01*
G02X308012Y1702994I1J-302D01*
G01Y1692988D01*
G02X307709Y1692686I-303J1D01*
G01X304009D01*
G02X303706Y1692988I-1J302D01*
G01Y1695022D01*
G02X303616Y1695629I2002J607D01*
G02X304338Y1697211I2094J0D01*
G01X304657Y1697861D01*
G03Y1698123I-267J131D01*
G01X304339Y1698772D01*
G02X303616Y1700354I1369J1582D01*
G02X303706Y1700961I2092J0D01*
G01Y1702994D01*
G02X304009Y1703296I303J-1D01*
G37*
G36*
G01X319757D02*
X323457D01*
G02X323760Y1702994I1J-302D01*
G01Y1692988D01*
G02X323457Y1692686I-303J1D01*
G01X319757D01*
G02X319454Y1692988I-1J302D01*
G01Y1695022D01*
G02X319364Y1695629I2002J607D01*
G02X320086Y1697211I2094J0D01*
G01X320405Y1697861D01*
G03Y1698123I-267J131D01*
G01X320087Y1698772D01*
G02X319364Y1700354I1369J1582D01*
G02X319454Y1700961I2092J0D01*
G01Y1702994D01*
G02X319757Y1703296I303J-1D01*
G37*
G36*
G01X335505D02*
X339205D01*
G02X339508Y1702994I1J-302D01*
G01Y1692988D01*
G02X339205Y1692686I-303J1D01*
G01X335505D01*
G02X335202Y1692988I-1J302D01*
G01Y1695022D01*
G02X335112Y1695629I2002J607D01*
G02X335834Y1697211I2094J0D01*
G01X336153Y1697861D01*
G03Y1698123I-267J131D01*
G01X335835Y1698772D01*
G02X335112Y1700354I1369J1582D01*
G02X335202Y1700961I2092J0D01*
G01Y1702994D01*
G02X335505Y1703296I303J-1D01*
G37*
G36*
G01X351253D02*
X354953D01*
G02X355256Y1702994I1J-302D01*
G01Y1692988D01*
G02X354953Y1692686I-303J1D01*
G01X351253D01*
G02X350950Y1692988I-1J302D01*
G01Y1695022D01*
G02X350860Y1695629I2002J607D01*
G02X351582Y1697211I2094J0D01*
G01X351901Y1697861D01*
G03Y1698123I-267J131D01*
G01X351583Y1698772D01*
G02X350860Y1700354I1369J1582D01*
G02X350950Y1700961I2092J0D01*
G01Y1702994D01*
G02X351253Y1703296I303J-1D01*
G37*
G36*
G01X501253D02*
X504953D01*
G02X505256Y1702994I1J-302D01*
G01Y1692988D01*
G02X504953Y1692686I-303J1D01*
G01X501253D01*
G02X500950Y1692988I-1J302D01*
G01Y1695400D01*
G02X500937Y1695629I2003J229D01*
G02X500950Y1695858I2016J0D01*
G01Y1700125D01*
G02X500937Y1700354I2003J229D01*
G02X500950Y1700583I2016J0D01*
G01Y1702994D01*
G02X501253Y1703296I303J-1D01*
G37*
G36*
G01X517001D02*
X520701D01*
G02X521004Y1702994I1J-302D01*
G01Y1692988D01*
G02X520701Y1692686I-303J1D01*
G01X517001D01*
G02X516698Y1692988I-1J302D01*
G01Y1695400D01*
G02X516685Y1695629I2003J229D01*
G02X516698Y1695858I2016J0D01*
G01Y1700125D01*
G02X516685Y1700354I2003J229D01*
G02X516698Y1700583I2016J0D01*
G01Y1702994D01*
G02X517001Y1703296I303J-1D01*
G37*
G36*
G01X532749D02*
X536449D01*
G02X536752Y1702994I1J-302D01*
G01Y1692988D01*
G02X536449Y1692686I-303J1D01*
G01X532749D01*
G02X532446Y1692988I-1J302D01*
G01Y1695400D01*
G02X532433Y1695629I2003J229D01*
G02X532446Y1695858I2016J0D01*
G01Y1700125D01*
G02X532433Y1700354I2003J229D01*
G02X532446Y1700583I2016J0D01*
G01Y1702994D01*
G02X532749Y1703296I303J-1D01*
G37*
G36*
G01X548497D02*
X552197D01*
G02X552500Y1702994I1J-302D01*
G01Y1692988D01*
G02X552197Y1692686I-303J1D01*
G01X548497D01*
G02X548194Y1692988I-1J302D01*
G01Y1695400D01*
G02X548181Y1695629I2003J229D01*
G02X548194Y1695858I2016J0D01*
G01Y1700125D01*
G02X548181Y1700354I2003J229D01*
G02X548194Y1700583I2016J0D01*
G01Y1702994D01*
G02X548497Y1703296I303J-1D01*
G37*
G36*
G01X1311883D02*
X1315583D01*
G02X1315886Y1702994I1J-302D01*
G01Y1692988D01*
G02X1315583Y1692686I-303J1D01*
G01X1311883D01*
G02X1311580Y1692988I-1J302D01*
G01Y1695022D01*
G02X1311490Y1695629I2002J607D01*
G02X1312212Y1697211I2094J0D01*
G01X1312531Y1697861D01*
G03Y1698123I-267J131D01*
G01X1312213Y1698772D01*
G02X1311490Y1700354I1369J1582D01*
G02X1311580Y1700961I2092J0D01*
G01Y1702994D01*
G02X1311883Y1703296I303J-1D01*
G37*
G36*
G01X1327631D02*
X1331331D01*
G02X1331634Y1702994I1J-302D01*
G01Y1692988D01*
G02X1331331Y1692686I-303J1D01*
G01X1327631D01*
G02X1327328Y1692988I-1J302D01*
G01Y1695022D01*
G02X1327238Y1695629I2002J607D01*
G02X1327960Y1697211I2094J0D01*
G01X1328279Y1697861D01*
G03Y1698123I-267J131D01*
G01X1327961Y1698772D01*
G02X1327238Y1700354I1369J1582D01*
G02X1327328Y1700961I2092J0D01*
G01Y1702994D01*
G02X1327631Y1703296I303J-1D01*
G37*
G36*
G01X1343379D02*
X1347079D01*
G02X1347382Y1702994I1J-302D01*
G01Y1692988D01*
G02X1347079Y1692686I-303J1D01*
G01X1343379D01*
G02X1343076Y1692988I-1J302D01*
G01Y1695022D01*
G02X1342986Y1695629I2002J607D01*
G02X1343708Y1697211I2094J0D01*
G01X1344027Y1697861D01*
G03Y1698123I-267J131D01*
G01X1343709Y1698772D01*
G02X1342986Y1700354I1369J1582D01*
G02X1343076Y1700961I2092J0D01*
G01Y1702994D01*
G02X1343379Y1703296I303J-1D01*
G37*
G36*
G01X1359127D02*
X1362827D01*
G02X1363130Y1702994I1J-302D01*
G01Y1692988D01*
G02X1362827Y1692686I-303J1D01*
G01X1359127D01*
G02X1358824Y1692988I-1J302D01*
G01Y1695022D01*
G02X1358734Y1695629I2002J607D01*
G02X1359456Y1697211I2094J0D01*
G01X1359775Y1697861D01*
G03Y1698123I-267J131D01*
G01X1359457Y1698772D01*
G02X1358734Y1700354I1369J1582D01*
G02X1358824Y1700961I2092J0D01*
G01Y1702994D01*
G02X1359127Y1703296I303J-1D01*
G37*
G36*
G01X1509127D02*
X1512827D01*
G02X1513130Y1702994I1J-302D01*
G01Y1692988D01*
G02X1512827Y1692686I-303J1D01*
G01X1509127D01*
G02X1508824Y1692988I-1J302D01*
G01Y1695400D01*
G02X1508811Y1695629I2003J229D01*
G02X1508824Y1695858I2016J0D01*
G01Y1700125D01*
G02X1508811Y1700354I2003J229D01*
G02X1508824Y1700583I2016J0D01*
G01Y1702994D01*
G02X1509127Y1703296I303J-1D01*
G37*
G36*
G01X1524875D02*
X1528575D01*
G02X1528878Y1702994I1J-302D01*
G01Y1692988D01*
G02X1528575Y1692686I-303J1D01*
G01X1524875D01*
G02X1524572Y1692988I-1J302D01*
G01Y1695400D01*
G02X1524559Y1695629I2003J229D01*
G02X1524572Y1695858I2016J0D01*
G01Y1700125D01*
G02X1524559Y1700354I2003J229D01*
G02X1524572Y1700583I2016J0D01*
G01Y1702994D01*
G02X1524875Y1703296I303J-1D01*
G37*
G36*
G01X1540623D02*
X1544323D01*
G02X1544626Y1702994I1J-302D01*
G01Y1692988D01*
G02X1544323Y1692686I-303J1D01*
G01X1540623D01*
G02X1540320Y1692988I-1J302D01*
G01Y1695400D01*
G02X1540307Y1695629I2003J229D01*
G02X1540320Y1695858I2016J0D01*
G01Y1700125D01*
G02X1540307Y1700354I2003J229D01*
G02X1540320Y1700583I2016J0D01*
G01Y1702994D01*
G02X1540623Y1703296I303J-1D01*
G37*
G36*
G01X1556371D02*
X1560071D01*
G02X1560374Y1702994I1J-302D01*
G01Y1692988D01*
G02X1560071Y1692686I-303J1D01*
G01X1556371D01*
G02X1556068Y1692988I-1J302D01*
G01Y1695400D01*
G02X1556055Y1695629I2003J229D01*
G02X1556068Y1695858I2016J0D01*
G01Y1700125D01*
G02X1556055Y1700354I2003J229D01*
G02X1556068Y1700583I2016J0D01*
G01Y1702994D01*
G02X1556371Y1703296I303J-1D01*
G37*
G36*
G01X229206Y1713532D02*
X232906D01*
G02X233208Y1713230I0J-302D01*
G01Y1703224D01*
G02X232906Y1702922I-302J0D01*
G01X229206D01*
G02X228904Y1703224I0J302D01*
G01Y1705629D01*
G02X228890Y1705866I2002J237D01*
G02X228904Y1706103I2016J0D01*
G01Y1710353D01*
G02X228890Y1710590I2002J237D01*
G02X228904Y1710827I2016J0D01*
G01Y1713230D01*
G02X229206Y1713532I302J0D01*
G37*
G36*
G01X244954D02*
X248654D01*
G02X248956Y1713230I0J-302D01*
G01Y1703224D01*
G02X248654Y1702922I-302J0D01*
G01X244954D01*
G02X244652Y1703224I0J302D01*
G01Y1705629D01*
G02X244638Y1705866I2002J237D01*
G02X244652Y1706103I2016J0D01*
G01Y1710353D01*
G02X244638Y1710590I2002J237D01*
G02X244652Y1710827I2016J0D01*
G01Y1713230D01*
G02X244954Y1713532I302J0D01*
G37*
G36*
G01X260702D02*
X264402D01*
G02X264704Y1713230I0J-302D01*
G01Y1703224D01*
G02X264402Y1702922I-302J0D01*
G01X260702D01*
G02X260400Y1703224I0J302D01*
G01Y1705629D01*
G02X260386Y1705866I2002J237D01*
G02X260400Y1706103I2016J0D01*
G01Y1710353D01*
G02X260386Y1710590I2002J237D01*
G02X260400Y1710827I2016J0D01*
G01Y1713230D01*
G02X260702Y1713532I302J0D01*
G37*
G36*
G01X276450D02*
X280150D01*
G02X280452Y1713230I0J-302D01*
G01Y1703224D01*
G02X280150Y1702922I-302J0D01*
G01X276450D01*
G02X276148Y1703224I0J302D01*
G01Y1705629D01*
G02X276134Y1705866I2002J237D01*
G02X276148Y1706103I2016J0D01*
G01Y1710353D01*
G02X276134Y1710590I2002J237D01*
G02X276148Y1710827I2016J0D01*
G01Y1713230D01*
G02X276450Y1713532I302J0D01*
G37*
G36*
G01X560308D02*
X564008D01*
G02X564310Y1713230I0J-302D01*
G01Y1703224D01*
G02X564008Y1702922I-302J0D01*
G01X560308D01*
G02X560006Y1703224I0J302D01*
G01Y1705256D01*
G02X559915Y1705866I2002J610D01*
G02X560638Y1707448I2092J0D01*
G01X560956Y1708097D01*
G03Y1708359I-267J131D01*
G01X560638Y1709008D01*
G02X559915Y1710590I1369J1582D01*
G02X560006Y1711200I2093J0D01*
G01Y1713230D01*
G02X560308Y1713532I302J0D01*
G37*
G36*
G01X576056D02*
X579756D01*
G02X580058Y1713230I0J-302D01*
G01Y1703224D01*
G02X579756Y1702922I-302J0D01*
G01X576056D01*
G02X575754Y1703224I0J302D01*
G01Y1705256D01*
G02X575663Y1705866I2002J610D01*
G02X576386Y1707448I2092J0D01*
G01X576704Y1708097D01*
G03Y1708359I-267J131D01*
G01X576386Y1709008D01*
G02X575663Y1710590I1369J1582D01*
G02X575754Y1711200I2093J0D01*
G01Y1713230D01*
G02X576056Y1713532I302J0D01*
G37*
G36*
G01X591804D02*
X595504D01*
G02X595806Y1713230I0J-302D01*
G01Y1703224D01*
G02X595504Y1702922I-302J0D01*
G01X591804D01*
G02X591502Y1703224I0J302D01*
G01Y1705256D01*
G02X591411Y1705866I2002J610D01*
G02X592134Y1707448I2092J0D01*
G01X592452Y1708097D01*
G03Y1708359I-267J131D01*
G01X592134Y1709008D01*
G02X591411Y1710590I1369J1582D01*
G02X591502Y1711200I2093J0D01*
G01Y1713230D01*
G02X591804Y1713532I302J0D01*
G37*
G36*
G01X607552D02*
X611252D01*
G02X611554Y1713230I0J-302D01*
G01Y1703224D01*
G02X611252Y1702922I-302J0D01*
G01X607552D01*
G02X607250Y1703224I0J302D01*
G01Y1705256D01*
G02X607159Y1705866I2002J610D01*
G02X607882Y1707448I2092J0D01*
G01X608200Y1708097D01*
G03Y1708359I-267J131D01*
G01X607882Y1709008D01*
G02X607159Y1710590I1369J1582D01*
G02X607250Y1711200I2093J0D01*
G01Y1713230D01*
G02X607552Y1713532I302J0D01*
G37*
G36*
G01X1237080D02*
X1240780D01*
G02X1241082Y1713230I0J-302D01*
G01Y1703224D01*
G02X1240780Y1702922I-302J0D01*
G01X1237080D01*
G02X1236778Y1703224I0J302D01*
G01Y1705629D01*
G02X1236764Y1705866I2002J237D01*
G02X1236778Y1706103I2016J0D01*
G01Y1710353D01*
G02X1236764Y1710590I2002J237D01*
G02X1236778Y1710827I2016J0D01*
G01Y1713230D01*
G02X1237080Y1713532I302J0D01*
G37*
G36*
G01X1252828D02*
X1256528D01*
G02X1256830Y1713230I0J-302D01*
G01Y1703224D01*
G02X1256528Y1702922I-302J0D01*
G01X1252828D01*
G02X1252526Y1703224I0J302D01*
G01Y1705629D01*
G02X1252512Y1705866I2002J237D01*
G02X1252526Y1706103I2016J0D01*
G01Y1710353D01*
G02X1252512Y1710590I2002J237D01*
G02X1252526Y1710827I2016J0D01*
G01Y1713230D01*
G02X1252828Y1713532I302J0D01*
G37*
G36*
G01X1268576D02*
X1272276D01*
G02X1272578Y1713230I0J-302D01*
G01Y1703224D01*
G02X1272276Y1702922I-302J0D01*
G01X1268576D01*
G02X1268274Y1703224I0J302D01*
G01Y1705629D01*
G02X1268260Y1705866I2002J237D01*
G02X1268274Y1706103I2016J0D01*
G01Y1710353D01*
G02X1268260Y1710590I2002J237D01*
G02X1268274Y1710827I2016J0D01*
G01Y1713230D01*
G02X1268576Y1713532I302J0D01*
G37*
G36*
G01X1284324D02*
X1288024D01*
G02X1288326Y1713230I0J-302D01*
G01Y1703224D01*
G02X1288024Y1702922I-302J0D01*
G01X1284324D01*
G02X1284022Y1703224I0J302D01*
G01Y1705629D01*
G02X1284008Y1705866I2002J237D01*
G02X1284022Y1706103I2016J0D01*
G01Y1710353D01*
G02X1284008Y1710590I2002J237D01*
G02X1284022Y1710827I2016J0D01*
G01Y1713230D01*
G02X1284324Y1713532I302J0D01*
G37*
G36*
G01X1568182D02*
X1571882D01*
G02X1572184Y1713230I0J-302D01*
G01Y1703224D01*
G02X1571882Y1702922I-302J0D01*
G01X1568182D01*
G02X1567880Y1703224I0J302D01*
G01Y1705256D01*
G02X1567789Y1705866I2002J610D01*
G02X1568512Y1707448I2092J0D01*
G01X1568830Y1708097D01*
G03Y1708359I-267J131D01*
G01X1568512Y1709008D01*
G02X1567789Y1710590I1369J1582D01*
G02X1567880Y1711200I2093J0D01*
G01Y1713230D01*
G02X1568182Y1713532I302J0D01*
G37*
G36*
G01X1583930D02*
X1587630D01*
G02X1587932Y1713230I0J-302D01*
G01Y1703224D01*
G02X1587630Y1702922I-302J0D01*
G01X1583930D01*
G02X1583628Y1703224I0J302D01*
G01Y1705256D01*
G02X1583537Y1705866I2002J610D01*
G02X1584260Y1707448I2092J0D01*
G01X1584578Y1708097D01*
G03Y1708359I-267J131D01*
G01X1584260Y1709008D01*
G02X1583537Y1710590I1369J1582D01*
G02X1583628Y1711200I2093J0D01*
G01Y1713230D01*
G02X1583930Y1713532I302J0D01*
G37*
G36*
G01X1599678D02*
X1603378D01*
G02X1603680Y1713230I0J-302D01*
G01Y1703224D01*
G02X1603378Y1702922I-302J0D01*
G01X1599678D01*
G02X1599376Y1703224I0J302D01*
G01Y1705256D01*
G02X1599285Y1705866I2002J610D01*
G02X1600008Y1707448I2092J0D01*
G01X1600326Y1708097D01*
G03Y1708359I-267J131D01*
G01X1600008Y1709008D01*
G02X1599285Y1710590I1369J1582D01*
G02X1599376Y1711200I2093J0D01*
G01Y1713230D01*
G02X1599678Y1713532I302J0D01*
G37*
G36*
G01X1615426D02*
X1619126D01*
G02X1619428Y1713230I0J-302D01*
G01Y1703224D01*
G02X1619126Y1702922I-302J0D01*
G01X1615426D01*
G02X1615124Y1703224I0J302D01*
G01Y1705256D01*
G02X1615033Y1705866I2002J610D01*
G02X1615756Y1707448I2092J0D01*
G01X1616074Y1708097D01*
G03Y1708359I-267J131D01*
G01X1615756Y1709008D01*
G02X1615033Y1710590I1369J1582D01*
G02X1615124Y1711200I2093J0D01*
G01Y1713230D01*
G02X1615426Y1713532I302J0D01*
G37*
G36*
G01X296135D02*
X299835D01*
G02X300138Y1713230I1J-302D01*
G01Y1703224D01*
G02X299835Y1702922I-303J1D01*
G01X296135D01*
G02X295832Y1703224I-1J302D01*
G01Y1705637D01*
G02X295819Y1705866I2003J229D01*
G02X295832Y1706095I2016J0D01*
G01Y1710361D01*
G02X295819Y1710590I2003J229D01*
G02X295832Y1710819I2016J0D01*
G01Y1713230D01*
G02X296135Y1713532I303J-1D01*
G37*
G36*
G01X311883D02*
X315583D01*
G02X315886Y1713230I1J-302D01*
G01Y1703224D01*
G02X315583Y1702922I-303J1D01*
G01X311883D01*
G02X311580Y1703224I-1J302D01*
G01Y1705637D01*
G02X311567Y1705866I2003J229D01*
G02X311580Y1706095I2016J0D01*
G01Y1710361D01*
G02X311567Y1710590I2003J229D01*
G02X311580Y1710819I2016J0D01*
G01Y1713230D01*
G02X311883Y1713532I303J-1D01*
G37*
G36*
G01X327631D02*
X331331D01*
G02X331634Y1713230I1J-302D01*
G01Y1703224D01*
G02X331331Y1702922I-303J1D01*
G01X327631D01*
G02X327328Y1703224I-1J302D01*
G01Y1705637D01*
G02X327315Y1705866I2003J229D01*
G02X327328Y1706095I2016J0D01*
G01Y1710361D01*
G02X327315Y1710590I2003J229D01*
G02X327328Y1710819I2016J0D01*
G01Y1713230D01*
G02X327631Y1713532I303J-1D01*
G37*
G36*
G01X343379D02*
X347079D01*
G02X347382Y1713230I1J-302D01*
G01Y1703224D01*
G02X347079Y1702922I-303J1D01*
G01X343379D01*
G02X343076Y1703224I-1J302D01*
G01Y1705637D01*
G02X343063Y1705866I2003J229D01*
G02X343076Y1706095I2016J0D01*
G01Y1710361D01*
G02X343063Y1710590I2003J229D01*
G02X343076Y1710819I2016J0D01*
G01Y1713230D01*
G02X343379Y1713532I303J-1D01*
G37*
G36*
G01X493379D02*
X497079D01*
G02X497382Y1713230I1J-302D01*
G01Y1703224D01*
G02X497079Y1702922I-303J1D01*
G01X493379D01*
G02X493076Y1703224I-1J302D01*
G01Y1705259D01*
G02X492986Y1705866I2002J607D01*
G02X493709Y1707448I2092J0D01*
G01X494027Y1708097D01*
G03Y1708359I-267J131D01*
G01X493709Y1709008D01*
G02X492986Y1710590I1369J1582D01*
G02X493076Y1711197I2092J0D01*
G01Y1713230D01*
G02X493379Y1713532I303J-1D01*
G37*
G36*
G01X509127D02*
X512827D01*
G02X513130Y1713230I1J-302D01*
G01Y1703224D01*
G02X512827Y1702922I-303J1D01*
G01X509127D01*
G02X508824Y1703224I-1J302D01*
G01Y1705259D01*
G02X508734Y1705866I2002J607D01*
G02X509457Y1707448I2092J0D01*
G01X509775Y1708097D01*
G03Y1708359I-267J131D01*
G01X509457Y1709008D01*
G02X508734Y1710590I1369J1582D01*
G02X508824Y1711197I2092J0D01*
G01Y1713230D01*
G02X509127Y1713532I303J-1D01*
G37*
G36*
G01X524875D02*
X528575D01*
G02X528878Y1713230I1J-302D01*
G01Y1703224D01*
G02X528575Y1702922I-303J1D01*
G01X524875D01*
G02X524572Y1703224I-1J302D01*
G01Y1705259D01*
G02X524482Y1705866I2002J607D01*
G02X525205Y1707448I2092J0D01*
G01X525523Y1708097D01*
G03Y1708359I-267J131D01*
G01X525205Y1709008D01*
G02X524482Y1710590I1369J1582D01*
G02X524572Y1711197I2092J0D01*
G01Y1713230D01*
G02X524875Y1713532I303J-1D01*
G37*
G36*
G01X540623D02*
X544323D01*
G02X544626Y1713230I1J-302D01*
G01Y1703224D01*
G02X544323Y1702922I-303J1D01*
G01X540623D01*
G02X540320Y1703224I-1J302D01*
G01Y1705259D01*
G02X540230Y1705866I2002J607D01*
G02X540953Y1707448I2092J0D01*
G01X541271Y1708097D01*
G03Y1708359I-267J131D01*
G01X540953Y1709008D01*
G02X540230Y1710590I1369J1582D01*
G02X540320Y1711197I2092J0D01*
G01Y1713230D01*
G02X540623Y1713532I303J-1D01*
G37*
G36*
G01X1304009D02*
X1307709D01*
G02X1308012Y1713230I1J-302D01*
G01Y1703224D01*
G02X1307709Y1702922I-303J1D01*
G01X1304009D01*
G02X1303706Y1703224I-1J302D01*
G01Y1705637D01*
G02X1303693Y1705866I2003J229D01*
G02X1303706Y1706095I2016J0D01*
G01Y1710361D01*
G02X1303693Y1710590I2003J229D01*
G02X1303706Y1710819I2016J0D01*
G01Y1713230D01*
G02X1304009Y1713532I303J-1D01*
G37*
G36*
G01X1319757D02*
X1323457D01*
G02X1323760Y1713230I1J-302D01*
G01Y1703224D01*
G02X1323457Y1702922I-303J1D01*
G01X1319757D01*
G02X1319454Y1703224I-1J302D01*
G01Y1705637D01*
G02X1319441Y1705866I2003J229D01*
G02X1319454Y1706095I2016J0D01*
G01Y1710361D01*
G02X1319441Y1710590I2003J229D01*
G02X1319454Y1710819I2016J0D01*
G01Y1713230D01*
G02X1319757Y1713532I303J-1D01*
G37*
G36*
G01X1335505D02*
X1339205D01*
G02X1339508Y1713230I1J-302D01*
G01Y1703224D01*
G02X1339205Y1702922I-303J1D01*
G01X1335505D01*
G02X1335202Y1703224I-1J302D01*
G01Y1705637D01*
G02X1335189Y1705866I2003J229D01*
G02X1335202Y1706095I2016J0D01*
G01Y1710361D01*
G02X1335189Y1710590I2003J229D01*
G02X1335202Y1710819I2016J0D01*
G01Y1713230D01*
G02X1335505Y1713532I303J-1D01*
G37*
G36*
G01X1351253D02*
X1354953D01*
G02X1355256Y1713230I1J-302D01*
G01Y1703224D01*
G02X1354953Y1702922I-303J1D01*
G01X1351253D01*
G02X1350950Y1703224I-1J302D01*
G01Y1705637D01*
G02X1350937Y1705866I2003J229D01*
G02X1350950Y1706095I2016J0D01*
G01Y1710361D01*
G02X1350937Y1710590I2003J229D01*
G02X1350950Y1710819I2016J0D01*
G01Y1713230D01*
G02X1351253Y1713532I303J-1D01*
G37*
G36*
G01X1501253D02*
X1504953D01*
G02X1505256Y1713230I1J-302D01*
G01Y1703224D01*
G02X1504953Y1702922I-303J1D01*
G01X1501253D01*
G02X1500950Y1703224I-1J302D01*
G01Y1705259D01*
G02X1500860Y1705866I2002J607D01*
G02X1501583Y1707448I2092J0D01*
G01X1501901Y1708097D01*
G03Y1708359I-267J131D01*
G01X1501583Y1709008D01*
G02X1500860Y1710590I1369J1582D01*
G02X1500950Y1711197I2092J0D01*
G01Y1713230D01*
G02X1501253Y1713532I303J-1D01*
G37*
G36*
G01X1517001D02*
X1520701D01*
G02X1521004Y1713230I1J-302D01*
G01Y1703224D01*
G02X1520701Y1702922I-303J1D01*
G01X1517001D01*
G02X1516698Y1703224I-1J302D01*
G01Y1705259D01*
G02X1516608Y1705866I2002J607D01*
G02X1517331Y1707448I2092J0D01*
G01X1517649Y1708097D01*
G03Y1708359I-267J131D01*
G01X1517331Y1709008D01*
G02X1516608Y1710590I1369J1582D01*
G02X1516698Y1711197I2092J0D01*
G01Y1713230D01*
G02X1517001Y1713532I303J-1D01*
G37*
G36*
G01X1532749D02*
X1536449D01*
G02X1536752Y1713230I1J-302D01*
G01Y1703224D01*
G02X1536449Y1702922I-303J1D01*
G01X1532749D01*
G02X1532446Y1703224I-1J302D01*
G01Y1705259D01*
G02X1532356Y1705866I2002J607D01*
G02X1533079Y1707448I2092J0D01*
G01X1533397Y1708097D01*
G03Y1708359I-267J131D01*
G01X1533079Y1709008D01*
G02X1532356Y1710590I1369J1582D01*
G02X1532446Y1711197I2092J0D01*
G01Y1713230D01*
G02X1532749Y1713532I303J-1D01*
G37*
G36*
G01X1548497D02*
X1552197D01*
G02X1552500Y1713230I1J-302D01*
G01Y1703224D01*
G02X1552197Y1702922I-303J1D01*
G01X1548497D01*
G02X1548194Y1703224I-1J302D01*
G01Y1705259D01*
G02X1548104Y1705866I2002J607D01*
G02X1548827Y1707448I2092J0D01*
G01X1549145Y1708097D01*
G03Y1708359I-267J131D01*
G01X1548827Y1709008D01*
G02X1548104Y1710590I1369J1582D01*
G02X1548194Y1711197I2092J0D01*
G01Y1713230D01*
G02X1548497Y1713532I303J-1D01*
G37*
G36*
G01X237080Y1717470D02*
X240780D01*
G02X241082Y1717167I-1J-303D01*
G01Y1707161D01*
G02X240780Y1706858I-302J-1D01*
G01X237080D01*
G02X236778Y1707161I1J303D01*
G01Y1709566D01*
G02X236764Y1709803I2002J237D01*
G02X236778Y1710040I2016J0D01*
G01Y1714290D01*
G02X236764Y1714527I2002J237D01*
G02X236778Y1714764I2016J0D01*
G01Y1717167D01*
G02X237080Y1717470I302J1D01*
G37*
G36*
G01X252828D02*
X256528D01*
G02X256830Y1717167I-1J-303D01*
G01Y1707161D01*
G02X256528Y1706858I-302J-1D01*
G01X252828D01*
G02X252526Y1707161I1J303D01*
G01Y1709566D01*
G02X252512Y1709803I2002J237D01*
G02X252526Y1710040I2016J0D01*
G01Y1714290D01*
G02X252512Y1714527I2002J237D01*
G02X252526Y1714764I2016J0D01*
G01Y1717167D01*
G02X252828Y1717470I302J1D01*
G37*
G36*
G01X268576D02*
X272276D01*
G02X272578Y1717167I-1J-303D01*
G01Y1707161D01*
G02X272276Y1706858I-302J-1D01*
G01X268576D01*
G02X268274Y1707161I1J303D01*
G01Y1709566D01*
G02X268260Y1709803I2002J237D01*
G02X268274Y1710040I2016J0D01*
G01Y1714290D01*
G02X268260Y1714527I2002J237D01*
G02X268274Y1714764I2016J0D01*
G01Y1717167D01*
G02X268576Y1717470I302J1D01*
G37*
G36*
G01X284324D02*
X288024D01*
G02X288326Y1717167I-1J-303D01*
G01Y1707161D01*
G02X288024Y1706858I-302J-1D01*
G01X284324D01*
G02X284022Y1707161I1J303D01*
G01Y1709566D01*
G02X284008Y1709803I2002J237D01*
G02X284022Y1710040I2016J0D01*
G01Y1714290D01*
G02X284008Y1714527I2002J237D01*
G02X284022Y1714764I2016J0D01*
G01Y1717167D01*
G02X284324Y1717470I302J1D01*
G37*
G36*
G01X304009D02*
X307709D01*
G02X308012Y1717167I0J-303D01*
G01Y1707161D01*
G02X307709Y1706858I-303J0D01*
G01X304009D01*
G02X303706Y1707161I0J303D01*
G01Y1709574D01*
G02X303693Y1709803I2003J229D01*
G02X303706Y1710032I2016J0D01*
G01Y1714298D01*
G02X303693Y1714527I2003J229D01*
G02X303706Y1714756I2016J0D01*
G01Y1717167D01*
G02X304009Y1717470I303J0D01*
G37*
G36*
G01X319757D02*
X323457D01*
G02X323760Y1717167I0J-303D01*
G01Y1707161D01*
G02X323457Y1706858I-303J0D01*
G01X319757D01*
G02X319454Y1707161I0J303D01*
G01Y1709574D01*
G02X319441Y1709803I2003J229D01*
G02X319454Y1710032I2016J0D01*
G01Y1714298D01*
G02X319441Y1714527I2003J229D01*
G02X319454Y1714756I2016J0D01*
G01Y1717167D01*
G02X319757Y1717470I303J0D01*
G37*
G36*
G01X335505D02*
X339205D01*
G02X339508Y1717167I0J-303D01*
G01Y1707161D01*
G02X339205Y1706858I-303J0D01*
G01X335505D01*
G02X335202Y1707161I0J303D01*
G01Y1709574D01*
G02X335189Y1709803I2003J229D01*
G02X335202Y1710032I2016J0D01*
G01Y1714298D01*
G02X335189Y1714527I2003J229D01*
G02X335202Y1714756I2016J0D01*
G01Y1717167D01*
G02X335505Y1717470I303J0D01*
G37*
G36*
G01X351253D02*
X354953D01*
G02X355256Y1717167I0J-303D01*
G01Y1707161D01*
G02X354953Y1706858I-303J0D01*
G01X351253D01*
G02X350950Y1707161I0J303D01*
G01Y1709574D01*
G02X350937Y1709803I2003J229D01*
G02X350950Y1710032I2016J0D01*
G01Y1714298D01*
G02X350937Y1714527I2003J229D01*
G02X350950Y1714756I2016J0D01*
G01Y1717167D01*
G02X351253Y1717470I303J0D01*
G37*
G36*
G01X501253D02*
X504953D01*
G02X505256Y1717167I0J-303D01*
G01Y1707161D01*
G02X504953Y1706858I-303J0D01*
G01X501253D01*
G02X500950Y1707161I0J303D01*
G01Y1709196D01*
G02X500860Y1709803I2002J607D01*
G02X501583Y1711385I2092J0D01*
G01X501901Y1712034D01*
G03Y1712296I-267J131D01*
G01X501583Y1712945D01*
G02X500860Y1714527I1369J1582D01*
G02X500950Y1715134I2092J0D01*
G01Y1717167D01*
G02X501253Y1717470I303J0D01*
G37*
G36*
G01X517001D02*
X520701D01*
G02X521004Y1717167I0J-303D01*
G01Y1707161D01*
G02X520701Y1706858I-303J0D01*
G01X517001D01*
G02X516698Y1707161I0J303D01*
G01Y1709196D01*
G02X516608Y1709803I2002J607D01*
G02X517331Y1711385I2092J0D01*
G01X517649Y1712034D01*
G03Y1712296I-267J131D01*
G01X517331Y1712945D01*
G02X516608Y1714527I1369J1582D01*
G02X516698Y1715134I2092J0D01*
G01Y1717167D01*
G02X517001Y1717470I303J0D01*
G37*
G36*
G01X532749D02*
X536449D01*
G02X536752Y1717167I0J-303D01*
G01Y1707161D01*
G02X536449Y1706858I-303J0D01*
G01X532749D01*
G02X532446Y1707161I0J303D01*
G01Y1709196D01*
G02X532356Y1709803I2002J607D01*
G02X533079Y1711385I2092J0D01*
G01X533397Y1712034D01*
G03Y1712296I-267J131D01*
G01X533079Y1712945D01*
G02X532356Y1714527I1369J1582D01*
G02X532446Y1715134I2092J0D01*
G01Y1717167D01*
G02X532749Y1717470I303J0D01*
G37*
G36*
G01X548497D02*
X552197D01*
G02X552500Y1717167I0J-303D01*
G01Y1707161D01*
G02X552197Y1706858I-303J0D01*
G01X548497D01*
G02X548194Y1707161I0J303D01*
G01Y1709196D01*
G02X548104Y1709803I2002J607D01*
G02X548827Y1711385I2092J0D01*
G01X549145Y1712034D01*
G03Y1712296I-267J131D01*
G01X548827Y1712945D01*
G02X548104Y1714527I1369J1582D01*
G02X548194Y1715134I2092J0D01*
G01Y1717167D01*
G02X548497Y1717470I303J0D01*
G37*
G36*
G01X568182D02*
X571882D01*
G02X572184Y1717167I-1J-303D01*
G01Y1707161D01*
G02X571882Y1706858I-302J-1D01*
G01X568182D01*
G02X567880Y1707161I1J303D01*
G01Y1709193D01*
G02X567789Y1709803I2002J610D01*
G02X568512Y1711385I2092J0D01*
G01X568830Y1712034D01*
G03Y1712296I-267J131D01*
G01X568512Y1712945D01*
G02X567789Y1714527I1369J1582D01*
G02X567880Y1715137I2093J0D01*
G01Y1717167D01*
G02X568182Y1717470I302J1D01*
G37*
G36*
G01X583930D02*
X587630D01*
G02X587932Y1717167I-1J-303D01*
G01Y1707161D01*
G02X587630Y1706858I-302J-1D01*
G01X583930D01*
G02X583628Y1707161I1J303D01*
G01Y1709193D01*
G02X583537Y1709803I2002J610D01*
G02X584260Y1711385I2092J0D01*
G01X584578Y1712034D01*
G03Y1712296I-267J131D01*
G01X584260Y1712945D01*
G02X583537Y1714527I1369J1582D01*
G02X583628Y1715137I2093J0D01*
G01Y1717167D01*
G02X583930Y1717470I302J1D01*
G37*
G36*
G01X599678D02*
X603378D01*
G02X603680Y1717167I-1J-303D01*
G01Y1707161D01*
G02X603378Y1706858I-302J-1D01*
G01X599678D01*
G02X599376Y1707161I1J303D01*
G01Y1709193D01*
G02X599285Y1709803I2002J610D01*
G02X600008Y1711385I2092J0D01*
G01X600326Y1712034D01*
G03Y1712296I-267J131D01*
G01X600008Y1712945D01*
G02X599285Y1714527I1369J1582D01*
G02X599376Y1715137I2093J0D01*
G01Y1717167D01*
G02X599678Y1717470I302J1D01*
G37*
G36*
G01X615426D02*
X619126D01*
G02X619428Y1717167I-1J-303D01*
G01Y1707161D01*
G02X619126Y1706858I-302J-1D01*
G01X615426D01*
G02X615124Y1707161I1J303D01*
G01Y1709193D01*
G02X615033Y1709803I2002J610D01*
G02X615756Y1711385I2092J0D01*
G01X616074Y1712034D01*
G03Y1712296I-267J131D01*
G01X615756Y1712945D01*
G02X615033Y1714527I1369J1582D01*
G02X615124Y1715137I2093J0D01*
G01Y1717167D01*
G02X615426Y1717470I302J1D01*
G37*
G36*
G01X1244954D02*
X1248654D01*
G02X1248956Y1717167I-1J-303D01*
G01Y1707161D01*
G02X1248654Y1706858I-302J-1D01*
G01X1244954D01*
G02X1244652Y1707161I1J303D01*
G01Y1709566D01*
G02X1244638Y1709803I2002J237D01*
G02X1244652Y1710040I2016J0D01*
G01Y1714290D01*
G02X1244638Y1714527I2002J237D01*
G02X1244652Y1714764I2016J0D01*
G01Y1717167D01*
G02X1244954Y1717470I302J1D01*
G37*
G36*
G01X1260702D02*
X1264402D01*
G02X1264704Y1717167I-1J-303D01*
G01Y1707161D01*
G02X1264402Y1706858I-302J-1D01*
G01X1260702D01*
G02X1260400Y1707161I1J303D01*
G01Y1709566D01*
G02X1260386Y1709803I2002J237D01*
G02X1260400Y1710040I2016J0D01*
G01Y1714290D01*
G02X1260386Y1714527I2002J237D01*
G02X1260400Y1714764I2016J0D01*
G01Y1717167D01*
G02X1260702Y1717470I302J1D01*
G37*
G36*
G01X1276450D02*
X1280150D01*
G02X1280452Y1717167I-1J-303D01*
G01Y1707161D01*
G02X1280150Y1706858I-302J-1D01*
G01X1276450D01*
G02X1276148Y1707161I1J303D01*
G01Y1709566D01*
G02X1276134Y1709803I2002J237D01*
G02X1276148Y1710040I2016J0D01*
G01Y1714290D01*
G02X1276134Y1714527I2002J237D01*
G02X1276148Y1714764I2016J0D01*
G01Y1717167D01*
G02X1276450Y1717470I302J1D01*
G37*
G36*
G01X1292198D02*
X1295898D01*
G02X1296200Y1717167I-1J-303D01*
G01Y1707161D01*
G02X1295898Y1706858I-302J-1D01*
G01X1292198D01*
G02X1291896Y1707161I1J303D01*
G01Y1709566D01*
G02X1291882Y1709803I2002J237D01*
G02X1291896Y1710040I2016J0D01*
G01Y1714290D01*
G02X1291882Y1714527I2002J237D01*
G02X1291896Y1714764I2016J0D01*
G01Y1717167D01*
G02X1292198Y1717470I302J1D01*
G37*
G36*
G01X1311883D02*
X1315583D01*
G02X1315886Y1717167I0J-303D01*
G01Y1707161D01*
G02X1315583Y1706858I-303J0D01*
G01X1311883D01*
G02X1311580Y1707161I0J303D01*
G01Y1709574D01*
G02X1311567Y1709803I2003J229D01*
G02X1311580Y1710032I2016J0D01*
G01Y1714298D01*
G02X1311567Y1714527I2003J229D01*
G02X1311580Y1714756I2016J0D01*
G01Y1717167D01*
G02X1311883Y1717470I303J0D01*
G37*
G36*
G01X1327631D02*
X1331331D01*
G02X1331634Y1717167I0J-303D01*
G01Y1707161D01*
G02X1331331Y1706858I-303J0D01*
G01X1327631D01*
G02X1327328Y1707161I0J303D01*
G01Y1709574D01*
G02X1327315Y1709803I2003J229D01*
G02X1327328Y1710032I2016J0D01*
G01Y1714298D01*
G02X1327315Y1714527I2003J229D01*
G02X1327328Y1714756I2016J0D01*
G01Y1717167D01*
G02X1327631Y1717470I303J0D01*
G37*
G36*
G01X1343379D02*
X1347079D01*
G02X1347382Y1717167I0J-303D01*
G01Y1707161D01*
G02X1347079Y1706858I-303J0D01*
G01X1343379D01*
G02X1343076Y1707161I0J303D01*
G01Y1709574D01*
G02X1343063Y1709803I2003J229D01*
G02X1343076Y1710032I2016J0D01*
G01Y1714298D01*
G02X1343063Y1714527I2003J229D01*
G02X1343076Y1714756I2016J0D01*
G01Y1717167D01*
G02X1343379Y1717470I303J0D01*
G37*
G36*
G01X1359127D02*
X1362827D01*
G02X1363130Y1717167I0J-303D01*
G01Y1707161D01*
G02X1362827Y1706858I-303J0D01*
G01X1359127D01*
G02X1358824Y1707161I0J303D01*
G01Y1709574D01*
G02X1358811Y1709803I2003J229D01*
G02X1358824Y1710032I2016J0D01*
G01Y1714298D01*
G02X1358811Y1714527I2003J229D01*
G02X1358824Y1714756I2016J0D01*
G01Y1717167D01*
G02X1359127Y1717470I303J0D01*
G37*
G36*
G01X1509127D02*
X1512827D01*
G02X1513130Y1717167I0J-303D01*
G01Y1707161D01*
G02X1512827Y1706858I-303J0D01*
G01X1509127D01*
G02X1508824Y1707161I0J303D01*
G01Y1709196D01*
G02X1508734Y1709803I2002J607D01*
G02X1509457Y1711385I2092J0D01*
G01X1509775Y1712034D01*
G03Y1712296I-267J131D01*
G01X1509457Y1712945D01*
G02X1508734Y1714527I1369J1582D01*
G02X1508824Y1715134I2092J0D01*
G01Y1717167D01*
G02X1509127Y1717470I303J0D01*
G37*
G36*
G01X1524875D02*
X1528575D01*
G02X1528878Y1717167I0J-303D01*
G01Y1707161D01*
G02X1528575Y1706858I-303J0D01*
G01X1524875D01*
G02X1524572Y1707161I0J303D01*
G01Y1709196D01*
G02X1524482Y1709803I2002J607D01*
G02X1525205Y1711385I2092J0D01*
G01X1525523Y1712034D01*
G03Y1712296I-267J131D01*
G01X1525205Y1712945D01*
G02X1524482Y1714527I1369J1582D01*
G02X1524572Y1715134I2092J0D01*
G01Y1717167D01*
G02X1524875Y1717470I303J0D01*
G37*
G36*
G01X1540623D02*
X1544323D01*
G02X1544626Y1717167I0J-303D01*
G01Y1707161D01*
G02X1544323Y1706858I-303J0D01*
G01X1540623D01*
G02X1540320Y1707161I0J303D01*
G01Y1709196D01*
G02X1540230Y1709803I2002J607D01*
G02X1540953Y1711385I2092J0D01*
G01X1541271Y1712034D01*
G03Y1712296I-267J131D01*
G01X1540953Y1712945D01*
G02X1540230Y1714527I1369J1582D01*
G02X1540320Y1715134I2092J0D01*
G01Y1717167D01*
G02X1540623Y1717470I303J0D01*
G37*
G36*
G01X1556371D02*
X1560071D01*
G02X1560374Y1717167I0J-303D01*
G01Y1707161D01*
G02X1560071Y1706858I-303J0D01*
G01X1556371D01*
G02X1556068Y1707161I0J303D01*
G01Y1709196D01*
G02X1555978Y1709803I2002J607D01*
G02X1556701Y1711385I2092J0D01*
G01X1557019Y1712034D01*
G03Y1712296I-267J131D01*
G01X1556701Y1712945D01*
G02X1555978Y1714527I1369J1582D01*
G02X1556068Y1715134I2092J0D01*
G01Y1717167D01*
G02X1556371Y1717470I303J0D01*
G37*
G36*
G01X1576056D02*
X1579756D01*
G02X1580058Y1717167I-1J-303D01*
G01Y1707161D01*
G02X1579756Y1706858I-302J-1D01*
G01X1576056D01*
G02X1575754Y1707161I1J303D01*
G01Y1709193D01*
G02X1575663Y1709803I2002J610D01*
G02X1576386Y1711385I2092J0D01*
G01X1576704Y1712034D01*
G03Y1712296I-267J131D01*
G01X1576386Y1712945D01*
G02X1575663Y1714527I1369J1582D01*
G02X1575754Y1715137I2093J0D01*
G01Y1717167D01*
G02X1576056Y1717470I302J1D01*
G37*
G36*
G01X1591804D02*
X1595504D01*
G02X1595806Y1717167I-1J-303D01*
G01Y1707161D01*
G02X1595504Y1706858I-302J-1D01*
G01X1591804D01*
G02X1591502Y1707161I1J303D01*
G01Y1709193D01*
G02X1591411Y1709803I2002J610D01*
G02X1592134Y1711385I2092J0D01*
G01X1592452Y1712034D01*
G03Y1712296I-267J131D01*
G01X1592134Y1712945D01*
G02X1591411Y1714527I1369J1582D01*
G02X1591502Y1715137I2093J0D01*
G01Y1717167D01*
G02X1591804Y1717470I302J1D01*
G37*
G36*
G01X1607552D02*
X1611252D01*
G02X1611554Y1717167I-1J-303D01*
G01Y1707161D01*
G02X1611252Y1706858I-302J-1D01*
G01X1607552D01*
G02X1607250Y1707161I1J303D01*
G01Y1709193D01*
G02X1607159Y1709803I2002J610D01*
G02X1607882Y1711385I2092J0D01*
G01X1608200Y1712034D01*
G03Y1712296I-267J131D01*
G01X1607882Y1712945D01*
G02X1607159Y1714527I1369J1582D01*
G02X1607250Y1715137I2093J0D01*
G01Y1717167D01*
G02X1607552Y1717470I302J1D01*
G37*
G36*
G01X1623300D02*
X1627000D01*
G02X1627302Y1717167I-1J-303D01*
G01Y1707161D01*
G02X1627000Y1706858I-302J-1D01*
G01X1623300D01*
G02X1622998Y1707161I1J303D01*
G01Y1709193D01*
G02X1622907Y1709803I2002J610D01*
G02X1623630Y1711385I2092J0D01*
G01X1623948Y1712034D01*
G03Y1712296I-267J131D01*
G01X1623630Y1712945D01*
G02X1622907Y1714527I1369J1582D01*
G02X1622998Y1715137I2093J0D01*
G01Y1717167D01*
G02X1623300Y1717470I302J1D01*
G37*
G36*
G01X229206Y1727706D02*
X232906D01*
G02X233208Y1727404I0J-302D01*
G01Y1717398D01*
G02X232906Y1717096I-302J0D01*
G01X229206D01*
G02X228904Y1717398I0J302D01*
G01Y1719429D01*
G02X228813Y1720039I2002J610D01*
G02X229535Y1721621I2094J0D01*
G01X229854Y1722271D01*
G03Y1722533I-267J131D01*
G01X229537Y1723180D01*
G02X228813Y1724763I1369J1583D01*
G02X228904Y1725373I2093J0D01*
G01Y1727404D01*
G02X229206Y1727706I302J0D01*
G37*
G36*
G01X244954D02*
X248654D01*
G02X248956Y1727404I0J-302D01*
G01Y1717398D01*
G02X248654Y1717096I-302J0D01*
G01X244954D01*
G02X244652Y1717398I0J302D01*
G01Y1719429D01*
G02X244561Y1720039I2002J610D01*
G02X245283Y1721621I2094J0D01*
G01X245602Y1722271D01*
G03Y1722533I-267J131D01*
G01X245285Y1723180D01*
G02X244561Y1724763I1369J1583D01*
G02X244652Y1725373I2093J0D01*
G01Y1727404D01*
G02X244954Y1727706I302J0D01*
G37*
G36*
G01X260702D02*
X264402D01*
G02X264704Y1727404I0J-302D01*
G01Y1717398D01*
G02X264402Y1717096I-302J0D01*
G01X260702D01*
G02X260400Y1717398I0J302D01*
G01Y1719429D01*
G02X260309Y1720039I2002J610D01*
G02X261031Y1721621I2094J0D01*
G01X261350Y1722271D01*
G03Y1722533I-267J131D01*
G01X261033Y1723180D01*
G02X260309Y1724763I1369J1583D01*
G02X260400Y1725373I2093J0D01*
G01Y1727404D01*
G02X260702Y1727706I302J0D01*
G37*
G36*
G01X276450D02*
X280150D01*
G02X280452Y1727404I0J-302D01*
G01Y1717398D01*
G02X280150Y1717096I-302J0D01*
G01X276450D01*
G02X276148Y1717398I0J302D01*
G01Y1719429D01*
G02X276057Y1720039I2002J610D01*
G02X276779Y1721621I2094J0D01*
G01X277098Y1722271D01*
G03Y1722533I-267J131D01*
G01X276781Y1723180D01*
G02X276057Y1724763I1369J1583D01*
G02X276148Y1725373I2093J0D01*
G01Y1727404D01*
G02X276450Y1727706I302J0D01*
G37*
G36*
G01X560308D02*
X564008D01*
G02X564310Y1727404I0J-302D01*
G01Y1717398D01*
G02X564008Y1717096I-302J0D01*
G01X560308D01*
G02X560006Y1717398I0J302D01*
G01Y1719802D01*
G02X559992Y1720039I2002J237D01*
G02X560006Y1720276I2016J0D01*
G01Y1724526D01*
G02X559992Y1724763I2002J237D01*
G02X560006Y1725000I2016J0D01*
G01Y1727404D01*
G02X560308Y1727706I302J0D01*
G37*
G36*
G01X576056D02*
X579756D01*
G02X580058Y1727404I0J-302D01*
G01Y1717398D01*
G02X579756Y1717096I-302J0D01*
G01X576056D01*
G02X575754Y1717398I0J302D01*
G01Y1719802D01*
G02X575740Y1720039I2002J237D01*
G02X575754Y1720276I2016J0D01*
G01Y1724526D01*
G02X575740Y1724763I2002J237D01*
G02X575754Y1725000I2016J0D01*
G01Y1727404D01*
G02X576056Y1727706I302J0D01*
G37*
G36*
G01X591804D02*
X595504D01*
G02X595806Y1727404I0J-302D01*
G01Y1717398D01*
G02X595504Y1717096I-302J0D01*
G01X591804D01*
G02X591502Y1717398I0J302D01*
G01Y1719802D01*
G02X591488Y1720039I2002J237D01*
G02X591502Y1720276I2016J0D01*
G01Y1724526D01*
G02X591488Y1724763I2002J237D01*
G02X591502Y1725000I2016J0D01*
G01Y1727404D01*
G02X591804Y1727706I302J0D01*
G37*
G36*
G01X607552D02*
X611252D01*
G02X611554Y1727404I0J-302D01*
G01Y1717398D01*
G02X611252Y1717096I-302J0D01*
G01X607552D01*
G02X607250Y1717398I0J302D01*
G01Y1719802D01*
G02X607236Y1720039I2002J237D01*
G02X607250Y1720276I2016J0D01*
G01Y1724526D01*
G02X607236Y1724763I2002J237D01*
G02X607250Y1725000I2016J0D01*
G01Y1727404D01*
G02X607552Y1727706I302J0D01*
G37*
G36*
G01X1237080D02*
X1240780D01*
G02X1241082Y1727404I0J-302D01*
G01Y1717398D01*
G02X1240780Y1717096I-302J0D01*
G01X1237080D01*
G02X1236778Y1717398I0J302D01*
G01Y1719429D01*
G02X1236687Y1720039I2002J610D01*
G02X1237409Y1721621I2094J0D01*
G01X1237728Y1722271D01*
G03Y1722533I-267J131D01*
G01X1237411Y1723180D01*
G02X1236687Y1724763I1369J1583D01*
G02X1236778Y1725373I2093J0D01*
G01Y1727404D01*
G02X1237080Y1727706I302J0D01*
G37*
G36*
G01X1252828D02*
X1256528D01*
G02X1256830Y1727404I0J-302D01*
G01Y1717398D01*
G02X1256528Y1717096I-302J0D01*
G01X1252828D01*
G02X1252526Y1717398I0J302D01*
G01Y1719429D01*
G02X1252435Y1720039I2002J610D01*
G02X1253157Y1721621I2094J0D01*
G01X1253476Y1722271D01*
G03Y1722533I-267J131D01*
G01X1253159Y1723180D01*
G02X1252435Y1724763I1369J1583D01*
G02X1252526Y1725373I2093J0D01*
G01Y1727404D01*
G02X1252828Y1727706I302J0D01*
G37*
G36*
G01X1268576D02*
X1272276D01*
G02X1272578Y1727404I0J-302D01*
G01Y1717398D01*
G02X1272276Y1717096I-302J0D01*
G01X1268576D01*
G02X1268274Y1717398I0J302D01*
G01Y1719429D01*
G02X1268183Y1720039I2002J610D01*
G02X1268905Y1721621I2094J0D01*
G01X1269224Y1722271D01*
G03Y1722533I-267J131D01*
G01X1268907Y1723180D01*
G02X1268183Y1724763I1369J1583D01*
G02X1268274Y1725373I2093J0D01*
G01Y1727404D01*
G02X1268576Y1727706I302J0D01*
G37*
G36*
G01X1284324D02*
X1288024D01*
G02X1288326Y1727404I0J-302D01*
G01Y1717398D01*
G02X1288024Y1717096I-302J0D01*
G01X1284324D01*
G02X1284022Y1717398I0J302D01*
G01Y1719429D01*
G02X1283931Y1720039I2002J610D01*
G02X1284653Y1721621I2094J0D01*
G01X1284972Y1722271D01*
G03Y1722533I-267J131D01*
G01X1284655Y1723180D01*
G02X1283931Y1724763I1369J1583D01*
G02X1284022Y1725373I2093J0D01*
G01Y1727404D01*
G02X1284324Y1727706I302J0D01*
G37*
G36*
G01X1568182D02*
X1571882D01*
G02X1572184Y1727404I0J-302D01*
G01Y1717398D01*
G02X1571882Y1717096I-302J0D01*
G01X1568182D01*
G02X1567880Y1717398I0J302D01*
G01Y1719802D01*
G02X1567866Y1720039I2002J237D01*
G02X1567880Y1720276I2016J0D01*
G01Y1724526D01*
G02X1567866Y1724763I2002J237D01*
G02X1567880Y1725000I2016J0D01*
G01Y1727404D01*
G02X1568182Y1727706I302J0D01*
G37*
G36*
G01X1583930D02*
X1587630D01*
G02X1587932Y1727404I0J-302D01*
G01Y1717398D01*
G02X1587630Y1717096I-302J0D01*
G01X1583930D01*
G02X1583628Y1717398I0J302D01*
G01Y1719802D01*
G02X1583614Y1720039I2002J237D01*
G02X1583628Y1720276I2016J0D01*
G01Y1724526D01*
G02X1583614Y1724763I2002J237D01*
G02X1583628Y1725000I2016J0D01*
G01Y1727404D01*
G02X1583930Y1727706I302J0D01*
G37*
G36*
G01X1599678D02*
X1603378D01*
G02X1603680Y1727404I0J-302D01*
G01Y1717398D01*
G02X1603378Y1717096I-302J0D01*
G01X1599678D01*
G02X1599376Y1717398I0J302D01*
G01Y1719802D01*
G02X1599362Y1720039I2002J237D01*
G02X1599376Y1720276I2016J0D01*
G01Y1724526D01*
G02X1599362Y1724763I2002J237D01*
G02X1599376Y1725000I2016J0D01*
G01Y1727404D01*
G02X1599678Y1727706I302J0D01*
G37*
G36*
G01X1615426D02*
X1619126D01*
G02X1619428Y1727404I0J-302D01*
G01Y1717398D01*
G02X1619126Y1717096I-302J0D01*
G01X1615426D01*
G02X1615124Y1717398I0J302D01*
G01Y1719802D01*
G02X1615110Y1720039I2002J237D01*
G02X1615124Y1720276I2016J0D01*
G01Y1724526D01*
G02X1615110Y1724763I2002J237D01*
G02X1615124Y1725000I2016J0D01*
G01Y1727404D01*
G02X1615426Y1727706I302J0D01*
G37*
G36*
G01X296135D02*
X299835D01*
G02X300138Y1727404I1J-302D01*
G01Y1717398D01*
G02X299835Y1717096I-303J1D01*
G01X296135D01*
G02X295832Y1717398I-1J302D01*
G01Y1719432D01*
G02X295742Y1720039I2002J607D01*
G02X296464Y1721621I2094J0D01*
G01X296783Y1722271D01*
G03Y1722533I-267J131D01*
G01X296466Y1723180D01*
G02X295742Y1724763I1369J1583D01*
G02X295832Y1725370I2092J0D01*
G01Y1727404D01*
G02X296135Y1727706I303J-1D01*
G37*
G36*
G01X311883D02*
X315583D01*
G02X315886Y1727404I1J-302D01*
G01Y1717398D01*
G02X315583Y1717096I-303J1D01*
G01X311883D01*
G02X311580Y1717398I-1J302D01*
G01Y1719432D01*
G02X311490Y1720039I2002J607D01*
G02X312212Y1721621I2094J0D01*
G01X312531Y1722271D01*
G03Y1722533I-267J131D01*
G01X312214Y1723180D01*
G02X311490Y1724763I1369J1583D01*
G02X311580Y1725370I2092J0D01*
G01Y1727404D01*
G02X311883Y1727706I303J-1D01*
G37*
G36*
G01X327631D02*
X331331D01*
G02X331634Y1727404I1J-302D01*
G01Y1717398D01*
G02X331331Y1717096I-303J1D01*
G01X327631D01*
G02X327328Y1717398I-1J302D01*
G01Y1719432D01*
G02X327238Y1720039I2002J607D01*
G02X327960Y1721621I2094J0D01*
G01X328279Y1722271D01*
G03Y1722533I-267J131D01*
G01X327962Y1723180D01*
G02X327238Y1724763I1369J1583D01*
G02X327328Y1725370I2092J0D01*
G01Y1727404D01*
G02X327631Y1727706I303J-1D01*
G37*
G36*
G01X343379D02*
X347079D01*
G02X347382Y1727404I1J-302D01*
G01Y1717398D01*
G02X347079Y1717096I-303J1D01*
G01X343379D01*
G02X343076Y1717398I-1J302D01*
G01Y1719432D01*
G02X342986Y1720039I2002J607D01*
G02X343708Y1721621I2094J0D01*
G01X344027Y1722271D01*
G03Y1722533I-267J131D01*
G01X343710Y1723180D01*
G02X342986Y1724763I1369J1583D01*
G02X343076Y1725370I2092J0D01*
G01Y1727404D01*
G02X343379Y1727706I303J-1D01*
G37*
G36*
G01X493379D02*
X497079D01*
G02X497382Y1727404I1J-302D01*
G01Y1717398D01*
G02X497079Y1717096I-303J1D01*
G01X493379D01*
G02X493076Y1717398I-1J302D01*
G01Y1719810D01*
G02X493063Y1720039I2003J229D01*
G02X493076Y1720268I2016J0D01*
G01Y1724534D01*
G02X493063Y1724763I2003J229D01*
G02X493076Y1724992I2016J0D01*
G01Y1727404D01*
G02X493379Y1727706I303J-1D01*
G37*
G36*
G01X509127D02*
X512827D01*
G02X513130Y1727404I1J-302D01*
G01Y1717398D01*
G02X512827Y1717096I-303J1D01*
G01X509127D01*
G02X508824Y1717398I-1J302D01*
G01Y1719810D01*
G02X508811Y1720039I2003J229D01*
G02X508824Y1720268I2016J0D01*
G01Y1724534D01*
G02X508811Y1724763I2003J229D01*
G02X508824Y1724992I2016J0D01*
G01Y1727404D01*
G02X509127Y1727706I303J-1D01*
G37*
G36*
G01X524875D02*
X528575D01*
G02X528878Y1727404I1J-302D01*
G01Y1717398D01*
G02X528575Y1717096I-303J1D01*
G01X524875D01*
G02X524572Y1717398I-1J302D01*
G01Y1719810D01*
G02X524559Y1720039I2003J229D01*
G02X524572Y1720268I2016J0D01*
G01Y1724534D01*
G02X524559Y1724763I2003J229D01*
G02X524572Y1724992I2016J0D01*
G01Y1727404D01*
G02X524875Y1727706I303J-1D01*
G37*
G36*
G01X540623D02*
X544323D01*
G02X544626Y1727404I1J-302D01*
G01Y1717398D01*
G02X544323Y1717096I-303J1D01*
G01X540623D01*
G02X540320Y1717398I-1J302D01*
G01Y1719810D01*
G02X540307Y1720039I2003J229D01*
G02X540320Y1720268I2016J0D01*
G01Y1724534D01*
G02X540307Y1724763I2003J229D01*
G02X540320Y1724992I2016J0D01*
G01Y1727404D01*
G02X540623Y1727706I303J-1D01*
G37*
G36*
G01X1304009D02*
X1307709D01*
G02X1308012Y1727404I1J-302D01*
G01Y1717398D01*
G02X1307709Y1717096I-303J1D01*
G01X1304009D01*
G02X1303706Y1717398I-1J302D01*
G01Y1719432D01*
G02X1303616Y1720039I2002J607D01*
G02X1304338Y1721621I2094J0D01*
G01X1304657Y1722271D01*
G03Y1722533I-267J131D01*
G01X1304340Y1723180D01*
G02X1303616Y1724763I1369J1583D01*
G02X1303706Y1725370I2092J0D01*
G01Y1727404D01*
G02X1304009Y1727706I303J-1D01*
G37*
G36*
G01X1319757D02*
X1323457D01*
G02X1323760Y1727404I1J-302D01*
G01Y1717398D01*
G02X1323457Y1717096I-303J1D01*
G01X1319757D01*
G02X1319454Y1717398I-1J302D01*
G01Y1719432D01*
G02X1319364Y1720039I2002J607D01*
G02X1320086Y1721621I2094J0D01*
G01X1320405Y1722271D01*
G03Y1722533I-267J131D01*
G01X1320088Y1723180D01*
G02X1319364Y1724763I1369J1583D01*
G02X1319454Y1725370I2092J0D01*
G01Y1727404D01*
G02X1319757Y1727706I303J-1D01*
G37*
G36*
G01X1335505D02*
X1339205D01*
G02X1339508Y1727404I1J-302D01*
G01Y1717398D01*
G02X1339205Y1717096I-303J1D01*
G01X1335505D01*
G02X1335202Y1717398I-1J302D01*
G01Y1719432D01*
G02X1335112Y1720039I2002J607D01*
G02X1335834Y1721621I2094J0D01*
G01X1336153Y1722271D01*
G03Y1722533I-267J131D01*
G01X1335836Y1723180D01*
G02X1335112Y1724763I1369J1583D01*
G02X1335202Y1725370I2092J0D01*
G01Y1727404D01*
G02X1335505Y1727706I303J-1D01*
G37*
G36*
G01X1351253D02*
X1354953D01*
G02X1355256Y1727404I1J-302D01*
G01Y1717398D01*
G02X1354953Y1717096I-303J1D01*
G01X1351253D01*
G02X1350950Y1717398I-1J302D01*
G01Y1719432D01*
G02X1350860Y1720039I2002J607D01*
G02X1351582Y1721621I2094J0D01*
G01X1351901Y1722271D01*
G03Y1722533I-267J131D01*
G01X1351584Y1723180D01*
G02X1350860Y1724763I1369J1583D01*
G02X1350950Y1725370I2092J0D01*
G01Y1727404D01*
G02X1351253Y1727706I303J-1D01*
G37*
G36*
G01X1501253D02*
X1504953D01*
G02X1505256Y1727404I1J-302D01*
G01Y1717398D01*
G02X1504953Y1717096I-303J1D01*
G01X1501253D01*
G02X1500950Y1717398I-1J302D01*
G01Y1719810D01*
G02X1500937Y1720039I2003J229D01*
G02X1500950Y1720268I2016J0D01*
G01Y1724534D01*
G02X1500937Y1724763I2003J229D01*
G02X1500950Y1724992I2016J0D01*
G01Y1727404D01*
G02X1501253Y1727706I303J-1D01*
G37*
G36*
G01X1517001D02*
X1520701D01*
G02X1521004Y1727404I1J-302D01*
G01Y1717398D01*
G02X1520701Y1717096I-303J1D01*
G01X1517001D01*
G02X1516698Y1717398I-1J302D01*
G01Y1719810D01*
G02X1516685Y1720039I2003J229D01*
G02X1516698Y1720268I2016J0D01*
G01Y1724534D01*
G02X1516685Y1724763I2003J229D01*
G02X1516698Y1724992I2016J0D01*
G01Y1727404D01*
G02X1517001Y1727706I303J-1D01*
G37*
G36*
G01X1532749D02*
X1536449D01*
G02X1536752Y1727404I1J-302D01*
G01Y1717398D01*
G02X1536449Y1717096I-303J1D01*
G01X1532749D01*
G02X1532446Y1717398I-1J302D01*
G01Y1719810D01*
G02X1532433Y1720039I2003J229D01*
G02X1532446Y1720268I2016J0D01*
G01Y1724534D01*
G02X1532433Y1724763I2003J229D01*
G02X1532446Y1724992I2016J0D01*
G01Y1727404D01*
G02X1532749Y1727706I303J-1D01*
G37*
G36*
G01X1548497D02*
X1552197D01*
G02X1552500Y1727404I1J-302D01*
G01Y1717398D01*
G02X1552197Y1717096I-303J1D01*
G01X1548497D01*
G02X1548194Y1717398I-1J302D01*
G01Y1719810D01*
G02X1548181Y1720039I2003J229D01*
G02X1548194Y1720268I2016J0D01*
G01Y1724534D01*
G02X1548181Y1724763I2003J229D01*
G02X1548194Y1724992I2016J0D01*
G01Y1727404D01*
G02X1548497Y1727706I303J-1D01*
G37*
G36*
G01X237080Y1731644D02*
X240780D01*
G02X241082Y1731341I-1J-303D01*
G01Y1721335D01*
G02X240780Y1721032I-302J-1D01*
G01X237080D01*
G02X236778Y1721335I1J303D01*
G01Y1723366D01*
G02X236687Y1723976I2002J610D01*
G02X237409Y1725558I2094J0D01*
G01X237728Y1726208D01*
G03Y1726470I-267J131D01*
G01X237411Y1727117D01*
G02X236687Y1728700I1369J1583D01*
G02X236778Y1729310I2093J0D01*
G01Y1731341D01*
G02X237080Y1731644I302J1D01*
G37*
G36*
G01X252828D02*
X256528D01*
G02X256830Y1731341I-1J-303D01*
G01Y1721335D01*
G02X256528Y1721032I-302J-1D01*
G01X252828D01*
G02X252526Y1721335I1J303D01*
G01Y1723366D01*
G02X252435Y1723976I2002J610D01*
G02X253157Y1725558I2094J0D01*
G01X253476Y1726208D01*
G03Y1726470I-267J131D01*
G01X253159Y1727117D01*
G02X252435Y1728700I1369J1583D01*
G02X252526Y1729310I2093J0D01*
G01Y1731341D01*
G02X252828Y1731644I302J1D01*
G37*
G36*
G01X268576D02*
X272276D01*
G02X272578Y1731341I-1J-303D01*
G01Y1721335D01*
G02X272276Y1721032I-302J-1D01*
G01X268576D01*
G02X268274Y1721335I1J303D01*
G01Y1723366D01*
G02X268183Y1723976I2002J610D01*
G02X268905Y1725558I2094J0D01*
G01X269224Y1726208D01*
G03Y1726470I-267J131D01*
G01X268907Y1727117D01*
G02X268183Y1728700I1369J1583D01*
G02X268274Y1729310I2093J0D01*
G01Y1731341D01*
G02X268576Y1731644I302J1D01*
G37*
G36*
G01X284324D02*
X288024D01*
G02X288326Y1731341I-1J-303D01*
G01Y1721335D01*
G02X288024Y1721032I-302J-1D01*
G01X284324D01*
G02X284022Y1721335I1J303D01*
G01Y1723366D01*
G02X283931Y1723976I2002J610D01*
G02X284653Y1725558I2094J0D01*
G01X284972Y1726208D01*
G03Y1726470I-267J131D01*
G01X284655Y1727117D01*
G02X283931Y1728700I1369J1583D01*
G02X284022Y1729310I2093J0D01*
G01Y1731341D01*
G02X284324Y1731644I302J1D01*
G37*
G36*
G01X304009D02*
X307709D01*
G02X308012Y1731341I0J-303D01*
G01Y1721335D01*
G02X307709Y1721032I-303J0D01*
G01X304009D01*
G02X303706Y1721335I0J303D01*
G01Y1723369D01*
G02X303616Y1723976I2002J607D01*
G02X304338Y1725558I2094J0D01*
G01X304657Y1726208D01*
G03Y1726470I-267J131D01*
G01X304340Y1727117D01*
G02X303616Y1728700I1369J1583D01*
G02X303706Y1729307I2092J0D01*
G01Y1731341D01*
G02X304009Y1731644I303J0D01*
G37*
G36*
G01X319757D02*
X323457D01*
G02X323760Y1731341I0J-303D01*
G01Y1721335D01*
G02X323457Y1721032I-303J0D01*
G01X319757D01*
G02X319454Y1721335I0J303D01*
G01Y1723369D01*
G02X319364Y1723976I2002J607D01*
G02X320086Y1725558I2094J0D01*
G01X320405Y1726208D01*
G03Y1726470I-267J131D01*
G01X320088Y1727117D01*
G02X319364Y1728700I1369J1583D01*
G02X319454Y1729307I2092J0D01*
G01Y1731341D01*
G02X319757Y1731644I303J0D01*
G37*
G36*
G01X335505D02*
X339205D01*
G02X339508Y1731341I0J-303D01*
G01Y1721335D01*
G02X339205Y1721032I-303J0D01*
G01X335505D01*
G02X335202Y1721335I0J303D01*
G01Y1723369D01*
G02X335112Y1723976I2002J607D01*
G02X335834Y1725558I2094J0D01*
G01X336153Y1726208D01*
G03Y1726470I-267J131D01*
G01X335836Y1727117D01*
G02X335112Y1728700I1369J1583D01*
G02X335202Y1729307I2092J0D01*
G01Y1731341D01*
G02X335505Y1731644I303J0D01*
G37*
G36*
G01X351253D02*
X354953D01*
G02X355256Y1731341I0J-303D01*
G01Y1721335D01*
G02X354953Y1721032I-303J0D01*
G01X351253D01*
G02X350950Y1721335I0J303D01*
G01Y1723369D01*
G02X350860Y1723976I2002J607D01*
G02X351582Y1725558I2094J0D01*
G01X351901Y1726208D01*
G03Y1726470I-267J131D01*
G01X351584Y1727117D01*
G02X350860Y1728700I1369J1583D01*
G02X350950Y1729307I2092J0D01*
G01Y1731341D01*
G02X351253Y1731644I303J0D01*
G37*
G36*
G01X501253D02*
X504953D01*
G02X505256Y1731341I0J-303D01*
G01Y1721335D01*
G02X504953Y1721032I-303J0D01*
G01X501253D01*
G02X500950Y1721335I0J303D01*
G01Y1723747D01*
G02X500937Y1723976I2003J229D01*
G02X500950Y1724205I2016J0D01*
G01Y1728471D01*
G02X500937Y1728700I2003J229D01*
G02X500950Y1728929I2016J0D01*
G01Y1731341D01*
G02X501253Y1731644I303J0D01*
G37*
G36*
G01X517001D02*
X520701D01*
G02X521004Y1731341I0J-303D01*
G01Y1721335D01*
G02X520701Y1721032I-303J0D01*
G01X517001D01*
G02X516698Y1721335I0J303D01*
G01Y1723747D01*
G02X516685Y1723976I2003J229D01*
G02X516698Y1724205I2016J0D01*
G01Y1728471D01*
G02X516685Y1728700I2003J229D01*
G02X516698Y1728929I2016J0D01*
G01Y1731341D01*
G02X517001Y1731644I303J0D01*
G37*
G36*
G01X532749D02*
X536449D01*
G02X536752Y1731341I0J-303D01*
G01Y1721335D01*
G02X536449Y1721032I-303J0D01*
G01X532749D01*
G02X532446Y1721335I0J303D01*
G01Y1723747D01*
G02X532433Y1723976I2003J229D01*
G02X532446Y1724205I2016J0D01*
G01Y1728471D01*
G02X532433Y1728700I2003J229D01*
G02X532446Y1728929I2016J0D01*
G01Y1731341D01*
G02X532749Y1731644I303J0D01*
G37*
G36*
G01X548497D02*
X552197D01*
G02X552500Y1731341I0J-303D01*
G01Y1721335D01*
G02X552197Y1721032I-303J0D01*
G01X548497D01*
G02X548194Y1721335I0J303D01*
G01Y1723747D01*
G02X548181Y1723976I2003J229D01*
G02X548194Y1724205I2016J0D01*
G01Y1728471D01*
G02X548181Y1728700I2003J229D01*
G02X548194Y1728929I2016J0D01*
G01Y1731341D01*
G02X548497Y1731644I303J0D01*
G37*
G36*
G01X568182D02*
X571882D01*
G02X572184Y1731341I-1J-303D01*
G01Y1721335D01*
G02X571882Y1721032I-302J-1D01*
G01X568182D01*
G02X567880Y1721335I1J303D01*
G01Y1723739D01*
G02X567866Y1723976I2002J237D01*
G02X567880Y1724213I2016J0D01*
G01Y1728463D01*
G02X567866Y1728700I2002J237D01*
G02X567880Y1728937I2016J0D01*
G01Y1731341D01*
G02X568182Y1731644I302J1D01*
G37*
G36*
G01X583930D02*
X587630D01*
G02X587932Y1731341I-1J-303D01*
G01Y1721335D01*
G02X587630Y1721032I-302J-1D01*
G01X583930D01*
G02X583628Y1721335I1J303D01*
G01Y1723739D01*
G02X583614Y1723976I2002J237D01*
G02X583628Y1724213I2016J0D01*
G01Y1728463D01*
G02X583614Y1728700I2002J237D01*
G02X583628Y1728937I2016J0D01*
G01Y1731341D01*
G02X583930Y1731644I302J1D01*
G37*
G36*
G01X599678D02*
X603378D01*
G02X603680Y1731341I-1J-303D01*
G01Y1721335D01*
G02X603378Y1721032I-302J-1D01*
G01X599678D01*
G02X599376Y1721335I1J303D01*
G01Y1723739D01*
G02X599362Y1723976I2002J237D01*
G02X599376Y1724213I2016J0D01*
G01Y1728463D01*
G02X599362Y1728700I2002J237D01*
G02X599376Y1728937I2016J0D01*
G01Y1731341D01*
G02X599678Y1731644I302J1D01*
G37*
G36*
G01X615426D02*
X619126D01*
G02X619428Y1731341I-1J-303D01*
G01Y1721335D01*
G02X619126Y1721032I-302J-1D01*
G01X615426D01*
G02X615124Y1721335I1J303D01*
G01Y1723739D01*
G02X615110Y1723976I2002J237D01*
G02X615124Y1724213I2016J0D01*
G01Y1728463D01*
G02X615110Y1728700I2002J237D01*
G02X615124Y1728937I2016J0D01*
G01Y1731341D01*
G02X615426Y1731644I302J1D01*
G37*
G36*
G01X1244954D02*
X1248654D01*
G02X1248956Y1731341I-1J-303D01*
G01Y1721335D01*
G02X1248654Y1721032I-302J-1D01*
G01X1244954D01*
G02X1244652Y1721335I1J303D01*
G01Y1723366D01*
G02X1244561Y1723976I2002J610D01*
G02X1245283Y1725558I2094J0D01*
G01X1245602Y1726208D01*
G03Y1726470I-267J131D01*
G01X1245285Y1727117D01*
G02X1244561Y1728700I1369J1583D01*
G02X1244652Y1729310I2093J0D01*
G01Y1731341D01*
G02X1244954Y1731644I302J1D01*
G37*
G36*
G01X1260702D02*
X1264402D01*
G02X1264704Y1731341I-1J-303D01*
G01Y1721335D01*
G02X1264402Y1721032I-302J-1D01*
G01X1260702D01*
G02X1260400Y1721335I1J303D01*
G01Y1723366D01*
G02X1260309Y1723976I2002J610D01*
G02X1261031Y1725558I2094J0D01*
G01X1261350Y1726208D01*
G03Y1726470I-267J131D01*
G01X1261033Y1727117D01*
G02X1260309Y1728700I1369J1583D01*
G02X1260400Y1729310I2093J0D01*
G01Y1731341D01*
G02X1260702Y1731644I302J1D01*
G37*
G36*
G01X1276450D02*
X1280150D01*
G02X1280452Y1731341I-1J-303D01*
G01Y1721335D01*
G02X1280150Y1721032I-302J-1D01*
G01X1276450D01*
G02X1276148Y1721335I1J303D01*
G01Y1723366D01*
G02X1276057Y1723976I2002J610D01*
G02X1276779Y1725558I2094J0D01*
G01X1277098Y1726208D01*
G03Y1726470I-267J131D01*
G01X1276781Y1727117D01*
G02X1276057Y1728700I1369J1583D01*
G02X1276148Y1729310I2093J0D01*
G01Y1731341D01*
G02X1276450Y1731644I302J1D01*
G37*
G36*
G01X1292198D02*
X1295898D01*
G02X1296200Y1731341I-1J-303D01*
G01Y1721335D01*
G02X1295898Y1721032I-302J-1D01*
G01X1292198D01*
G02X1291896Y1721335I1J303D01*
G01Y1723366D01*
G02X1291805Y1723976I2002J610D01*
G02X1292527Y1725558I2094J0D01*
G01X1292846Y1726208D01*
G03Y1726470I-267J131D01*
G01X1292529Y1727117D01*
G02X1291805Y1728700I1369J1583D01*
G02X1291896Y1729310I2093J0D01*
G01Y1731341D01*
G02X1292198Y1731644I302J1D01*
G37*
G36*
G01X1311883D02*
X1315583D01*
G02X1315886Y1731341I0J-303D01*
G01Y1721335D01*
G02X1315583Y1721032I-303J0D01*
G01X1311883D01*
G02X1311580Y1721335I0J303D01*
G01Y1723369D01*
G02X1311490Y1723976I2002J607D01*
G02X1312212Y1725558I2094J0D01*
G01X1312531Y1726208D01*
G03Y1726470I-267J131D01*
G01X1312214Y1727117D01*
G02X1311490Y1728700I1369J1583D01*
G02X1311580Y1729307I2092J0D01*
G01Y1731341D01*
G02X1311883Y1731644I303J0D01*
G37*
G36*
G01X1327631D02*
X1331331D01*
G02X1331634Y1731341I0J-303D01*
G01Y1721335D01*
G02X1331331Y1721032I-303J0D01*
G01X1327631D01*
G02X1327328Y1721335I0J303D01*
G01Y1723369D01*
G02X1327238Y1723976I2002J607D01*
G02X1327960Y1725558I2094J0D01*
G01X1328279Y1726208D01*
G03Y1726470I-267J131D01*
G01X1327962Y1727117D01*
G02X1327238Y1728700I1369J1583D01*
G02X1327328Y1729307I2092J0D01*
G01Y1731341D01*
G02X1327631Y1731644I303J0D01*
G37*
G36*
G01X1343379D02*
X1347079D01*
G02X1347382Y1731341I0J-303D01*
G01Y1721335D01*
G02X1347079Y1721032I-303J0D01*
G01X1343379D01*
G02X1343076Y1721335I0J303D01*
G01Y1723369D01*
G02X1342986Y1723976I2002J607D01*
G02X1343708Y1725558I2094J0D01*
G01X1344027Y1726208D01*
G03Y1726470I-267J131D01*
G01X1343710Y1727117D01*
G02X1342986Y1728700I1369J1583D01*
G02X1343076Y1729307I2092J0D01*
G01Y1731341D01*
G02X1343379Y1731644I303J0D01*
G37*
G36*
G01X1359127D02*
X1362827D01*
G02X1363130Y1731341I0J-303D01*
G01Y1721335D01*
G02X1362827Y1721032I-303J0D01*
G01X1359127D01*
G02X1358824Y1721335I0J303D01*
G01Y1723369D01*
G02X1358734Y1723976I2002J607D01*
G02X1359456Y1725558I2094J0D01*
G01X1359775Y1726208D01*
G03Y1726470I-267J131D01*
G01X1359458Y1727117D01*
G02X1358734Y1728700I1369J1583D01*
G02X1358824Y1729307I2092J0D01*
G01Y1731341D01*
G02X1359127Y1731644I303J0D01*
G37*
G36*
G01X1509127D02*
X1512827D01*
G02X1513130Y1731341I0J-303D01*
G01Y1721335D01*
G02X1512827Y1721032I-303J0D01*
G01X1509127D01*
G02X1508824Y1721335I0J303D01*
G01Y1723747D01*
G02X1508811Y1723976I2003J229D01*
G02X1508824Y1724205I2016J0D01*
G01Y1728471D01*
G02X1508811Y1728700I2003J229D01*
G02X1508824Y1728929I2016J0D01*
G01Y1731341D01*
G02X1509127Y1731644I303J0D01*
G37*
G36*
G01X1524875D02*
X1528575D01*
G02X1528878Y1731341I0J-303D01*
G01Y1721335D01*
G02X1528575Y1721032I-303J0D01*
G01X1524875D01*
G02X1524572Y1721335I0J303D01*
G01Y1723747D01*
G02X1524559Y1723976I2003J229D01*
G02X1524572Y1724205I2016J0D01*
G01Y1728471D01*
G02X1524559Y1728700I2003J229D01*
G02X1524572Y1728929I2016J0D01*
G01Y1731341D01*
G02X1524875Y1731644I303J0D01*
G37*
G36*
G01X1540623D02*
X1544323D01*
G02X1544626Y1731341I0J-303D01*
G01Y1721335D01*
G02X1544323Y1721032I-303J0D01*
G01X1540623D01*
G02X1540320Y1721335I0J303D01*
G01Y1723747D01*
G02X1540307Y1723976I2003J229D01*
G02X1540320Y1724205I2016J0D01*
G01Y1728471D01*
G02X1540307Y1728700I2003J229D01*
G02X1540320Y1728929I2016J0D01*
G01Y1731341D01*
G02X1540623Y1731644I303J0D01*
G37*
G36*
G01X1556371D02*
X1560071D01*
G02X1560374Y1731341I0J-303D01*
G01Y1721335D01*
G02X1560071Y1721032I-303J0D01*
G01X1556371D01*
G02X1556068Y1721335I0J303D01*
G01Y1723747D01*
G02X1556055Y1723976I2003J229D01*
G02X1556068Y1724205I2016J0D01*
G01Y1728471D01*
G02X1556055Y1728700I2003J229D01*
G02X1556068Y1728929I2016J0D01*
G01Y1731341D01*
G02X1556371Y1731644I303J0D01*
G37*
G36*
G01X1576056D02*
X1579756D01*
G02X1580058Y1731341I-1J-303D01*
G01Y1721335D01*
G02X1579756Y1721032I-302J-1D01*
G01X1576056D01*
G02X1575754Y1721335I1J303D01*
G01Y1723739D01*
G02X1575740Y1723976I2002J237D01*
G02X1575754Y1724213I2016J0D01*
G01Y1728463D01*
G02X1575740Y1728700I2002J237D01*
G02X1575754Y1728937I2016J0D01*
G01Y1731341D01*
G02X1576056Y1731644I302J1D01*
G37*
G36*
G01X1591804D02*
X1595504D01*
G02X1595806Y1731341I-1J-303D01*
G01Y1721335D01*
G02X1595504Y1721032I-302J-1D01*
G01X1591804D01*
G02X1591502Y1721335I1J303D01*
G01Y1723739D01*
G02X1591488Y1723976I2002J237D01*
G02X1591502Y1724213I2016J0D01*
G01Y1728463D01*
G02X1591488Y1728700I2002J237D01*
G02X1591502Y1728937I2016J0D01*
G01Y1731341D01*
G02X1591804Y1731644I302J1D01*
G37*
G36*
G01X1607552D02*
X1611252D01*
G02X1611554Y1731341I-1J-303D01*
G01Y1721335D01*
G02X1611252Y1721032I-302J-1D01*
G01X1607552D01*
G02X1607250Y1721335I1J303D01*
G01Y1723739D01*
G02X1607236Y1723976I2002J237D01*
G02X1607250Y1724213I2016J0D01*
G01Y1728463D01*
G02X1607236Y1728700I2002J237D01*
G02X1607250Y1728937I2016J0D01*
G01Y1731341D01*
G02X1607552Y1731644I302J1D01*
G37*
G36*
G01X1623300D02*
X1627000D01*
G02X1627302Y1731341I-1J-303D01*
G01Y1721335D01*
G02X1627000Y1721032I-302J-1D01*
G01X1623300D01*
G02X1622998Y1721335I1J303D01*
G01Y1723739D01*
G02X1622984Y1723976I2002J237D01*
G02X1622998Y1724213I2016J0D01*
G01Y1728463D01*
G02X1622984Y1728700I2002J237D01*
G02X1622998Y1728937I2016J0D01*
G01Y1731341D01*
G02X1623300Y1731644I302J1D01*
G37*
G36*
G01X816942Y1721140D02*
X901218D01*
G02X902102Y1720774I0J-1251D01*
G01X909144Y1713732D01*
G02X909510Y1712848I-885J-884D01*
G01Y1667658D01*
X918658Y1658510D01*
X1064948D01*
G02X1065832Y1658144I0J-1251D01*
G01X1085876Y1638100D01*
X1102078D01*
G02X1102962Y1637734I0J-1251D01*
G01X1105274Y1635422D01*
G02X1105640Y1634538I-885J-884D01*
G01Y1606962D01*
G02X1105274Y1606078I-1251J0D01*
G01X1103642Y1604446D01*
G02X1102758Y1604080I-884J885D01*
G01X943752D01*
G02X942868Y1604446I0J1251D01*
G01X916564Y1630750D01*
X815802D01*
G02X814918Y1631116I0J1251D01*
G01X810826Y1635208D01*
G02X810460Y1636092I885J884D01*
G01Y1714658D01*
G02X810826Y1715542I1251J0D01*
G01X816058Y1720774D01*
G02X816942Y1721140I884J-885D01*
G37*
G36*
G01X944340Y1584840D02*
X1103630D01*
G02X1104337Y1584547I0J-999D01*
G01X1105077Y1583807D01*
G02X1105370Y1583100I-706J-707D01*
G01Y1564620D01*
G02X1105077Y1563913I-999J0D01*
G01X1104017Y1562853D01*
G02X1103310Y1562560I-707J706D01*
G01X945140D01*
G02X944433Y1562853I0J999D01*
G01X942903Y1564383D01*
G02X942610Y1565090I706J707D01*
G01Y1583110D01*
G02X942903Y1583817I999J0D01*
G01X943633Y1584547D01*
G02X944340Y1584840I707J-706D01*
G37*
G36*
G01X105651Y1575002D02*
X102251D01*
G02Y1578006I0J1502D01*
G01X105651D01*
G02Y1575002I0J-1502D01*
G37*
G36*
G01X74218Y1574006D02*
X77618D01*
G02Y1571002I0J-1502D01*
G01X74218D01*
G02Y1574006I0J1502D01*
G37*
G36*
G01X76369Y1508958D02*
X79769D01*
G02Y1505954I0J-1502D01*
G01X76369D01*
G02Y1508958I0J1502D01*
G37*
G36*
G01X391330Y1583652D02*
X387930D01*
G02Y1586658I0J1503D01*
G01X391330D01*
G02Y1583652I0J-1503D01*
G37*
G36*
G01X148938Y1515872D02*
X145538D01*
G02Y1518876I0J1502D01*
G01X148938D01*
G02Y1515872I0J-1502D01*
G37*
G36*
G01X164710Y1519516D02*
X168110D01*
G02Y1516512I0J-1502D01*
G01X164710D01*
G02Y1519516I0J1502D01*
G37*
G36*
G01X89264Y1509114D02*
X92664D01*
G02Y1506108I0J-1503D01*
G01X89264D01*
G02Y1509114I0J1503D01*
G37*
G36*
G01X167266Y1571470D02*
X170666D01*
G02Y1568466I0J-1502D01*
G01X167266D01*
G02Y1571470I0J1502D01*
G37*
G36*
G01X1346792Y1615794D02*
X1350192D01*
G02Y1612790I0J-1502D01*
G01X1346792D01*
G02Y1615794I0J1502D01*
G37*
G36*
G01X1358852D02*
X1362252D01*
G02Y1612790I0J-1502D01*
G01X1358852D01*
G02Y1615794I0J1502D01*
G37*
G36*
G01X1365612Y1591596D02*
X1369012D01*
G02Y1588592I0J-1502D01*
G01X1365612D01*
G02Y1591596I0J1502D01*
G37*
G36*
G01Y1579684D02*
X1369012D01*
G02Y1576680I0J-1502D01*
G01X1365612D01*
G02Y1579684I0J1502D01*
G37*
G36*
G01X1305312D02*
X1308712D01*
G02Y1576680I0J-1502D01*
G01X1305312D01*
G02Y1579684I0J1502D01*
G37*
G36*
G01X1293252Y1591596D02*
X1296652D01*
G02Y1588592I0J-1502D01*
G01X1293252D01*
G02Y1591596I0J1502D01*
G37*
G36*
G01X1310612Y1615794D02*
X1314012D01*
G02Y1612790I0J-1502D01*
G01X1310612D01*
G02Y1615794I0J1502D01*
G37*
G36*
G01X1262372Y1603882D02*
X1265772D01*
G02Y1600878I0J-1502D01*
G01X1262372D01*
G02Y1603882I0J1502D01*
G37*
G36*
G01X1286492Y1615794D02*
X1289892D01*
G02Y1612790I0J-1502D01*
G01X1286492D01*
G02Y1615794I0J1502D01*
G37*
G36*
G01X1262372D02*
X1265772D01*
G02Y1612790I0J-1502D01*
G01X1262372D01*
G02Y1615794I0J1502D01*
G37*
G36*
G01X1334732Y1603882D02*
X1338132D01*
G02Y1600878I0J-1502D01*
G01X1334732D01*
G02Y1603882I0J1502D01*
G37*
G36*
G01X1220892Y1579684D02*
X1224292D01*
G02Y1576680I0J-1502D01*
G01X1220892D01*
G02Y1579684I0J1502D01*
G37*
G36*
G01X1334732Y1615794D02*
X1338132D01*
G02Y1612790I0J-1502D01*
G01X1334732D01*
G02Y1615794I0J1502D01*
G37*
G36*
G01X1370912Y1603882D02*
X1374312D01*
G02Y1600878I0J-1502D01*
G01X1370912D01*
G02Y1603882I0J1502D01*
G37*
G36*
G01X1214132D02*
X1217532D01*
G02Y1600878I0J-1502D01*
G01X1214132D01*
G02Y1603882I0J1502D01*
G37*
G36*
G01X1286492D02*
X1289892D01*
G02Y1600878I0J-1502D01*
G01X1286492D01*
G02Y1603882I0J1502D01*
G37*
G36*
G01X1298552D02*
X1301952D01*
G02Y1600878I0J-1502D01*
G01X1298552D01*
G02Y1603882I0J1502D01*
G37*
G36*
G01X1353552Y1579684D02*
X1356952D01*
G02Y1576680I0J-1502D01*
G01X1353552D01*
G02Y1579684I0J1502D01*
G37*
G36*
G01X1341492Y1591596D02*
X1344892D01*
G02Y1588592I0J-1502D01*
G01X1341492D01*
G02Y1591596I0J1502D01*
G37*
G36*
G01X1370912Y1615794D02*
X1374312D01*
G02Y1612790I0J-1502D01*
G01X1370912D01*
G02Y1615794I0J1502D01*
G37*
G36*
G01X1269132Y1591596D02*
X1272532D01*
G02Y1588592I0J-1502D01*
G01X1269132D01*
G02Y1591596I0J1502D01*
G37*
G36*
G01X1238252Y1603882D02*
X1241652D01*
G02Y1600878I0J-1502D01*
G01X1238252D01*
G02Y1603882I0J1502D01*
G37*
G36*
G01X1353552Y1591596D02*
X1356952D01*
G02Y1588592I0J-1502D01*
G01X1353552D01*
G02Y1591596I0J1502D01*
G37*
G36*
G01X1214132Y1615794D02*
X1217532D01*
G02Y1612790I0J-1502D01*
G01X1214132D01*
G02Y1615794I0J1502D01*
G37*
G36*
G01X1226192Y1603882D02*
X1229592D01*
G02Y1600878I0J-1502D01*
G01X1226192D01*
G02Y1603882I0J1502D01*
G37*
G36*
G01X1208832Y1579684D02*
X1212232D01*
G02Y1576680I0J-1502D01*
G01X1208832D01*
G02Y1579684I0J1502D01*
G37*
G36*
G01Y1591596D02*
X1212232D01*
G02Y1588592I0J-1502D01*
G01X1208832D01*
G02Y1591596I0J1502D01*
G37*
G36*
G01X1341492Y1579684D02*
X1344892D01*
G02Y1576680I0J-1502D01*
G01X1341492D01*
G02Y1579684I0J1502D01*
G37*
G36*
G01X1250312Y1615794D02*
X1253712D01*
G02Y1612790I0J-1502D01*
G01X1250312D01*
G02Y1615794I0J1502D01*
G37*
G36*
G01X1232952Y1579684D02*
X1236352D01*
G02Y1576680I0J-1502D01*
G01X1232952D01*
G02Y1579684I0J1502D01*
G37*
G36*
G01Y1591596D02*
X1236352D01*
G02Y1588592I0J-1502D01*
G01X1232952D01*
G02Y1591596I0J1502D01*
G37*
G36*
G01X1196772Y1579684D02*
X1200172D01*
G02Y1576680I0J-1502D01*
G01X1196772D01*
G02Y1579684I0J1502D01*
G37*
G36*
G01X1257072D02*
X1260472D01*
G02Y1576680I0J-1502D01*
G01X1257072D01*
G02Y1579684I0J1502D01*
G37*
G36*
G01X1220892Y1591596D02*
X1224292D01*
G02Y1588592I0J-1502D01*
G01X1220892D01*
G02Y1591596I0J1502D01*
G37*
G36*
G01X1269132Y1579684D02*
X1272532D01*
G02Y1576680I0J-1502D01*
G01X1269132D01*
G02Y1579684I0J1502D01*
G37*
G36*
G01X1305312Y1591596D02*
X1308712D01*
G02Y1588592I0J-1502D01*
G01X1305312D01*
G02Y1591596I0J1502D01*
G37*
G36*
G01X1245012D02*
X1248412D01*
G02Y1588592I0J-1502D01*
G01X1245012D01*
G02Y1591596I0J1502D01*
G37*
G36*
G01X1250312Y1603882D02*
X1253712D01*
G02Y1600878I0J-1502D01*
G01X1250312D01*
G02Y1603882I0J1502D01*
G37*
G36*
G01X1317372Y1579684D02*
X1320772D01*
G02Y1576680I0J-1502D01*
G01X1317372D01*
G02Y1579684I0J1502D01*
G37*
G36*
G01X1358852Y1603882D02*
X1362252D01*
G02Y1600878I0J-1502D01*
G01X1358852D01*
G02Y1603882I0J1502D01*
G37*
G36*
G01X1202072D02*
X1205472D01*
G02Y1600878I0J-1502D01*
G01X1202072D01*
G02Y1603882I0J1502D01*
G37*
G36*
G01Y1615794D02*
X1205472D01*
G02Y1612790I0J-1502D01*
G01X1202072D01*
G02Y1615794I0J1502D01*
G37*
G36*
G01X1322672Y1603882D02*
X1326072D01*
G02Y1600878I0J-1502D01*
G01X1322672D01*
G02Y1603882I0J1502D01*
G37*
G36*
G01X1310612D02*
X1314012D01*
G02Y1600878I0J-1502D01*
G01X1310612D01*
G02Y1603882I0J1502D01*
G37*
G36*
G01X1274432Y1615794D02*
X1277832D01*
G02Y1612790I0J-1502D01*
G01X1274432D01*
G02Y1615794I0J1502D01*
G37*
G36*
G01X1329432Y1579684D02*
X1332832D01*
G02Y1576680I0J-1502D01*
G01X1329432D01*
G02Y1579684I0J1502D01*
G37*
G36*
G01X1346792Y1603882D02*
X1350192D01*
G02Y1600878I0J-1502D01*
G01X1346792D01*
G02Y1603882I0J1502D01*
G37*
G36*
G01X1317372Y1591596D02*
X1320772D01*
G02Y1588592I0J-1502D01*
G01X1317372D01*
G02Y1591596I0J1502D01*
G37*
G36*
G01X1329432D02*
X1332832D01*
G02Y1588592I0J-1502D01*
G01X1329432D01*
G02Y1591596I0J1502D01*
G37*
G36*
G01X1322672Y1615794D02*
X1326072D01*
G02Y1612790I0J-1502D01*
G01X1322672D01*
G02Y1615794I0J1502D01*
G37*
G36*
G01X1281192Y1591596D02*
X1284592D01*
G02Y1588592I0J-1502D01*
G01X1281192D01*
G02Y1591596I0J1502D01*
G37*
G36*
G01X1196772D02*
X1200172D01*
G02Y1588592I0J-1502D01*
G01X1196772D01*
G02Y1591596I0J1502D01*
G37*
G36*
G01X1226192Y1615794D02*
X1229592D01*
G02Y1612790I0J-1502D01*
G01X1226192D01*
G02Y1615794I0J1502D01*
G37*
G36*
G01X1293252Y1579684D02*
X1296652D01*
G02Y1576680I0J-1502D01*
G01X1293252D01*
G02Y1579684I0J1502D01*
G37*
G36*
G01X1298552Y1615794D02*
X1301952D01*
G02Y1612790I0J-1502D01*
G01X1298552D01*
G02Y1615794I0J1502D01*
G37*
G36*
G01X1281192Y1579684D02*
X1284592D01*
G02Y1576680I0J-1502D01*
G01X1281192D01*
G02Y1579684I0J1502D01*
G37*
G36*
G01X1245012D02*
X1248412D01*
G02Y1576680I0J-1502D01*
G01X1245012D01*
G02Y1579684I0J1502D01*
G37*
G36*
G01X1257072Y1591596D02*
X1260472D01*
G02Y1588592I0J-1502D01*
G01X1257072D01*
G02Y1591596I0J1502D01*
G37*
G36*
G01X1274432Y1603882D02*
X1277832D01*
G02Y1600878I0J-1502D01*
G01X1274432D01*
G02Y1603882I0J1502D01*
G37*
G36*
G01X1238252Y1615794D02*
X1241652D01*
G02Y1612790I0J-1502D01*
G01X1238252D01*
G02Y1615794I0J1502D01*
G37*
G36*
G01X1474516Y730492D02*
G02X1473515Y728758I-2002J0D01*
G01X1469877Y726657D01*
G02X1468878Y726390I-999J1736D01*
G01X1468876D01*
G02X1466874Y728392I0J2002D01*
G02X1467875Y730126I2002J0D01*
G01X1471513Y732227D01*
G02X1472512Y732494I999J-1736D01*
G01X1472514D01*
G02X1474516Y730492I0J-2002D01*
G37*
G36*
G01X1477716Y717492D02*
G02X1476715Y715758I-2002J0D01*
G01X1473077Y713657D01*
G02X1472078Y713390I-999J1736D01*
G01X1472076D01*
G02X1470074Y715392I0J2002D01*
G02X1471075Y717126I2002J0D01*
G01X1474713Y719227D01*
G02X1475712Y719494I999J-1736D01*
G01X1475714D01*
G02X1477716Y717492I0J-2002D01*
G37*
G36*
G01Y702992D02*
G02X1476715Y701258I-2002J0D01*
G01X1473077Y699157D01*
G02X1472078Y698890I-999J1736D01*
G01X1472076D01*
G02X1470074Y700892I0J2002D01*
G02X1471075Y702626I2002J0D01*
G01X1474713Y704727D01*
G02X1475712Y704994I999J-1736D01*
G01X1475714D01*
G02X1477716Y702992I0J-2002D01*
G37*
G36*
G01Y688492D02*
G02X1476715Y686758I-2002J0D01*
G01X1473077Y684657D01*
G02X1472078Y684390I-999J1736D01*
G01X1472076D01*
G02X1470074Y686392I0J2002D01*
G02X1471075Y688126I2002J0D01*
G01X1474713Y690227D01*
G02X1475712Y690494I999J-1736D01*
G01X1475714D01*
G02X1477716Y688492I0J-2002D01*
G37*
G36*
G01Y673992D02*
G02X1476715Y672258I-2002J0D01*
G01X1473077Y670157D01*
G02X1472078Y669890I-999J1736D01*
G01X1472076D01*
G02X1470074Y671892I0J2002D01*
G02X1471075Y673626I2002J0D01*
G01X1474713Y675727D01*
G02X1475712Y675994I999J-1736D01*
G01X1475714D01*
G02X1477716Y673992I0J-2002D01*
G37*
G36*
G01Y659492D02*
G02X1476715Y657758I-2002J0D01*
G01X1473077Y655657D01*
G02X1472078Y655390I-999J1736D01*
G01X1472076D01*
G02X1470074Y657392I0J2002D01*
G02X1471075Y659126I2002J0D01*
G01X1474713Y661227D01*
G02X1475712Y661494I999J-1736D01*
G01X1475714D01*
G02X1477716Y659492I0J-2002D01*
G37*
G36*
G01X1455174Y716992D02*
G02X1457176Y718994I2002J0D01*
G01X1457178D01*
G02X1458177Y718727I0J-2003D01*
G01X1461815Y716626D01*
G02X1462816Y714892I-1001J-1734D01*
G02X1460814Y712890I-2002J0D01*
G01X1460812D01*
G02X1459813Y713157I0J2003D01*
G01X1456175Y715258D01*
G02X1455174Y716992I1001J1734D01*
G37*
G36*
G01Y704992D02*
G02X1457176Y706994I2002J0D01*
G01X1457178D01*
G02X1458177Y706727I0J-2003D01*
G01X1461815Y704626D01*
G02X1462816Y702892I-1001J-1734D01*
G02X1460814Y700890I-2002J0D01*
G01X1460812D01*
G02X1459813Y701157I0J2003D01*
G01X1456175Y703258D01*
G02X1455174Y704992I1001J1734D01*
G37*
G36*
G01Y692992D02*
G02X1457176Y694994I2002J0D01*
G01X1457178D01*
G02X1458177Y694727I0J-2003D01*
G01X1461815Y692626D01*
G02X1462816Y690892I-1001J-1734D01*
G02X1460814Y688890I-2002J0D01*
G01X1460812D01*
G02X1459813Y689157I0J2003D01*
G01X1456175Y691258D01*
G02X1455174Y692992I1001J1734D01*
G37*
G36*
G01Y680992D02*
G02X1457176Y682994I2002J0D01*
G01X1457178D01*
G02X1458177Y682727I0J-2003D01*
G01X1461815Y680626D01*
G02X1462816Y678892I-1001J-1734D01*
G02X1460814Y676890I-2002J0D01*
G01X1460812D01*
G02X1459813Y677157I0J2003D01*
G01X1456175Y679258D01*
G02X1455174Y680992I1001J1734D01*
G37*
G36*
G01Y668992D02*
G02X1457176Y670994I2002J0D01*
G01X1457178D01*
G02X1458177Y670727I0J-2003D01*
G01X1461815Y668626D01*
G02X1462816Y666892I-1001J-1734D01*
G02X1460814Y664890I-2002J0D01*
G01X1460812D01*
G02X1459813Y665157I0J2003D01*
G01X1456175Y667258D01*
G02X1455174Y668992I1001J1734D01*
G37*
G36*
G01Y656992D02*
G02X1457176Y658994I2002J0D01*
G01X1457178D01*
G02X1458177Y658727I0J-2003D01*
G01X1461815Y656626D01*
G02X1462816Y654892I-1001J-1734D01*
G02X1460814Y652890I-2002J0D01*
G01X1460812D01*
G02X1459813Y653157I0J2003D01*
G01X1456175Y655258D01*
G02X1455174Y656992I1001J1734D01*
G37*
G36*
G01X1390978Y737198D02*
G02X1389977Y735464I-2002J0D01*
G01X1386339Y733363D01*
G02X1385340Y733096I-999J1736D01*
G01X1385338D01*
G02X1383336Y735098I0J2002D01*
G02X1384337Y736832I2002J0D01*
G01X1387975Y738933D01*
G02X1388974Y739200I999J-1736D01*
G01X1388976D01*
G02X1390978Y737198I0J-2002D01*
G37*
G36*
G01X1395208Y722735D02*
G02X1394207Y721001I-2002J0D01*
G01X1390569Y718900D01*
G02X1389570Y718632I-1001J1735D01*
G01X1389568D01*
G02X1387566Y720635I1J2003D01*
G02X1388567Y722369I2002J0D01*
G01X1392205Y724470D01*
G02X1393204Y724738I1001J-1735D01*
G01X1393206D01*
G02X1395208Y722735I-1J-2003D01*
G37*
G36*
G01Y693708D02*
G02X1394207Y691974I-2002J0D01*
G01X1390569Y689873D01*
G02X1389570Y689606I-999J1736D01*
G01X1389568D01*
G02X1387566Y691608I0J2002D01*
G02X1388567Y693342I2002J0D01*
G01X1392205Y695443D01*
G02X1393204Y695710I999J-1736D01*
G01X1393206D01*
G02X1395208Y693708I0J-2002D01*
G37*
G36*
G01Y708208D02*
G02X1394207Y706474I-2002J0D01*
G01X1390569Y704373D01*
G02X1389570Y704106I-999J1736D01*
G01X1389568D01*
G02X1387566Y706108I0J2002D01*
G02X1388567Y707842I2002J0D01*
G01X1392205Y709943D01*
G02X1393204Y710210I999J-1736D01*
G01X1393206D01*
G02X1395208Y708208I0J-2002D01*
G37*
G36*
G01Y679208D02*
G02X1394207Y677474I-2002J0D01*
G01X1390569Y675373D01*
G02X1389570Y675106I-999J1736D01*
G01X1389568D01*
G02X1387566Y677108I0J2002D01*
G02X1388567Y678842I2002J0D01*
G01X1392205Y680943D01*
G02X1393204Y681210I999J-1736D01*
G01X1393206D01*
G02X1395208Y679208I0J-2002D01*
G37*
G36*
G01Y664708D02*
G02X1394207Y662974I-2002J0D01*
G01X1390569Y660873D01*
G02X1389570Y660606I-999J1736D01*
G01X1389568D01*
G02X1387566Y662608I0J2002D01*
G02X1388567Y664342I2002J0D01*
G01X1392205Y666443D01*
G02X1393204Y666710I999J-1736D01*
G01X1393206D01*
G02X1395208Y664708I0J-2002D01*
G37*
G36*
G01X1372666Y719708D02*
G02X1374668Y721710I2002J0D01*
G01X1374670D01*
G02X1375669Y721443I0J-2003D01*
G01X1379307Y719342D01*
G02X1380308Y717608I-1001J-1734D01*
G02X1378306Y715606I-2002J0D01*
G01X1378304D01*
G02X1377305Y715873I0J2003D01*
G01X1373667Y717974D01*
G02X1372666Y719708I1001J1734D01*
G37*
G36*
G01Y695708D02*
G02X1374668Y697710I2002J0D01*
G01X1374670D01*
G02X1375669Y697443I0J-2003D01*
G01X1379307Y695342D01*
G02X1380308Y693608I-1001J-1734D01*
G02X1378306Y691606I-2002J0D01*
G01X1378304D01*
G02X1377305Y691873I0J2003D01*
G01X1373667Y693974D01*
G02X1372666Y695708I1001J1734D01*
G37*
G36*
G01Y707708D02*
G02X1374668Y709710I2002J0D01*
G01X1374670D01*
G02X1375669Y709443I0J-2003D01*
G01X1379307Y707342D01*
G02X1380308Y705608I-1001J-1734D01*
G02X1378306Y703606I-2002J0D01*
G01X1378304D01*
G02X1377305Y703873I0J2003D01*
G01X1373667Y705974D01*
G02X1372666Y707708I1001J1734D01*
G37*
G36*
G01Y683708D02*
G02X1374668Y685710I2002J0D01*
G01X1374670D01*
G02X1375669Y685443I0J-2003D01*
G01X1379307Y683342D01*
G02X1380308Y681608I-1001J-1734D01*
G02X1378306Y679606I-2002J0D01*
G01X1378304D01*
G02X1377305Y679873I0J2003D01*
G01X1373667Y681974D01*
G02X1372666Y683708I1001J1734D01*
G37*
G36*
G01Y671708D02*
G02X1374668Y673710I2002J0D01*
G01X1374670D01*
G02X1375669Y673443I0J-2003D01*
G01X1379307Y671342D01*
G02X1380308Y669608I-1001J-1734D01*
G02X1378306Y667606I-2002J0D01*
G01X1378304D01*
G02X1377305Y667873I0J2003D01*
G01X1373667Y669974D01*
G02X1372666Y671708I1001J1734D01*
G37*
G36*
G01Y659708D02*
G02X1374668Y661710I2002J0D01*
G01X1374670D01*
G02X1375669Y661443I0J-2003D01*
G01X1379307Y659342D01*
G02X1380308Y657608I-1001J-1734D01*
G02X1378306Y655606I-2002J0D01*
G01X1378304D01*
G02X1377305Y655873I0J2003D01*
G01X1373667Y657974D01*
G02X1372666Y659708I1001J1734D01*
G37*
G36*
G01X146312Y1571028D02*
X149712D01*
G02Y1568022I0J-1503D01*
G01X146312D01*
G02Y1571028I0J1503D01*
G37*
G36*
G01X1701934Y76800D02*
X1705334D01*
G02Y73794I0J-1503D01*
G01X1701934D01*
G02Y76800I0J1503D01*
G37*
G36*
G01X1690934Y70800D02*
X1694334D01*
G02Y67794I0J-1503D01*
G01X1690934D01*
G02Y70800I0J1503D01*
G37*
G36*
G01X1679934Y76800D02*
X1683334D01*
G02Y73794I0J-1503D01*
G01X1679934D01*
G02Y76800I0J1503D01*
G37*
G36*
G01X1657800D02*
X1661200D01*
G02Y73794I0J-1503D01*
G01X1657800D01*
G02Y76800I0J1503D01*
G37*
G36*
G01X1668800Y70800D02*
X1672200D01*
G02Y67794I0J-1503D01*
G01X1668800D01*
G02Y70800I0J1503D01*
G37*
G36*
G01X1646800D02*
X1650200D01*
G02Y67794I0J-1503D01*
G01X1646800D01*
G02Y70800I0J1503D01*
G37*
G36*
G01X1635800Y76800D02*
X1639200D01*
G02Y73794I0J-1503D01*
G01X1635800D01*
G02Y76800I0J1503D01*
G37*
G36*
G01X1612596D02*
X1615996D01*
G02Y73794I0J-1503D01*
G01X1612596D01*
G02Y76800I0J1503D01*
G37*
G36*
G01X1623596Y70800D02*
X1626996D01*
G02Y67794I0J-1503D01*
G01X1623596D01*
G02Y70800I0J1503D01*
G37*
G36*
G01X1601596D02*
X1604996D01*
G02Y67794I0J-1503D01*
G01X1601596D01*
G02Y70800I0J1503D01*
G37*
G36*
G01X1590596Y76800D02*
X1593996D01*
G02Y73794I0J-1503D01*
G01X1590596D01*
G02Y76800I0J1503D01*
G37*
G36*
G01X1579596Y70800D02*
X1582996D01*
G02Y67794I0J-1503D01*
G01X1579596D01*
G02Y70800I0J1503D01*
G37*
G36*
G01X1568596Y76800D02*
X1571996D01*
G02Y73794I0J-1503D01*
G01X1568596D01*
G02Y76800I0J1503D01*
G37*
G36*
G01X1546596D02*
X1549996D01*
G02Y73794I0J-1503D01*
G01X1546596D01*
G02Y76800I0J1503D01*
G37*
G36*
G01X1557596Y70800D02*
X1560996D01*
G02Y67794I0J-1503D01*
G01X1557596D01*
G02Y70800I0J1503D01*
G37*
G36*
G01X1535596D02*
X1538996D01*
G02Y67794I0J-1503D01*
G01X1535596D01*
G02Y70800I0J1503D01*
G37*
G36*
G01X230895Y73838D02*
X227495D01*
G02Y76842I0J1502D01*
G01X230895D01*
G02Y73838I0J-1502D01*
G37*
G36*
G01X219895Y67838D02*
X216495D01*
G02Y70842I0J1502D01*
G01X219895D01*
G02Y67838I0J-1502D01*
G37*
G36*
G01X208895Y73838D02*
X205495D01*
G02Y76842I0J1502D01*
G01X208895D01*
G02Y73838I0J-1502D01*
G37*
G36*
G01X194361Y70842D02*
X197761D01*
G02Y67838I0J-1502D01*
G01X194361D01*
G02Y70842I0J1502D01*
G37*
G36*
G01X183361Y76842D02*
X186761D01*
G02Y73838I0J-1502D01*
G01X183361D01*
G02Y76842I0J1502D01*
G37*
G36*
G01X161361D02*
X164761D01*
G02Y73838I0J-1502D01*
G01X161361D01*
G02Y76842I0J1502D01*
G37*
G36*
G01X172361Y70842D02*
X175761D01*
G02Y67838I0J-1502D01*
G01X172361D01*
G02Y70842I0J1502D01*
G37*
G36*
G01X149157D02*
X152557D01*
G02Y67838I0J-1502D01*
G01X149157D01*
G02Y70842I0J1502D01*
G37*
G36*
G01X138157Y76842D02*
X141557D01*
G02Y73838I0J-1502D01*
G01X138157D01*
G02Y76842I0J1502D01*
G37*
G36*
G01X116157D02*
X119557D01*
G02Y73838I0J-1502D01*
G01X116157D01*
G02Y76842I0J1502D01*
G37*
G36*
G01X127157Y70842D02*
X130557D01*
G02Y67838I0J-1502D01*
G01X127157D01*
G02Y70842I0J1502D01*
G37*
G36*
G01X105157D02*
X108557D01*
G02Y67838I0J-1502D01*
G01X105157D01*
G02Y70842I0J1502D01*
G37*
G36*
G01X94157Y76842D02*
X97557D01*
G02Y73838I0J-1502D01*
G01X94157D01*
G02Y76842I0J1502D01*
G37*
G36*
G01X83157Y70842D02*
X86557D01*
G02Y67838I0J-1502D01*
G01X83157D01*
G02Y70842I0J1502D01*
G37*
G36*
G01X72157Y76842D02*
X75557D01*
G02Y73838I0J-1502D01*
G01X72157D01*
G02Y76842I0J1502D01*
G37*
G36*
G01X61157Y70842D02*
X64557D01*
G02Y67838I0J-1502D01*
G01X61157D01*
G02Y70842I0J1502D01*
G37*
G36*
G01X1619075Y1579684D02*
X1622475D01*
G02Y1576680I0J-1502D01*
G01X1619075D01*
G02Y1579684I0J1502D01*
G37*
G36*
G01X326857Y1603882D02*
X330257D01*
G02Y1600878I0J-1502D01*
G01X326857D01*
G02Y1603882I0J1502D01*
G37*
G36*
G01X363037Y1615794D02*
X366437D01*
G02Y1612790I0J-1502D01*
G01X363037D01*
G02Y1615794I0J1502D01*
G37*
G36*
G01X545411Y1579684D02*
X548811D01*
G02Y1576680I0J-1502D01*
G01X545411D01*
G02Y1579684I0J1502D01*
G37*
G36*
G01Y1591596D02*
X548811D01*
G02Y1588592I0J-1502D01*
G01X545411D01*
G02Y1591596I0J1502D01*
G37*
G36*
G01X1377672D02*
X1381072D01*
G02Y1588592I0J-1502D01*
G01X1377672D01*
G02Y1591596I0J1502D01*
G37*
G36*
G01X533351D02*
X536751D01*
G02Y1588592I0J-1502D01*
G01X533351D01*
G02Y1591596I0J1502D01*
G37*
G36*
G01Y1579684D02*
X536751D01*
G02Y1576680I0J-1502D01*
G01X533351D01*
G02Y1579684I0J1502D01*
G37*
G36*
G01X1594955Y1591596D02*
X1598355D01*
G02Y1588592I0J-1502D01*
G01X1594955D01*
G02Y1591596I0J1502D01*
G37*
G36*
G01X581591D02*
X584991D01*
G02Y1588592I0J-1502D01*
G01X581591D01*
G02Y1591596I0J1502D01*
G37*
G36*
G01Y1579684D02*
X584991D01*
G02Y1576680I0J-1502D01*
G01X581591D01*
G02Y1579684I0J1502D01*
G37*
G36*
G01X1594955D02*
X1598355D01*
G02Y1576680I0J-1502D01*
G01X1594955D01*
G02Y1579684I0J1502D01*
G37*
G36*
G01X605711Y1591596D02*
X609111D01*
G02Y1588592I0J-1502D01*
G01X605711D01*
G02Y1591596I0J1502D01*
G37*
G36*
G01X333617Y1579684D02*
X337017D01*
G02Y1576680I0J-1502D01*
G01X333617D01*
G02Y1579684I0J1502D01*
G37*
G36*
G01X345677D02*
X349077D01*
G02Y1576680I0J-1502D01*
G01X345677D01*
G02Y1579684I0J1502D01*
G37*
G36*
G01X617771D02*
X621171D01*
G02Y1576680I0J-1502D01*
G01X617771D01*
G02Y1579684I0J1502D01*
G37*
G36*
G01Y1591596D02*
X621171D01*
G02Y1588592I0J-1502D01*
G01X617771D01*
G02Y1591596I0J1502D01*
G37*
G36*
G01X629831Y1579684D02*
X633231D01*
G02Y1576680I0J-1502D01*
G01X629831D01*
G02Y1579684I0J1502D01*
G37*
G36*
G01X1582895D02*
X1586295D01*
G02Y1576680I0J-1502D01*
G01X1582895D01*
G02Y1579684I0J1502D01*
G37*
G36*
G01X1570835D02*
X1574235D01*
G02Y1576680I0J-1502D01*
G01X1570835D01*
G02Y1579684I0J1502D01*
G37*
G36*
G01X1558775D02*
X1562175D01*
G02Y1576680I0J-1502D01*
G01X1558775D01*
G02Y1579684I0J1502D01*
G37*
G36*
G01X321557D02*
X324957D01*
G02Y1576680I0J-1502D01*
G01X321557D01*
G02Y1579684I0J1502D01*
G37*
G36*
G01X278617Y1603882D02*
X282017D01*
G02Y1600878I0J-1502D01*
G01X278617D01*
G02Y1603882I0J1502D01*
G37*
G36*
G01X1534655Y1591596D02*
X1538055D01*
G02Y1588592I0J-1502D01*
G01X1534655D01*
G02Y1591596I0J1502D01*
G37*
G36*
G01Y1579684D02*
X1538055D01*
G02Y1576680I0J-1502D01*
G01X1534655D01*
G02Y1579684I0J1502D01*
G37*
G36*
G01X1510535Y1591596D02*
X1513935D01*
G02Y1588592I0J-1502D01*
G01X1510535D01*
G02Y1591596I0J1502D01*
G37*
G36*
G01X1522595D02*
X1525995D01*
G02Y1588592I0J-1502D01*
G01X1522595D01*
G02Y1591596I0J1502D01*
G37*
G36*
G01X309497Y1579684D02*
X312897D01*
G02Y1576680I0J-1502D01*
G01X309497D01*
G02Y1579684I0J1502D01*
G37*
G36*
G01X302737Y1603882D02*
X306137D01*
G02Y1600878I0J-1502D01*
G01X302737D01*
G02Y1603882I0J1502D01*
G37*
G36*
G01X1498475Y1579684D02*
X1501875D01*
G02Y1576680I0J-1502D01*
G01X1498475D01*
G02Y1579684I0J1502D01*
G37*
G36*
G01X314797Y1615794D02*
X318197D01*
G02Y1612790I0J-1502D01*
G01X314797D01*
G02Y1615794I0J1502D01*
G37*
G36*
G01X278617D02*
X282017D01*
G02Y1612790I0J-1502D01*
G01X278617D01*
G02Y1615794I0J1502D01*
G37*
G36*
G01X497171Y1591596D02*
X500571D01*
G02Y1588592I0J-1502D01*
G01X497171D01*
G02Y1591596I0J1502D01*
G37*
G36*
G01X509231D02*
X512631D01*
G02Y1588592I0J-1502D01*
G01X509231D01*
G02Y1591596I0J1502D01*
G37*
G36*
G01Y1579684D02*
X512631D01*
G02Y1576680I0J-1502D01*
G01X509231D01*
G02Y1579684I0J1502D01*
G37*
G36*
G01X1486415Y1591596D02*
X1489815D01*
G02Y1588592I0J-1502D01*
G01X1486415D01*
G02Y1591596I0J1502D01*
G37*
G36*
G01Y1579684D02*
X1489815D01*
G02Y1576680I0J-1502D01*
G01X1486415D01*
G02Y1579684I0J1502D01*
G37*
G36*
G01X321557Y1591596D02*
X324957D01*
G02Y1588592I0J-1502D01*
G01X321557D01*
G02Y1591596I0J1502D01*
G37*
G36*
G01X1462295D02*
X1465695D01*
G02Y1588592I0J-1502D01*
G01X1462295D01*
G02Y1591596I0J1502D01*
G37*
G36*
G01X1474355D02*
X1477755D01*
G02Y1588592I0J-1502D01*
G01X1474355D01*
G02Y1591596I0J1502D01*
G37*
G36*
G01X641891Y1579684D02*
X645291D01*
G02Y1576680I0J-1502D01*
G01X641891D01*
G02Y1579684I0J1502D01*
G37*
G36*
G01Y1591596D02*
X645291D01*
G02Y1588592I0J-1502D01*
G01X641891D01*
G02Y1591596I0J1502D01*
G37*
G36*
G01X285377Y1579684D02*
X288777D01*
G02Y1576680I0J-1502D01*
G01X285377D01*
G02Y1579684I0J1502D01*
G37*
G36*
G01X1462295D02*
X1465695D01*
G02Y1576680I0J-1502D01*
G01X1462295D01*
G02Y1579684I0J1502D01*
G37*
G36*
G01X206257Y1615794D02*
X209657D01*
G02Y1612790I0J-1502D01*
G01X206257D01*
G02Y1615794I0J1502D01*
G37*
G36*
G01X338917D02*
X342317D01*
G02Y1612790I0J-1502D01*
G01X338917D01*
G02Y1615794I0J1502D01*
G37*
G36*
G01X1474355Y1579684D02*
X1477755D01*
G02Y1576680I0J-1502D01*
G01X1474355D01*
G02Y1579684I0J1502D01*
G37*
G36*
G01X261257D02*
X264657D01*
G02Y1576680I0J-1502D01*
G01X261257D01*
G02Y1579684I0J1502D01*
G37*
G36*
G01X485111D02*
X488511D01*
G02Y1576680I0J-1502D01*
G01X485111D01*
G02Y1579684I0J1502D01*
G37*
G36*
G01Y1591596D02*
X488511D01*
G02Y1588592I0J-1502D01*
G01X485111D01*
G02Y1591596I0J1502D01*
G37*
G36*
G01X338917Y1603882D02*
X342317D01*
G02Y1600878I0J-1502D01*
G01X338917D01*
G02Y1603882I0J1502D01*
G37*
G36*
G01X1648495Y1615794D02*
X1651895D01*
G02Y1612790I0J-1502D01*
G01X1648495D01*
G02Y1615794I0J1502D01*
G37*
G36*
G01Y1603882D02*
X1651895D01*
G02Y1600878I0J-1502D01*
G01X1648495D01*
G02Y1603882I0J1502D01*
G37*
G36*
G01X1624375Y1615794D02*
X1627775D01*
G02Y1612790I0J-1502D01*
G01X1624375D01*
G02Y1615794I0J1502D01*
G37*
G36*
G01X266557D02*
X269957D01*
G02Y1612790I0J-1502D01*
G01X266557D01*
G02Y1615794I0J1502D01*
G37*
G36*
G01X254497Y1603882D02*
X257897D01*
G02Y1600878I0J-1502D01*
G01X254497D01*
G02Y1603882I0J1502D01*
G37*
G36*
G01X653951Y1591596D02*
X657351D01*
G02Y1588592I0J-1502D01*
G01X653951D01*
G02Y1591596I0J1502D01*
G37*
G36*
G01Y1579684D02*
X657351D01*
G02Y1576680I0J-1502D01*
G01X653951D01*
G02Y1579684I0J1502D01*
G37*
G36*
G01X369797Y1591596D02*
X373197D01*
G02Y1588592I0J-1502D01*
G01X369797D01*
G02Y1591596I0J1502D01*
G37*
G36*
G01X1636435Y1603882D02*
X1639835D01*
G02Y1600878I0J-1502D01*
G01X1636435D01*
G02Y1603882I0J1502D01*
G37*
G36*
G01X266557D02*
X269957D01*
G02Y1600878I0J-1502D01*
G01X266557D01*
G02Y1603882I0J1502D01*
G37*
G36*
G01X1624375D02*
X1627775D01*
G02Y1600878I0J-1502D01*
G01X1624375D01*
G02Y1603882I0J1502D01*
G37*
G36*
G01X254497Y1615794D02*
X257897D01*
G02Y1612790I0J-1502D01*
G01X254497D01*
G02Y1615794I0J1502D01*
G37*
G36*
G01X194197Y1603882D02*
X197597D01*
G02Y1600878I0J-1502D01*
G01X194197D01*
G02Y1603882I0J1502D01*
G37*
G36*
G01X242437D02*
X245837D01*
G02Y1600878I0J-1502D01*
G01X242437D01*
G02Y1603882I0J1502D01*
G37*
G36*
G01X1612315D02*
X1615715D01*
G02Y1600878I0J-1502D01*
G01X1612315D01*
G02Y1603882I0J1502D01*
G37*
G36*
G01Y1615794D02*
X1615715D01*
G02Y1612790I0J-1502D01*
G01X1612315D01*
G02Y1615794I0J1502D01*
G37*
G36*
G01X230377D02*
X233777D01*
G02Y1612790I0J-1502D01*
G01X230377D01*
G02Y1615794I0J1502D01*
G37*
G36*
G01X521291Y1579684D02*
X524691D01*
G02Y1576680I0J-1502D01*
G01X521291D01*
G02Y1579684I0J1502D01*
G37*
G36*
G01Y1591596D02*
X524691D01*
G02Y1588592I0J-1502D01*
G01X521291D01*
G02Y1591596I0J1502D01*
G37*
G36*
G01X497171Y1579684D02*
X500571D01*
G02Y1576680I0J-1502D01*
G01X497171D01*
G02Y1579684I0J1502D01*
G37*
G36*
G01X593651D02*
X597051D01*
G02Y1576680I0J-1502D01*
G01X593651D01*
G02Y1579684I0J1502D01*
G37*
G36*
G01Y1591596D02*
X597051D01*
G02Y1588592I0J-1502D01*
G01X593651D01*
G02Y1591596I0J1502D01*
G37*
G36*
G01X1600255Y1603882D02*
X1603655D01*
G02Y1600878I0J-1502D01*
G01X1600255D01*
G02Y1603882I0J1502D01*
G37*
G36*
G01Y1615794D02*
X1603655D01*
G02Y1612790I0J-1502D01*
G01X1600255D01*
G02Y1615794I0J1502D01*
G37*
G36*
G01X557471Y1579684D02*
X560871D01*
G02Y1576680I0J-1502D01*
G01X557471D01*
G02Y1579684I0J1502D01*
G37*
G36*
G01X569531D02*
X572931D01*
G02Y1576680I0J-1502D01*
G01X569531D01*
G02Y1579684I0J1502D01*
G37*
G36*
G01Y1591596D02*
X572931D01*
G02Y1588592I0J-1502D01*
G01X569531D01*
G02Y1591596I0J1502D01*
G37*
G36*
G01X557471D02*
X560871D01*
G02Y1588592I0J-1502D01*
G01X557471D01*
G02Y1591596I0J1502D01*
G37*
G36*
G01X333617D02*
X337017D01*
G02Y1588592I0J-1502D01*
G01X333617D01*
G02Y1591596I0J1502D01*
G37*
G36*
G01X345677D02*
X349077D01*
G02Y1588592I0J-1502D01*
G01X345677D01*
G02Y1591596I0J1502D01*
G37*
G36*
G01X1607015Y1579684D02*
X1610415D01*
G02Y1576680I0J-1502D01*
G01X1607015D01*
G02Y1579684I0J1502D01*
G37*
G36*
G01X1576135Y1615794D02*
X1579535D01*
G02Y1612790I0J-1502D01*
G01X1576135D01*
G02Y1615794I0J1502D01*
G37*
G36*
G01X314797Y1603882D02*
X318197D01*
G02Y1600878I0J-1502D01*
G01X314797D01*
G02Y1603882I0J1502D01*
G37*
G36*
G01X1576135D02*
X1579535D01*
G02Y1600878I0J-1502D01*
G01X1576135D01*
G02Y1603882I0J1502D01*
G37*
G36*
G01X261257Y1591596D02*
X264657D01*
G02Y1588592I0J-1502D01*
G01X261257D01*
G02Y1591596I0J1502D01*
G37*
G36*
G01X357737Y1579684D02*
X361137D01*
G02Y1576680I0J-1502D01*
G01X357737D01*
G02Y1579684I0J1502D01*
G37*
G36*
G01X1546715Y1591596D02*
X1550115D01*
G02Y1588592I0J-1502D01*
G01X1546715D01*
G02Y1591596I0J1502D01*
G37*
G36*
G01Y1579684D02*
X1550115D01*
G02Y1576680I0J-1502D01*
G01X1546715D01*
G02Y1579684I0J1502D01*
G37*
G36*
G01X326857Y1615794D02*
X330257D01*
G02Y1612790I0J-1502D01*
G01X326857D01*
G02Y1615794I0J1502D01*
G37*
G36*
G01X249197Y1591596D02*
X252597D01*
G02Y1588592I0J-1502D01*
G01X249197D01*
G02Y1591596I0J1502D01*
G37*
G36*
G01X309497D02*
X312897D01*
G02Y1588592I0J-1502D01*
G01X309497D01*
G02Y1591596I0J1502D01*
G37*
G36*
G01X1564075Y1603882D02*
X1567475D01*
G02Y1600878I0J-1502D01*
G01X1564075D01*
G02Y1603882I0J1502D01*
G37*
G36*
G01Y1615794D02*
X1567475D01*
G02Y1612790I0J-1502D01*
G01X1564075D01*
G02Y1615794I0J1502D01*
G37*
G36*
G01X1552015D02*
X1555415D01*
G02Y1612790I0J-1502D01*
G01X1552015D01*
G02Y1615794I0J1502D01*
G37*
G36*
G01X1503775D02*
X1507175D01*
G02Y1612790I0J-1502D01*
G01X1503775D01*
G02Y1615794I0J1502D01*
G37*
G36*
G01X1552015Y1603882D02*
X1555415D01*
G02Y1600878I0J-1502D01*
G01X1552015D01*
G02Y1603882I0J1502D01*
G37*
G36*
G01X629831Y1591596D02*
X633231D01*
G02Y1588592I0J-1502D01*
G01X629831D01*
G02Y1591596I0J1502D01*
G37*
G36*
G01X1377672Y1579684D02*
X1381072D01*
G02Y1576680I0J-1502D01*
G01X1377672D01*
G02Y1579684I0J1502D01*
G37*
G36*
G01X218317Y1603882D02*
X221717D01*
G02Y1600878I0J-1502D01*
G01X218317D01*
G02Y1603882I0J1502D01*
G37*
G36*
G01X206257D02*
X209657D01*
G02Y1600878I0J-1502D01*
G01X206257D01*
G02Y1603882I0J1502D01*
G37*
G36*
G01X1527895Y1615794D02*
X1531295D01*
G02Y1612790I0J-1502D01*
G01X1527895D01*
G02Y1615794I0J1502D01*
G37*
G36*
G01X200957Y1591596D02*
X204357D01*
G02Y1588592I0J-1502D01*
G01X200957D01*
G02Y1591596I0J1502D01*
G37*
G36*
G01X1631135D02*
X1634535D01*
G02Y1588592I0J-1502D01*
G01X1631135D01*
G02Y1591596I0J1502D01*
G37*
G36*
G01X1539955Y1615794D02*
X1543355D01*
G02Y1612790I0J-1502D01*
G01X1539955D01*
G02Y1615794I0J1502D01*
G37*
G36*
G01Y1603882D02*
X1543355D01*
G02Y1600878I0J-1502D01*
G01X1539955D01*
G02Y1603882I0J1502D01*
G37*
G36*
G01X1527895D02*
X1531295D01*
G02Y1600878I0J-1502D01*
G01X1527895D01*
G02Y1603882I0J1502D01*
G37*
G36*
G01X302737Y1615794D02*
X306137D01*
G02Y1612790I0J-1502D01*
G01X302737D01*
G02Y1615794I0J1502D01*
G37*
G36*
G01X1522595Y1579684D02*
X1525995D01*
G02Y1576680I0J-1502D01*
G01X1522595D01*
G02Y1579684I0J1502D01*
G37*
G36*
G01X1515835Y1615794D02*
X1519235D01*
G02Y1612790I0J-1502D01*
G01X1515835D01*
G02Y1615794I0J1502D01*
G37*
G36*
G01X1636435D02*
X1639835D01*
G02Y1612790I0J-1502D01*
G01X1636435D01*
G02Y1615794I0J1502D01*
G37*
G36*
G01X1498475Y1591596D02*
X1501875D01*
G02Y1588592I0J-1502D01*
G01X1498475D01*
G02Y1591596I0J1502D01*
G37*
G36*
G01X1643195D02*
X1646595D01*
G02Y1588592I0J-1502D01*
G01X1643195D01*
G02Y1591596I0J1502D01*
G37*
G36*
G01X1515835Y1603882D02*
X1519235D01*
G02Y1600878I0J-1502D01*
G01X1515835D01*
G02Y1603882I0J1502D01*
G37*
G36*
G01X357737Y1591596D02*
X361137D01*
G02Y1588592I0J-1502D01*
G01X357737D01*
G02Y1591596I0J1502D01*
G37*
G36*
G01X194197Y1615794D02*
X197597D01*
G02Y1612790I0J-1502D01*
G01X194197D01*
G02Y1615794I0J1502D01*
G37*
G36*
G01X1510535Y1579684D02*
X1513935D01*
G02Y1576680I0J-1502D01*
G01X1510535D01*
G02Y1579684I0J1502D01*
G37*
G36*
G01X1570835Y1591596D02*
X1574235D01*
G02Y1588592I0J-1502D01*
G01X1570835D01*
G02Y1591596I0J1502D01*
G37*
G36*
G01X273317D02*
X276717D01*
G02Y1588592I0J-1502D01*
G01X273317D01*
G02Y1591596I0J1502D01*
G37*
G36*
G01Y1579684D02*
X276717D01*
G02Y1576680I0J-1502D01*
G01X273317D01*
G02Y1579684I0J1502D01*
G37*
G36*
G01X1491715Y1603882D02*
X1495115D01*
G02Y1600878I0J-1502D01*
G01X1491715D01*
G02Y1603882I0J1502D01*
G37*
G36*
G01Y1615794D02*
X1495115D01*
G02Y1612790I0J-1502D01*
G01X1491715D01*
G02Y1615794I0J1502D01*
G37*
G36*
G01X1631135Y1579684D02*
X1634535D01*
G02Y1576680I0J-1502D01*
G01X1631135D01*
G02Y1579684I0J1502D01*
G37*
G36*
G01X213017Y1591596D02*
X216417D01*
G02Y1588592I0J-1502D01*
G01X213017D01*
G02Y1591596I0J1502D01*
G37*
G36*
G01X188897Y1579684D02*
X192297D01*
G02Y1576680I0J-1502D01*
G01X188897D01*
G02Y1579684I0J1502D01*
G37*
G36*
G01X1503775Y1603882D02*
X1507175D01*
G02Y1600878I0J-1502D01*
G01X1503775D01*
G02Y1603882I0J1502D01*
G37*
G36*
G01X200957Y1579684D02*
X204357D01*
G02Y1576680I0J-1502D01*
G01X200957D01*
G02Y1579684I0J1502D01*
G37*
G36*
G01X605711D02*
X609111D01*
G02Y1576680I0J-1502D01*
G01X605711D01*
G02Y1579684I0J1502D01*
G37*
G36*
G01X1479655Y1603882D02*
X1483055D01*
G02Y1600878I0J-1502D01*
G01X1479655D01*
G02Y1603882I0J1502D01*
G37*
G36*
G01Y1615794D02*
X1483055D01*
G02Y1612790I0J-1502D01*
G01X1479655D01*
G02Y1615794I0J1502D01*
G37*
G36*
G01X249197Y1579684D02*
X252597D01*
G02Y1576680I0J-1502D01*
G01X249197D01*
G02Y1579684I0J1502D01*
G37*
G36*
G01X1467595Y1615794D02*
X1470995D01*
G02Y1612790I0J-1502D01*
G01X1467595D01*
G02Y1615794I0J1502D01*
G37*
G36*
G01Y1603882D02*
X1470995D01*
G02Y1600878I0J-1502D01*
G01X1467595D01*
G02Y1603882I0J1502D01*
G37*
G36*
G01X1558775Y1591596D02*
X1562175D01*
G02Y1588592I0J-1502D01*
G01X1558775D01*
G02Y1591596I0J1502D01*
G37*
G36*
G01X1643195Y1579684D02*
X1646595D01*
G02Y1576680I0J-1502D01*
G01X1643195D01*
G02Y1579684I0J1502D01*
G37*
G36*
G01X188897Y1591596D02*
X192297D01*
G02Y1588592I0J-1502D01*
G01X188897D01*
G02Y1591596I0J1502D01*
G37*
G36*
G01X1607015D02*
X1610415D01*
G02Y1588592I0J-1502D01*
G01X1607015D01*
G02Y1591596I0J1502D01*
G37*
G36*
G01X1582895D02*
X1586295D01*
G02Y1588592I0J-1502D01*
G01X1582895D01*
G02Y1591596I0J1502D01*
G37*
G36*
G01X225077Y1579684D02*
X228477D01*
G02Y1576680I0J-1502D01*
G01X225077D01*
G02Y1579684I0J1502D01*
G37*
G36*
G01Y1591596D02*
X228477D01*
G02Y1588592I0J-1502D01*
G01X225077D01*
G02Y1591596I0J1502D01*
G37*
G36*
G01X218317Y1615794D02*
X221717D01*
G02Y1612790I0J-1502D01*
G01X218317D01*
G02Y1615794I0J1502D01*
G37*
G36*
G01X290677Y1603882D02*
X294077D01*
G02Y1600878I0J-1502D01*
G01X290677D01*
G02Y1603882I0J1502D01*
G37*
G36*
G01Y1615794D02*
X294077D01*
G02Y1612790I0J-1502D01*
G01X290677D01*
G02Y1615794I0J1502D01*
G37*
G36*
G01X237137Y1579684D02*
X240537D01*
G02Y1576680I0J-1502D01*
G01X237137D01*
G02Y1579684I0J1502D01*
G37*
G36*
G01X213017D02*
X216417D01*
G02Y1576680I0J-1502D01*
G01X213017D01*
G02Y1579684I0J1502D01*
G37*
G36*
G01X230377Y1603882D02*
X233777D01*
G02Y1600878I0J-1502D01*
G01X230377D01*
G02Y1603882I0J1502D01*
G37*
G36*
G01X1619075Y1591596D02*
X1622475D01*
G02Y1588592I0J-1502D01*
G01X1619075D01*
G02Y1591596I0J1502D01*
G37*
G36*
G01X242437Y1615794D02*
X245837D01*
G02Y1612790I0J-1502D01*
G01X242437D01*
G02Y1615794I0J1502D01*
G37*
G36*
G01X369797Y1579684D02*
X373197D01*
G02Y1576680I0J-1502D01*
G01X369797D01*
G02Y1579684I0J1502D01*
G37*
G36*
G01X473051Y1591596D02*
X476451D01*
G02Y1588592I0J-1502D01*
G01X473051D01*
G02Y1591596I0J1502D01*
G37*
G36*
G01Y1579684D02*
X476451D01*
G02Y1576680I0J-1502D01*
G01X473051D01*
G02Y1579684I0J1502D01*
G37*
G36*
G01X1588195Y1603882D02*
X1591595D01*
G02Y1600878I0J-1502D01*
G01X1588195D01*
G02Y1603882I0J1502D01*
G37*
G36*
G01Y1615794D02*
X1591595D01*
G02Y1612790I0J-1502D01*
G01X1588195D01*
G02Y1615794I0J1502D01*
G37*
G36*
G01X61470Y86124D02*
X64870D01*
G02Y83120I0J-1502D01*
G01X61470D01*
G02Y86124I0J1502D01*
G37*
G36*
G01X297437Y1579684D02*
X300837D01*
G02Y1576680I0J-1502D01*
G01X297437D01*
G02Y1579684I0J1502D01*
G37*
G36*
G01X350977Y1615794D02*
X354377D01*
G02Y1612790I0J-1502D01*
G01X350977D01*
G02Y1615794I0J1502D01*
G37*
G36*
G01X375097Y1603882D02*
X378497D01*
G02Y1600878I0J-1502D01*
G01X375097D01*
G02Y1603882I0J1502D01*
G37*
G36*
G01Y1615794D02*
X378497D01*
G02Y1612790I0J-1502D01*
G01X375097D01*
G02Y1615794I0J1502D01*
G37*
G36*
G01X363037Y1603882D02*
X366437D01*
G02Y1600878I0J-1502D01*
G01X363037D01*
G02Y1603882I0J1502D01*
G37*
G36*
G01X1320456Y1124651D02*
G02X1323050I1297J0D01*
G02X1322978Y1124223I-1298J-2D01*
G01X1322948Y1124137D01*
X1323755Y1122739D01*
X1323845Y1122722D01*
G02X1324900Y1121447I-243J-1275D01*
G02X1322306I-1297J0D01*
G02X1322378Y1121875I1298J2D01*
G01X1322408Y1121961D01*
X1321601Y1123359D01*
X1321511Y1123376D01*
G02X1320456Y1124651I243J1275D01*
G37*
G36*
G01X340614Y1111834D02*
G02X343210I1298J0D01*
G02X343137Y1111406I-1299J1D01*
G01X343107Y1111320D01*
X343914Y1109922D01*
X344004Y1109905D01*
G02X345060Y1108630I-242J-1275D01*
G02X342464I-1298J0D01*
G02X342537Y1109058I1299J-1D01*
G01X342567Y1109144D01*
X341760Y1110542D01*
X341670Y1110559D01*
G02X340614Y1111834I242J1275D01*
G37*
G36*
G01X349864Y1108630D02*
G02X352460I1298J0D01*
G01Y1108628D01*
G02X352387Y1108201I-1298J2D01*
G01X352357Y1108115D01*
X353164Y1106718D01*
X353254Y1106701D01*
G02X354308Y1105426I-244J-1275D01*
G01Y1105424D01*
G02X353011Y1104128I-1297J1D01*
G02X351714Y1105426I1J1298D01*
G02X351787Y1105855I1297J0D01*
G01X351817Y1105941D01*
X351010Y1107338D01*
X350920Y1107355D01*
G02X349864Y1108630I242J1275D01*
G37*
G36*
G01X1313541Y1122224D02*
X1315165D01*
G02X1316203Y1122744I1038J-776D01*
G02Y1120150I0J-1297D01*
G02X1315165Y1120670I0J1296D01*
G01X1313541D01*
G02X1312503Y1120150I-1038J776D01*
G02Y1122744I0J1297D01*
G02X1313541Y1122224I0J-1296D01*
G37*
G36*
G01X1497622Y873810D02*
G02X1500218I1298J0D01*
G01Y873808D01*
G02X1500145Y873381I-1298J2D01*
G01X1500115Y873295D01*
X1500921Y871898D01*
X1501011Y871881D01*
G02X1502068Y870606I-240J-1275D01*
G02X1499474I-1297J0D01*
G01Y870607D01*
G02X1499545Y871032I1297J2D01*
G01X1499575Y871118D01*
X1498768Y872518D01*
X1498678Y872535D01*
G02X1497622Y873810I242J1275D01*
G37*
G36*
G01X1336674Y883423D02*
G02X1339268I1297J0D01*
G01Y883421D01*
G02X1339196Y882994I-1298J-1D01*
G01X1339166Y882908D01*
X1339972Y881511D01*
X1340062Y881494D01*
G02X1341118Y880219I-242J-1275D01*
G02X1338522I-1298J0D01*
G02X1338595Y880647I1299J-1D01*
G01X1338625Y880733D01*
X1337819Y882131D01*
X1337729Y882148D01*
G02X1336674Y883423I243J1275D01*
G37*
G36*
G01X1316756Y1111834D02*
G02X1319352I1298J0D01*
G02X1319279Y1111406I-1299J1D01*
G01X1319249Y1111320D01*
X1320056Y1109922D01*
X1320146Y1109905D01*
G02X1321202Y1108630I-242J-1275D01*
G02X1318606I-1298J0D01*
G02X1318679Y1109058I1299J-1D01*
G01X1318709Y1109144D01*
X1317902Y1110542D01*
X1317812Y1110559D01*
G02X1316756Y1111834I242J1275D01*
G37*
G36*
G01X1505024Y886625D02*
Y886627D01*
G02X1507618I1297J0D01*
G02X1506563Y885352I-1298J0D01*
G01X1506473Y885335D01*
X1505666Y883937D01*
X1505696Y883851D01*
G02X1505768Y883423I-1226J-426D01*
G02X1503174I-1297J0D01*
G02X1504230Y884698I1298J0D01*
G01X1504320Y884715D01*
X1505126Y886112D01*
X1505096Y886198D01*
G02X1505024Y886625I1226J426D01*
G37*
G36*
G01X1505022Y873810D02*
G02X1507618I1298J0D01*
G01Y873808D01*
G02X1507545Y873381I-1298J2D01*
G01X1507515Y873295D01*
X1508321Y871898D01*
X1508411Y871881D01*
G02X1509468Y870606I-240J-1275D01*
G02X1506874I-1297J0D01*
G01Y870607D01*
G02X1506945Y871032I1297J2D01*
G01X1506975Y871118D01*
X1506168Y872518D01*
X1506078Y872535D01*
G02X1505022Y873810I242J1275D01*
G37*
G36*
G01X528880D02*
G02X531476I1298J0D01*
G01Y873808D01*
G02X531403Y873381I-1298J2D01*
G01X531373Y873295D01*
X532179Y871898D01*
X532269Y871881D01*
G02X533326Y870606I-240J-1275D01*
G02X530732I-1297J0D01*
G01Y870607D01*
G02X530803Y871032I1297J2D01*
G01X530833Y871118D01*
X530026Y872518D01*
X529936Y872535D01*
G02X528880Y873810I242J1275D01*
G37*
G36*
G01X1342222Y886625D02*
Y886627D01*
G02X1344818I1298J0D01*
G02X1343762Y885352I-1298J0D01*
G01X1343672Y885335D01*
X1342866Y883938D01*
X1342896Y883852D01*
G02X1342968Y883425I-1226J-426D01*
G01Y883423D01*
G02X1340374I-1297J0D01*
G02X1341429Y884698I1298J0D01*
G01X1341519Y884715D01*
X1342325Y886112D01*
X1342295Y886198D01*
G02X1342222Y886625I1225J429D01*
G37*
G36*
G01X350350Y1112612D02*
X351974D01*
G02X353012Y1113132I1038J-776D01*
G02Y1110536I0J-1298D01*
G02X351974Y1111056I0J1296D01*
G01X350350D01*
G02X349312Y1110536I-1038J776D01*
G02Y1113132I0J1298D01*
G02X350350Y1112612I0J-1296D01*
G37*
G36*
G01X515932Y883423D02*
G02X518526I1297J0D01*
G01Y883421D01*
G02X518454Y882994I-1298J-1D01*
G01X518424Y882908D01*
X519230Y881511D01*
X519320Y881494D01*
G02X520376Y880219I-242J-1275D01*
G02X517780I-1298J0D01*
G02X517853Y880647I1299J-1D01*
G01X517883Y880733D01*
X517077Y882131D01*
X516987Y882148D01*
G02X515932Y883423I243J1275D01*
G37*
G36*
G01X528882Y886625D02*
Y886627D01*
G02X531476I1297J0D01*
G02X530421Y885352I-1298J0D01*
G01X530331Y885335D01*
X529524Y883937D01*
X529554Y883851D01*
G02X529626Y883423I-1226J-426D01*
G02X527032I-1297J0D01*
G02X528088Y884698I1298J0D01*
G01X528178Y884715D01*
X528984Y886112D01*
X528954Y886198D01*
G02X528882Y886625I1226J426D01*
G37*
G36*
G01X1320941Y1128634D02*
X1322565D01*
G02X1323603Y1129154I1038J-776D01*
G02Y1126558I0J-1298D01*
G02X1322565Y1127078I0J1296D01*
G01X1320941D01*
G02X1319903Y1126558I-1038J776D01*
G02Y1129154I0J1298D01*
G02X1320941Y1128634I0J-1296D01*
G37*
G36*
G01X1329274Y883423D02*
G02X1331868I1297J0D01*
G01Y883421D01*
G02X1331796Y882994I-1298J-1D01*
G01X1331766Y882908D01*
X1332572Y881511D01*
X1332662Y881494D01*
G02X1333718Y880219I-242J-1275D01*
G02X1331122I-1298J0D01*
G02X1331195Y880647I1299J-1D01*
G01X1331225Y880733D01*
X1330419Y882131D01*
X1330329Y882148D01*
G02X1329274Y883423I243J1275D01*
G37*
G36*
G01X1334822Y886625D02*
Y886627D01*
G02X1337418I1298J0D01*
G02X1336362Y885352I-1298J0D01*
G01X1336272Y885335D01*
X1335466Y883938D01*
X1335496Y883852D01*
G02X1335568Y883425I-1226J-426D01*
G01Y883423D01*
G02X1332974I-1297J0D01*
G02X1334029Y884698I1298J0D01*
G01X1334119Y884715D01*
X1334925Y886112D01*
X1334895Y886198D01*
G02X1334822Y886625I1225J429D01*
G37*
G36*
G01X358680D02*
Y886627D01*
G02X361276I1298J0D01*
G02X360220Y885352I-1298J0D01*
G01X360130Y885335D01*
X359324Y883938D01*
X359354Y883852D01*
G02X359426Y883425I-1226J-426D01*
G01Y883423D01*
G02X356832I-1297J0D01*
G02X357887Y884698I1298J0D01*
G01X357977Y884715D01*
X358783Y886112D01*
X358753Y886198D01*
G02X358680Y886625I1225J429D01*
G37*
G36*
G01X1326492Y1112612D02*
X1328116D01*
G02X1329154Y1113132I1038J-776D01*
G02Y1110536I0J-1298D01*
G02X1328116Y1111056I0J1296D01*
G01X1326492D01*
G02X1325454Y1110536I-1038J776D01*
G02Y1113132I0J1298D01*
G02X1326492Y1112612I0J-1296D01*
G37*
G36*
G01X366080Y886625D02*
Y886627D01*
G02X368676I1298J0D01*
G02X367620Y885352I-1298J0D01*
G01X367530Y885335D01*
X366724Y883938D01*
X366754Y883852D01*
G02X366826Y883425I-1226J-426D01*
G01Y883423D01*
G02X364232I-1297J0D01*
G02X365287Y884698I1298J0D01*
G01X365377Y884715D01*
X366183Y886112D01*
X366153Y886198D01*
G02X366080Y886625I1225J429D01*
G37*
G36*
G01X1319091Y1106204D02*
X1320715D01*
G02X1321753Y1106724I1038J-776D01*
G02Y1104128I0J-1298D01*
G02X1320715Y1104648I0J1296D01*
G01X1319091D01*
G02X1318053Y1104128I-1038J776D01*
G02Y1106724I0J1298D01*
G02X1319091Y1106204I0J-1296D01*
G37*
G36*
G01X353132Y883423D02*
G02X355726I1297J0D01*
G01Y883421D01*
G02X355654Y882994I-1298J-1D01*
G01X355624Y882908D01*
X356430Y881511D01*
X356520Y881494D01*
G02X357576Y880219I-242J-1275D01*
G02X354980I-1298J0D01*
G02X355053Y880647I1299J-1D01*
G01X355083Y880733D01*
X354277Y882131D01*
X354187Y882148D01*
G02X353132Y883423I243J1275D01*
G37*
G36*
G01X1499474D02*
G02X1502068I1297J0D01*
G01Y883421D01*
G02X1501996Y882994I-1298J-1D01*
G01X1501966Y882908D01*
X1502772Y881511D01*
X1502862Y881494D01*
G02X1503918Y880219I-242J-1275D01*
G02X1501324I-1297J0D01*
G01Y880221D01*
G02X1501396Y880646I1297J-1D01*
G01X1501426Y880732D01*
X1500619Y882131D01*
X1500529Y882148D01*
G02X1499474Y883423I243J1275D01*
G37*
G36*
G01X337399Y1122224D02*
X339023D01*
G02X340061Y1122744I1038J-776D01*
G02Y1120150I0J-1297D01*
G02X339023Y1120670I0J1296D01*
G01X337399D01*
G02X336361Y1120150I-1038J776D01*
G02Y1122744I0J1297D01*
G02X337399Y1122224I0J-1296D01*
G37*
G36*
G01X344799Y1128634D02*
X346423D01*
G02X347461Y1129154I1038J-776D01*
G02Y1126558I0J-1298D01*
G02X346423Y1127078I0J1296D01*
G01X344799D01*
G02X343761Y1126558I-1038J776D01*
G02Y1129154I0J1298D01*
G02X344799Y1128634I0J-1296D01*
G37*
G36*
G01X523332Y883423D02*
G02X525926I1297J0D01*
G01Y883421D01*
G02X525854Y882994I-1298J-1D01*
G01X525824Y882908D01*
X526630Y881511D01*
X526720Y881494D01*
G02X527776Y880219I-242J-1275D01*
G02X525182I-1297J0D01*
G01Y880221D01*
G02X525254Y880646I1297J-1D01*
G01X525284Y880732D01*
X524477Y882131D01*
X524387Y882148D01*
G02X523332Y883423I243J1275D01*
G37*
G36*
G01X357264Y1115039D02*
G02X359858I1297J0D01*
G01Y1115037D01*
G02X359786Y1114610I-1298J-1D01*
G01X359756Y1114524D01*
X360563Y1113126D01*
X360653Y1113109D01*
G02X361710Y1111834I-240J-1275D01*
G02X359114I-1298J0D01*
G02X359187Y1112262I1299J-1D01*
G01X359217Y1112348D01*
X358409Y1113747D01*
X358319Y1113764D01*
G02X357264Y1115039I243J1275D01*
G37*
G36*
G01X1340806Y1108630D02*
G02X1343400I1297J0D01*
G02X1342345Y1107355I-1298J0D01*
G01X1342255Y1107338D01*
X1341448Y1105941D01*
X1341478Y1105855D01*
G02X1341551Y1105426I-1224J-429D01*
G01Y1105424D01*
G02X1340254Y1104128I-1297J1D01*
G02X1338956Y1105426I0J1298D01*
G02X1340011Y1106701I1298J0D01*
G01X1340101Y1106718D01*
X1340908Y1108116D01*
X1340878Y1108202D01*
G02X1340806Y1108630I1226J426D01*
G37*
G36*
G01X1326006D02*
G02X1328602I1298J0D01*
G01Y1108628D01*
G02X1328529Y1108201I-1298J2D01*
G01X1328499Y1108115D01*
X1329306Y1106718D01*
X1329396Y1106701D01*
G02X1330450Y1105426I-244J-1275D01*
G01Y1105424D01*
G02X1329153Y1104128I-1297J1D01*
G02X1327856Y1105426I1J1298D01*
G02X1327929Y1105855I1297J0D01*
G01X1327959Y1105941D01*
X1327152Y1107338D01*
X1327062Y1107355D01*
G02X1326006Y1108630I242J1275D01*
G37*
G36*
G01X1330101Y541552D02*
X1333143D01*
G02Y538546I0J-1503D01*
G01X1330101D01*
G02Y541552I0J1503D01*
G37*
G36*
G01X1333406Y1115039D02*
G02X1336000I1297J0D01*
G01Y1115037D01*
G02X1335928Y1114610I-1298J-1D01*
G01X1335898Y1114524D01*
X1336705Y1113126D01*
X1336795Y1113109D01*
G02X1337852Y1111834I-240J-1275D01*
G02X1335256I-1298J0D01*
G02X1335329Y1112262I1299J-1D01*
G01X1335359Y1112348D01*
X1334551Y1113747D01*
X1334461Y1113764D01*
G02X1333406Y1115039I243J1275D01*
G37*
G36*
G01X364664Y1108630D02*
G02X367258I1297J0D01*
G02X366203Y1107355I-1298J0D01*
G01X366113Y1107338D01*
X365306Y1105941D01*
X365336Y1105855D01*
G02X365409Y1105426I-1224J-429D01*
G01Y1105424D01*
G02X364112Y1104128I-1297J1D01*
G02X362814Y1105426I0J1298D01*
G02X363869Y1106701I1298J0D01*
G01X363959Y1106718D01*
X364766Y1108116D01*
X364736Y1108202D01*
G02X364664Y1108630I1226J426D01*
G37*
G36*
G01X1492074Y883423D02*
G02X1494668I1297J0D01*
G01Y883421D01*
G02X1494596Y882994I-1298J-1D01*
G01X1494566Y882908D01*
X1495372Y881511D01*
X1495462Y881494D01*
G02X1496518Y880219I-242J-1275D01*
G02X1493922I-1298J0D01*
G02X1493995Y880647I1299J-1D01*
G01X1494025Y880733D01*
X1493219Y882131D01*
X1493129Y882148D01*
G02X1492074Y883423I243J1275D01*
G37*
G36*
G01X344314Y1124651D02*
G02X346908I1297J0D01*
G02X346836Y1124223I-1298J-2D01*
G01X346806Y1124137D01*
X347613Y1122739D01*
X347703Y1122722D01*
G02X348758Y1121447I-243J-1275D01*
G02X346164I-1297J0D01*
G02X346236Y1121875I1298J2D01*
G01X346266Y1121961D01*
X345459Y1123359D01*
X345369Y1123376D01*
G02X344314Y1124651I243J1275D01*
G37*
G36*
G01X360532Y883423D02*
G02X363126I1297J0D01*
G01Y883421D01*
G02X363054Y882994I-1298J-1D01*
G01X363024Y882908D01*
X363830Y881511D01*
X363920Y881494D01*
G02X364976Y880219I-242J-1275D01*
G02X362380I-1298J0D01*
G02X362453Y880647I1299J-1D01*
G01X362483Y880733D01*
X361677Y882131D01*
X361587Y882148D01*
G02X360532Y883423I243J1275D01*
G37*
G36*
G01X1358624Y283142D02*
X1355224D01*
G02Y286146I0J1502D01*
G01X1358624D01*
G02Y283142I0J-1502D01*
G37*
G36*
G01X1348084Y278756D02*
X1344684D01*
G02Y281762I0J1503D01*
G01X1348084D01*
G02Y278756I0J-1503D01*
G37*
G36*
G01X1368524Y281242D02*
X1365124D01*
G02Y284246I0J1502D01*
G01X1368524D01*
G02Y281242I0J-1502D01*
G37*
G36*
G01X521480Y873810D02*
G02X524076I1298J0D01*
G01Y873808D01*
G02X524003Y873381I-1298J2D01*
G01X523973Y873295D01*
X524779Y871898D01*
X524869Y871881D01*
G02X525926Y870606I-240J-1275D01*
G02X523332I-1297J0D01*
G01Y870607D01*
G02X523403Y871032I1297J2D01*
G01X523433Y871118D01*
X522626Y872518D01*
X522536Y872535D01*
G02X521480Y873810I242J1275D01*
G37*
G36*
G01X1328480Y322400D02*
X1325080D01*
G02Y325404I0J1502D01*
G01X1328480D01*
G02Y322400I0J-1502D01*
G37*
G36*
G01X613970Y190254D02*
X617370D01*
G02Y187250I0J-1502D01*
G01X613970D01*
G02Y190254I0J1502D01*
G37*
G36*
G01X64571Y427304D02*
X61171D01*
G02Y430308I0J1502D01*
G01X64571D01*
G02Y427304I0J-1502D01*
G37*
G36*
G01X626640Y190254D02*
X630040D01*
G02Y187250I0J-1502D01*
G01X626640D01*
G02Y190254I0J1502D01*
G37*
G36*
G01X423180Y1601300D02*
X419780D01*
G02Y1604304I0J1502D01*
G01X423180D01*
G02Y1601300I0J-1502D01*
G37*
G36*
G01X49360Y427304D02*
X45960D01*
G02Y430308I0J1502D01*
G01X49360D01*
G02Y427304I0J-1502D01*
G37*
G36*
G01X1400985Y242432D02*
X1404385D01*
G02Y239426I0J-1503D01*
G01X1400985D01*
G02Y242432I0J1503D01*
G37*
G36*
G01X930731Y531982D02*
X933773D01*
G02Y528976I0J-1503D01*
G01X930731D01*
G02Y531982I0J1503D01*
G37*
G36*
G01X285377Y1591596D02*
X288777D01*
G02Y1588592I0J-1502D01*
G01X285377D01*
G02Y1591596I0J1502D01*
G37*
G36*
G01X229131Y49144D02*
X225731D01*
G02Y52148I0J1502D01*
G01X229131D01*
G02Y49144I0J-1502D01*
G37*
G36*
G01X284230D02*
X280830D01*
G02Y52148I0J1502D01*
G01X284230D01*
G02Y49144I0J-1502D01*
G37*
G36*
G01X1755272Y27934D02*
X1758672D01*
G02Y24928I0J-1503D01*
G01X1755272D01*
G02Y27934I0J1503D01*
G37*
G36*
G01X1530660Y101664D02*
X1534060D01*
G02Y98660I0J-1502D01*
G01X1530660D01*
G02Y101664I0J1502D01*
G37*
G36*
G01X1549308Y27934D02*
X1552708D01*
G02Y24928I0J-1503D01*
G01X1549308D01*
G02Y27934I0J1503D01*
G37*
G36*
G01X1556413Y20998D02*
X1559813D01*
G02Y17992I0J-1503D01*
G01X1556413D01*
G02Y20998I0J1503D01*
G37*
G36*
G01X1563481Y27934D02*
X1566881D01*
G02Y24928I0J-1503D01*
G01X1563481D01*
G02Y27934I0J1503D01*
G37*
G36*
G01X1570586Y20998D02*
X1573986D01*
G02Y17992I0J-1503D01*
G01X1570586D01*
G02Y20998I0J1503D01*
G37*
G36*
G01X1577654Y27934D02*
X1581054D01*
G02Y24928I0J-1503D01*
G01X1577654D01*
G02Y27934I0J1503D01*
G37*
G36*
G01X1584759Y20998D02*
X1588159D01*
G02Y17992I0J-1503D01*
G01X1584759D01*
G02Y20998I0J1503D01*
G37*
G36*
G01X1591828Y27934D02*
X1595228D01*
G02Y24928I0J-1503D01*
G01X1591828D01*
G02Y27934I0J1503D01*
G37*
G36*
G01X1598933Y20998D02*
X1602333D01*
G02Y17992I0J-1503D01*
G01X1598933D01*
G02Y20998I0J1503D01*
G37*
G36*
G01X1627694Y27934D02*
X1631094D01*
G02Y24928I0J-1503D01*
G01X1627694D01*
G02Y27934I0J1503D01*
G37*
G36*
G01X1634799Y20998D02*
X1638199D01*
G02Y17992I0J-1503D01*
G01X1634799D01*
G02Y20998I0J1503D01*
G37*
G36*
G01X218667Y21040D02*
X222067D01*
G02Y18036I0J-1502D01*
G01X218667D01*
G02Y21040I0J1502D01*
G37*
G36*
G01X211562Y27976D02*
X214962D01*
G02Y24972I0J-1502D01*
G01X211562D01*
G02Y27976I0J1502D01*
G37*
G36*
G01X204494Y21040D02*
X207894D01*
G02Y18036I0J-1502D01*
G01X204494D01*
G02Y21040I0J1502D01*
G37*
G36*
G01X197389Y27976D02*
X200789D01*
G02Y24972I0J-1502D01*
G01X197389D01*
G02Y27976I0J1502D01*
G37*
G36*
G01X167428D02*
X170828D01*
G02Y24972I0J-1502D01*
G01X167428D01*
G02Y27976I0J1502D01*
G37*
G36*
G01X174533Y21040D02*
X177933D01*
G02Y18036I0J-1502D01*
G01X174533D01*
G02Y21040I0J1502D01*
G37*
G36*
G01X153255Y27976D02*
X156655D01*
G02Y24972I0J-1502D01*
G01X153255D01*
G02Y27976I0J1502D01*
G37*
G36*
G01X160360Y21040D02*
X163760D01*
G02Y18036I0J-1502D01*
G01X160360D01*
G02Y21040I0J1502D01*
G37*
G36*
G01X124494D02*
X127894D01*
G02Y18036I0J-1502D01*
G01X124494D01*
G02Y21040I0J1502D01*
G37*
G36*
G01X117389Y27976D02*
X120789D01*
G02Y24972I0J-1502D01*
G01X117389D01*
G02Y27976I0J1502D01*
G37*
G36*
G01X103215D02*
X106615D01*
G02Y24972I0J-1502D01*
G01X103215D01*
G02Y27976I0J1502D01*
G37*
G36*
G01X110320Y21040D02*
X113720D01*
G02Y18036I0J-1502D01*
G01X110320D01*
G02Y21040I0J1502D01*
G37*
G36*
G01X89042Y27976D02*
X92442D01*
G02Y24972I0J-1502D01*
G01X89042D01*
G02Y27976I0J1502D01*
G37*
G36*
G01X96147Y21040D02*
X99547D01*
G02Y18036I0J-1502D01*
G01X96147D01*
G02Y21040I0J1502D01*
G37*
G36*
G01X74869Y27976D02*
X78269D01*
G02Y24972I0J-1502D01*
G01X74869D01*
G02Y27976I0J1502D01*
G37*
G36*
G01X81974Y21040D02*
X85374D01*
G02Y18036I0J-1502D01*
G01X81974D01*
G02Y21040I0J1502D01*
G37*
G36*
G01X1641867Y27934D02*
X1645267D01*
G02Y24928I0J-1503D01*
G01X1641867D01*
G02Y27934I0J1503D01*
G37*
G36*
G01X1648972Y20998D02*
X1652372D01*
G02Y17992I0J-1503D01*
G01X1648972D01*
G02Y20998I0J1503D01*
G37*
G36*
G01X1671828Y27934D02*
X1675228D01*
G02Y24928I0J-1503D01*
G01X1671828D01*
G02Y27934I0J1503D01*
G37*
G36*
G01X1678933Y20998D02*
X1682333D01*
G02Y17992I0J-1503D01*
G01X1678933D01*
G02Y20998I0J1503D01*
G37*
G36*
G01X1686001Y27934D02*
X1689401D01*
G02Y24928I0J-1503D01*
G01X1686001D01*
G02Y27934I0J1503D01*
G37*
G36*
G01X1693106Y20998D02*
X1696506D01*
G02Y17992I0J-1503D01*
G01X1693106D01*
G02Y20998I0J1503D01*
G37*
G36*
G01X1700217Y27962D02*
X1703617D01*
G02Y24956I0J-1503D01*
G01X1700217D01*
G02Y27962I0J1503D01*
G37*
G36*
G01X1700170Y52152D02*
X1703570D01*
G02Y49146I0J-1503D01*
G01X1700170D01*
G02Y52152I0J1503D01*
G37*
G36*
G01X670612Y48766D02*
X674012D01*
G02Y45762I0J-1502D01*
G01X670612D01*
G02Y48766I0J1502D01*
G37*
G36*
G01X284233Y24972D02*
X280833D01*
G02Y27976I0J1502D01*
G01X284233D01*
G02Y24972I0J-1502D01*
G37*
G36*
G01X1307442Y305496D02*
X1304042D01*
G02Y308500I0J1502D01*
G01X1307442D01*
G02Y305496I0J-1502D01*
G37*
G36*
G01X1382972Y1603882D02*
X1386372D01*
G02Y1600878I0J-1502D01*
G01X1382972D01*
G02Y1603882I0J1502D01*
G37*
G36*
G01Y1615794D02*
X1386372D01*
G02Y1612790I0J-1502D01*
G01X1382972D01*
G02Y1615794I0J1502D01*
G37*
G36*
G01X229135Y24972D02*
X225735D01*
G02Y27976I0J1502D01*
G01X229135D01*
G02Y24972I0J-1502D01*
G37*
G36*
G01X350977Y1603882D02*
X354377D01*
G02Y1600878I0J-1502D01*
G01X350977D01*
G02Y1603882I0J1502D01*
G37*
G36*
G01X342949Y1106204D02*
X344573D01*
G02X345611Y1106724I1038J-776D01*
G02Y1104128I0J-1298D01*
G02X344573Y1104648I0J1296D01*
G01X342949D01*
G02X341911Y1104128I-1038J776D01*
G02Y1106724I0J1298D01*
G02X342949Y1106204I0J-1296D01*
G37*
G36*
G01X1307042Y291134D02*
X1303642D01*
G02Y294138I0J1502D01*
G01X1307042D01*
G02Y291134I0J-1502D01*
G37*
G36*
G01X405990Y1617450D02*
X402590D01*
G02Y1620454I0J1502D01*
G01X405990D01*
G02Y1617450I0J-1502D01*
G37*
G36*
G01X441740Y1650764D02*
X438340D01*
G02Y1653768I0J1502D01*
G01X441740D01*
G02Y1650764I0J-1502D01*
G37*
G36*
G01X49212Y450100D02*
X45812D01*
G02Y453104I0J1502D01*
G01X49212D01*
G02Y450100I0J-1502D01*
G37*
G36*
G01X1418630Y221520D02*
X1422030D01*
G02Y218516I0J-1502D01*
G01X1418630D01*
G02Y221520I0J1502D01*
G37*
G36*
G01X1407420D02*
X1410820D01*
G02Y218516I0J-1502D01*
G01X1407420D01*
G02Y221520I0J1502D01*
G37*
G36*
G01X1432660D02*
X1436060D01*
G02Y218516I0J-1502D01*
G01X1432660D01*
G02Y221520I0J1502D01*
G37*
G36*
G01X862930Y71574D02*
X866330D01*
G02Y68570I0J-1502D01*
G01X862930D01*
G02Y71574I0J1502D01*
G37*
G36*
G01X1348824Y327478D02*
X1345424D01*
G02Y330484I0J1503D01*
G01X1348824D01*
G02Y327478I0J-1503D01*
G37*
G36*
G01X1341431Y321190D02*
X1338031D01*
G02Y324196I0J1503D01*
G01X1341431D01*
G02Y321190I0J-1503D01*
G37*
G36*
G01X1335145Y331114D02*
X1331745D01*
G02Y334118I0J1502D01*
G01X1335145D01*
G02Y331114I0J-1502D01*
G37*
G36*
G01X1319618Y316570D02*
X1316218D01*
G02Y319576I0J1503D01*
G01X1319618D01*
G02Y316570I0J-1503D01*
G37*
G36*
G01X1311077Y321494D02*
X1307677D01*
G02Y324498I0J1502D01*
G01X1311077D01*
G02Y321494I0J-1502D01*
G37*
G36*
G01X1380602Y199170D02*
X1384002D01*
G02Y196166I0J-1502D01*
G01X1380602D01*
G02Y199170I0J1502D01*
G37*
G36*
G01X1398006D02*
X1401406D01*
G02Y196166I0J-1502D01*
G01X1398006D01*
G02Y199170I0J1502D01*
G37*
G36*
G01X1373591Y177932D02*
X1376991D01*
G02Y174928I0J-1502D01*
G01X1373591D01*
G02Y177932I0J1502D01*
G37*
G36*
G01X1169820Y637554D02*
X1173220D01*
G02Y634550I0J-1502D01*
G01X1169820D01*
G02Y637554I0J1502D01*
G37*
G36*
G01X519764Y41830D02*
X523164D01*
G02Y38826I0J-1502D01*
G01X519764D01*
G02Y41830I0J1502D01*
G37*
G36*
G01X732793Y72938D02*
X736193D01*
G02Y69934I0J-1502D01*
G01X732793D01*
G02Y72938I0J1502D01*
G37*
G36*
G01X1161860Y643614D02*
X1165260D01*
G02Y640610I0J-1502D01*
G01X1161860D01*
G02Y643614I0J1502D01*
G37*
G36*
G01X663543Y44830D02*
X666943D01*
G02Y41826I0J-1502D01*
G01X663543D01*
G02Y44830I0J1502D01*
G37*
G36*
G01X656439Y48766D02*
X659839D01*
G02Y45762I0J-1502D01*
G01X656439D01*
G02Y48766I0J1502D01*
G37*
G36*
G01X562771Y1603882D02*
X566171D01*
G02Y1600878I0J-1502D01*
G01X562771D01*
G02Y1603882I0J1502D01*
G37*
G36*
G01X538651D02*
X542051D01*
G02Y1600878I0J-1502D01*
G01X538651D01*
G02Y1603882I0J1502D01*
G37*
G36*
G01X1406970Y140244D02*
X1410370D01*
G02Y137240I0J-1502D01*
G01X1406970D01*
G02Y140244I0J1502D01*
G37*
G36*
G01X1323303Y297674D02*
X1319903D01*
G02Y300678I0J1502D01*
G01X1323303D01*
G02Y297674I0J-1502D01*
G37*
G36*
G01X1361771Y330772D02*
X1358371D01*
G02Y333778I0J1503D01*
G01X1361771D01*
G02Y330772I0J-1503D01*
G37*
G36*
G01X555175Y72938D02*
X558575D01*
G02Y69934I0J-1502D01*
G01X555175D01*
G02Y72938I0J1502D01*
G37*
G36*
G01X541002D02*
X544402D01*
G02Y69934I0J-1502D01*
G01X541002D01*
G02Y72938I0J1502D01*
G37*
G36*
G01X519742D02*
X523142D01*
G02Y69934I0J-1502D01*
G01X519742D01*
G02Y72938I0J1502D01*
G37*
G36*
G01X533915Y61324D02*
X537315D01*
G02Y58320I0J-1502D01*
G01X533915D01*
G02Y61324I0J1502D01*
G37*
G36*
G01X1294500Y298190D02*
X1291100D01*
G02Y301194I0J1502D01*
G01X1294500D01*
G02Y298190I0J-1502D01*
G37*
G36*
G01X1404829Y185766D02*
X1408229D01*
G02Y182760I0J-1503D01*
G01X1404829D01*
G02Y185766I0J1503D01*
G37*
G36*
G01X538651Y1615794D02*
X542051D01*
G02Y1612790I0J-1502D01*
G01X538651D01*
G02Y1615794I0J1502D01*
G37*
G36*
G01X526591Y1603882D02*
X529991D01*
G02Y1600878I0J-1502D01*
G01X526591D01*
G02Y1603882I0J1502D01*
G37*
G36*
G01X514531D02*
X517931D01*
G02Y1600878I0J-1502D01*
G01X514531D01*
G02Y1603882I0J1502D01*
G37*
G36*
G01X526591Y1615794D02*
X529991D01*
G02Y1612790I0J-1502D01*
G01X526591D01*
G02Y1615794I0J1502D01*
G37*
G36*
G01X514531D02*
X517931D01*
G02Y1612790I0J-1502D01*
G01X514531D01*
G02Y1615794I0J1502D01*
G37*
G36*
G01X490411Y1603882D02*
X493811D01*
G02Y1600878I0J-1502D01*
G01X490411D01*
G02Y1603882I0J1502D01*
G37*
G36*
G01X478351Y1615794D02*
X481751D01*
G02Y1612790I0J-1502D01*
G01X478351D01*
G02Y1615794I0J1502D01*
G37*
G36*
G01X502471D02*
X505871D01*
G02Y1612790I0J-1502D01*
G01X502471D01*
G02Y1615794I0J1502D01*
G37*
G36*
G01X478351Y1603882D02*
X481751D01*
G02Y1600878I0J-1502D01*
G01X478351D01*
G02Y1603882I0J1502D01*
G37*
G36*
G01X1412284Y173198D02*
X1415684D01*
G02Y170194I0J-1502D01*
G01X1412284D01*
G02Y173198I0J1502D01*
G37*
G36*
G01X598951Y1603882D02*
X602351D01*
G02Y1600878I0J-1502D01*
G01X598951D01*
G02Y1603882I0J1502D01*
G37*
G36*
G01Y1615794D02*
X602351D01*
G02Y1612790I0J-1502D01*
G01X598951D01*
G02Y1615794I0J1502D01*
G37*
G36*
G01X586891Y1603882D02*
X590291D01*
G02Y1600878I0J-1502D01*
G01X586891D01*
G02Y1603882I0J1502D01*
G37*
G36*
G01X647191D02*
X650591D01*
G02Y1600878I0J-1502D01*
G01X647191D01*
G02Y1603882I0J1502D01*
G37*
G36*
G01X635131Y1615794D02*
X638531D01*
G02Y1612790I0J-1502D01*
G01X635131D01*
G02Y1615794I0J1502D01*
G37*
G36*
G01X647191D02*
X650591D01*
G02Y1612790I0J-1502D01*
G01X647191D01*
G02Y1615794I0J1502D01*
G37*
G36*
G01X623071D02*
X626471D01*
G02Y1612790I0J-1502D01*
G01X623071D01*
G02Y1615794I0J1502D01*
G37*
G36*
G01X1355200Y336340D02*
X1351800D01*
G02Y339346I0J1503D01*
G01X1355200D01*
G02Y336340I0J-1503D01*
G37*
G36*
G01X1328814Y292054D02*
X1325414D01*
G02Y295058I0J1502D01*
G01X1328814D01*
G02Y292054I0J-1502D01*
G37*
G36*
G01X1340161Y291902D02*
X1336761D01*
G02Y294906I0J1502D01*
G01X1340161D01*
G02Y291902I0J-1502D01*
G37*
G36*
G01X1413950Y185766D02*
X1417350D01*
G02Y182760I0J-1503D01*
G01X1413950D01*
G02Y185766I0J1503D01*
G37*
G36*
G01X1423110D02*
X1426510D01*
G02Y182760I0J-1503D01*
G01X1423110D01*
G02Y185766I0J1503D01*
G37*
G36*
G01X1401341Y178662D02*
X1404741D01*
G02Y175656I0J-1503D01*
G01X1401341D01*
G02Y178662I0J1503D01*
G37*
G36*
G01X1403778Y173186D02*
X1407178D01*
G02Y170182I0J-1502D01*
G01X1403778D01*
G02Y173186I0J1502D01*
G37*
G36*
G01X1389256Y199170D02*
X1392656D01*
G02Y196166I0J-1502D01*
G01X1389256D01*
G02Y199170I0J1502D01*
G37*
G36*
G01X550711Y1603882D02*
X554111D01*
G02Y1600878I0J-1502D01*
G01X550711D01*
G02Y1603882I0J1502D01*
G37*
G36*
G01X502471D02*
X505871D01*
G02Y1600878I0J-1502D01*
G01X502471D01*
G02Y1603882I0J1502D01*
G37*
G36*
G01X490411Y1615794D02*
X493811D01*
G02Y1612790I0J-1502D01*
G01X490411D01*
G02Y1615794I0J1502D01*
G37*
G36*
G01X987440Y432696D02*
X990840D01*
G02Y429690I0J-1503D01*
G01X987440D01*
G02Y432696I0J1503D01*
G37*
G36*
G01X1471460Y631900D02*
X1468060D01*
G02Y634904I0J1502D01*
G01X1471460D01*
G02Y631900I0J-1502D01*
G37*
G36*
G01X934047Y459364D02*
X937447D01*
G02Y456360I0J-1502D01*
G01X934047D01*
G02Y459364I0J1502D01*
G37*
G36*
G01X942047Y464514D02*
X945447D01*
G02Y461510I0J-1502D01*
G01X942047D01*
G02Y464514I0J1502D01*
G37*
G36*
G01X550711Y1615794D02*
X554111D01*
G02Y1612790I0J-1502D01*
G01X550711D01*
G02Y1615794I0J1502D01*
G37*
G36*
G01X635131Y1603882D02*
X638531D01*
G02Y1600878I0J-1502D01*
G01X635131D01*
G02Y1603882I0J1502D01*
G37*
G36*
G01X909584Y459638D02*
X912984D01*
G02Y456632I0J-1503D01*
G01X909584D01*
G02Y459638I0J1503D01*
G37*
G36*
G01X913394Y523164D02*
X916794D01*
G02Y520160I0J-1502D01*
G01X913394D01*
G02Y523164I0J1502D01*
G37*
G36*
G01X574831Y1603882D02*
X578231D01*
G02Y1600878I0J-1502D01*
G01X574831D01*
G02Y1603882I0J1502D01*
G37*
G36*
G01X659251D02*
X662651D01*
G02Y1600878I0J-1502D01*
G01X659251D01*
G02Y1603882I0J1502D01*
G37*
G36*
G01X1153370Y639694D02*
X1156770D01*
G02Y636690I0J-1502D01*
G01X1153370D01*
G02Y639694I0J1502D01*
G37*
G36*
G01X1406786Y199170D02*
X1410186D01*
G02Y196166I0J-1502D01*
G01X1406786D01*
G02Y199170I0J1502D01*
G37*
G36*
G01X611011Y1615794D02*
X614411D01*
G02Y1612790I0J-1502D01*
G01X611011D01*
G02Y1615794I0J1502D01*
G37*
G36*
G01X1312136Y283446D02*
X1308736D01*
G02Y286450I0J1502D01*
G01X1312136D01*
G02Y283446I0J-1502D01*
G37*
G36*
G01X611011Y1603882D02*
X614411D01*
G02Y1600878I0J-1502D01*
G01X611011D01*
G02Y1603882I0J1502D01*
G37*
G36*
G01X586891Y1615794D02*
X590291D01*
G02Y1612790I0J-1502D01*
G01X586891D01*
G02Y1615794I0J1502D01*
G37*
G36*
G01X659251D02*
X662651D01*
G02Y1612790I0J-1502D01*
G01X659251D01*
G02Y1615794I0J1502D01*
G37*
G36*
G01X574831D02*
X578231D01*
G02Y1612790I0J-1502D01*
G01X574831D01*
G02Y1615794I0J1502D01*
G37*
G36*
G01X1183360Y643564D02*
X1186760D01*
G02Y640560I0J-1502D01*
G01X1183360D01*
G02Y643564I0J1502D01*
G37*
G36*
G01X562771Y1615794D02*
X566171D01*
G02Y1612790I0J-1502D01*
G01X562771D01*
G02Y1615794I0J1502D01*
G37*
G36*
G01X901230Y533114D02*
X904630D01*
G02Y530110I0J-1502D01*
G01X901230D01*
G02Y533114I0J1502D01*
G37*
G36*
G01X954390Y529098D02*
X957790D01*
G02Y526094I0J-1502D01*
G01X954390D01*
G02Y529098I0J1502D01*
G37*
G36*
G01X963930Y534864D02*
X967330D01*
G02Y531860I0J-1502D01*
G01X963930D01*
G02Y534864I0J1502D01*
G37*
G36*
G01X548070Y80874D02*
X551470D01*
G02Y77870I0J-1502D01*
G01X548070D01*
G02Y80874I0J1502D01*
G37*
G36*
G01X623071Y1603882D02*
X626471D01*
G02Y1600878I0J-1502D01*
G01X623071D01*
G02Y1603882I0J1502D01*
G37*
G36*
G01X888130Y534114D02*
X891530D01*
G02Y531110I0J-1502D01*
G01X888130D01*
G02Y534114I0J1502D01*
G37*
G36*
G01X297437Y1591596D02*
X300837D01*
G02Y1588592I0J-1502D01*
G01X297437D01*
G02Y1591596I0J1502D01*
G37*
G36*
G01X237137D02*
X240537D01*
G02Y1588592I0J-1502D01*
G01X237137D01*
G02Y1591596I0J1502D01*
G37*
G36*
G01X937340Y309612D02*
X920138D01*
G02X937340I8601J12041D01*
G37*
G36*
G01X921047Y464514D02*
X924447D01*
G02Y461510I0J-1502D01*
G01X921047D01*
G02Y464514I0J1502D01*
G37*
G36*
G01X371587Y173422D02*
X365287D01*
G02Y197050I0J11814D01*
G01X371587D01*
G02Y173422I0J-11814D01*
G37*
G36*
G01X253477D02*
X247176D01*
G02X247175Y197050I0J11814D01*
G01X253476D01*
G02X253477Y173422I0J-11814D01*
G37*
G36*
G01X1012861Y434390D02*
X1016261D01*
G02Y431386I0J-1502D01*
G01X1012861D01*
G02Y434390I0J1502D01*
G37*
G36*
G01X50772Y120610D02*
X55372Y124913D01*
G02X66448Y113076I5538J-5919D01*
G01X61848Y108773D01*
G02X50772Y120610I-5538J5918D01*
G37*
G36*
G01X62587Y23395D02*
G02X58024Y17311I-2280J-3043D01*
G02X62587Y23395I2279J3044D01*
G37*
G36*
G01X443227Y845968D02*
G02X444266Y845448I0J-1298D01*
G01X445888D01*
G02X446927Y845968I1039J-778D01*
G02Y843374I0J-1297D01*
G02X445888Y843894I0J1298D01*
G01X444266D01*
G02X443227Y843374I-1039J778D01*
G02Y845968I0J1297D01*
G37*
G36*
G01X356830Y844971D02*
G02X359424I1297J0D01*
G02X358362Y843695I-1298J0D01*
G01X358267Y843677D01*
X357426Y842082D01*
X357465Y841994D01*
G02X357576Y841467I-1186J-525D01*
G02X354982I-1297J0D01*
G02X356044Y842743I1298J0D01*
G01X356139Y842761D01*
X356980Y844356D01*
X356941Y844444D01*
G02X356830Y844971I1186J525D01*
G37*
G36*
G01X364230D02*
G02X366824I1297J0D01*
G02X365762Y843695I-1298J0D01*
G01X365667Y843677D01*
X364826Y842082D01*
X364865Y841994D01*
G02X364976Y841467I-1186J-525D01*
G02X362382I-1297J0D01*
G02X363444Y842743I1298J0D01*
G01X363539Y842761D01*
X364380Y844356D01*
X364341Y844444D01*
G02X364230Y844971I1186J525D01*
G37*
G36*
G01X371630D02*
G02X374224I1297J0D01*
G02X373162Y843695I-1298J0D01*
G01X373067Y843677D01*
X372226Y842082D01*
X372265Y841994D01*
G02X372376Y841467I-1186J-525D01*
G02X369782I-1297J0D01*
G02X370844Y842743I1298J0D01*
G01X370939Y842761D01*
X371780Y844356D01*
X371741Y844444D01*
G02X371630Y844971I1186J525D01*
G37*
G36*
G01X379030D02*
G02X381624I1297J0D01*
G02X380562Y843695I-1298J0D01*
G01X380467Y843677D01*
X379626Y842082D01*
X379665Y841994D01*
G02X379776Y841467I-1186J-525D01*
G02X377182I-1297J0D01*
G02X378244Y842743I1298J0D01*
G01X378339Y842761D01*
X379180Y844356D01*
X379141Y844444D01*
G02X379030Y844971I1186J525D01*
G37*
G36*
G01X386430D02*
G02X389024I1297J0D01*
G02X387962Y843695I-1298J0D01*
G01X387867Y843677D01*
X387026Y842082D01*
X387065Y841994D01*
G02X387176Y841467I-1186J-525D01*
G02X384582I-1297J0D01*
G02X385644Y842743I1298J0D01*
G01X385739Y842761D01*
X386580Y844356D01*
X386541Y844444D01*
G02X386430Y844971I1186J525D01*
G37*
G36*
G01X393830D02*
G02X396424I1297J0D01*
G02X395362Y843695I-1298J0D01*
G01X395267Y843677D01*
X394426Y842082D01*
X394465Y841994D01*
G02X394576Y841467I-1186J-525D01*
G02X391982I-1297J0D01*
G02X393044Y842743I1298J0D01*
G01X393139Y842761D01*
X393980Y844356D01*
X393941Y844444D01*
G02X393830Y844971I1186J525D01*
G37*
G36*
G01X401230D02*
G02X403824I1297J0D01*
G02X402762Y843695I-1298J0D01*
G01X402667Y843677D01*
X401826Y842082D01*
X401865Y841994D01*
G02X401976Y841467I-1186J-525D01*
G02X399382I-1297J0D01*
G02X400444Y842743I1298J0D01*
G01X400539Y842761D01*
X401380Y844356D01*
X401341Y844444D01*
G02X401230Y844971I1186J525D01*
G37*
G36*
G01X408630D02*
G02X411224I1297J0D01*
G02X410162Y843695I-1298J0D01*
G01X410067Y843677D01*
X409226Y842082D01*
X409265Y841994D01*
G02X409376Y841467I-1186J-525D01*
G02X406782I-1297J0D01*
G02X407844Y842743I1298J0D01*
G01X407939Y842761D01*
X408780Y844356D01*
X408741Y844444D01*
G02X408630Y844971I1186J525D01*
G37*
G36*
G01X416030D02*
G02X418624I1297J0D01*
G02X417562Y843695I-1298J0D01*
G01X417467Y843677D01*
X416626Y842082D01*
X416665Y841994D01*
G02X416776Y841467I-1186J-525D01*
G02X414182I-1297J0D01*
G02X415244Y842743I1298J0D01*
G01X415339Y842761D01*
X416180Y844356D01*
X416141Y844444D01*
G02X416030Y844971I1186J525D01*
G37*
G36*
G01X423430D02*
G02X426024I1297J0D01*
G02X424962Y843695I-1298J0D01*
G01X424867Y843677D01*
X424026Y842082D01*
X424065Y841994D01*
G02X424176Y841467I-1186J-525D01*
G02X421582I-1297J0D01*
G02X422644Y842743I1298J0D01*
G01X422739Y842761D01*
X423580Y844356D01*
X423541Y844444D01*
G02X423430Y844971I1186J525D01*
G37*
G36*
G01X453030D02*
G02X455624I1297J0D01*
G02X454562Y843695I-1298J0D01*
G01X454467Y843677D01*
X453626Y842082D01*
X453665Y841994D01*
G02X453776Y841467I-1186J-525D01*
G02X451182I-1297J0D01*
G02X452244Y842743I1298J0D01*
G01X452339Y842761D01*
X453180Y844356D01*
X453141Y844444D01*
G02X453030Y844971I1186J525D01*
G37*
G36*
G01X460430D02*
G02X463024I1297J0D01*
G02X461962Y843695I-1298J0D01*
G01X461867Y843677D01*
X461026Y842082D01*
X461065Y841994D01*
G02X461176Y841467I-1186J-525D01*
G02X458582I-1297J0D01*
G02X459644Y842743I1298J0D01*
G01X459739Y842761D01*
X460580Y844356D01*
X460541Y844444D01*
G02X460430Y844971I1186J525D01*
G37*
G36*
G01X467830D02*
G02X470424I1297J0D01*
G02X469362Y843695I-1298J0D01*
G01X469267Y843677D01*
X468426Y842082D01*
X468465Y841994D01*
G02X468576Y841467I-1186J-525D01*
G02X465982I-1297J0D01*
G02X467044Y842743I1298J0D01*
G01X467139Y842761D01*
X467980Y844356D01*
X467941Y844444D01*
G02X467830Y844971I1186J525D01*
G37*
G36*
G01X475230D02*
G02X477824I1297J0D01*
G02X476762Y843695I-1298J0D01*
G01X476667Y843677D01*
X475826Y842082D01*
X475865Y841994D01*
G02X475976Y841467I-1186J-525D01*
G02X473382I-1297J0D01*
G02X474444Y842743I1298J0D01*
G01X474539Y842761D01*
X475380Y844356D01*
X475341Y844444D01*
G02X475230Y844971I1186J525D01*
G37*
G36*
G01X482630D02*
G02X485224I1297J0D01*
G02X484162Y843695I-1298J0D01*
G01X484067Y843677D01*
X483226Y842082D01*
X483265Y841994D01*
G02X483376Y841467I-1186J-525D01*
G02X480782I-1297J0D01*
G02X481844Y842743I1298J0D01*
G01X481939Y842761D01*
X482780Y844356D01*
X482741Y844444D01*
G02X482630Y844971I1186J525D01*
G37*
G36*
G01X490030D02*
G02X492624I1297J0D01*
G02X491519Y843688I-1297J0D01*
G01X491418Y843673D01*
X490608Y842112D01*
X490651Y842023D01*
G02X490776Y841467I-1174J-556D01*
G02X488180I-1298J0D01*
G02X489315Y842754I1297J0D01*
G01X489420Y842767D01*
X490213Y844297D01*
X490168Y844389D01*
G02X490030Y844971I1158J582D01*
G37*
G36*
G01X497430D02*
G02X500024I1297J0D01*
G02X498962Y843695I-1298J0D01*
G01X498867Y843677D01*
X498025Y842081D01*
X498064Y841993D01*
G02X498176Y841467I-1186J-527D01*
G02X495580I-1298J0D01*
G02X496644Y842743I1297J0D01*
G01X496739Y842761D01*
X497580Y844356D01*
X497541Y844444D01*
G02X497430Y844971I1186J525D01*
G37*
G36*
G01X504830D02*
G02X507424I1297J0D01*
G02X506362Y843695I-1298J0D01*
G01X506267Y843677D01*
X505426Y842082D01*
X505465Y841994D01*
G02X505576Y841467I-1186J-525D01*
G02X502982I-1297J0D01*
G02X504044Y842743I1298J0D01*
G01X504139Y842761D01*
X504980Y844356D01*
X504941Y844444D01*
G02X504830Y844971I1186J525D01*
G37*
G36*
G01X512230D02*
G02X514824I1297J0D01*
G02X513762Y843695I-1298J0D01*
G01X513667Y843677D01*
X512826Y842082D01*
X512865Y841994D01*
G02X512976Y841467I-1186J-525D01*
G02X510382I-1297J0D01*
G02X511444Y842743I1298J0D01*
G01X511539Y842761D01*
X512380Y844356D01*
X512341Y844444D01*
G02X512230Y844971I1186J525D01*
G37*
G36*
G01X519630D02*
G02X522224I1297J0D01*
G02X521162Y843695I-1298J0D01*
G01X521067Y843677D01*
X520226Y842082D01*
X520265Y841994D01*
G02X520376Y841467I-1186J-525D01*
G02X517782I-1297J0D01*
G02X518844Y842743I1298J0D01*
G01X518939Y842761D01*
X519780Y844356D01*
X519741Y844444D01*
G02X519630Y844971I1186J525D01*
G37*
G36*
G01X1332972D02*
G02X1335566I1297J0D01*
G02X1334504Y843695I-1298J0D01*
G01X1334409Y843677D01*
X1333568Y842082D01*
X1333607Y841994D01*
G02X1333718Y841467I-1186J-525D01*
G02X1331124I-1297J0D01*
G02X1332186Y842743I1298J0D01*
G01X1332281Y842761D01*
X1333122Y844356D01*
X1333083Y844444D01*
G02X1332972Y844971I1186J525D01*
G37*
G36*
G01X1340372D02*
G02X1342966I1297J0D01*
G02X1341904Y843695I-1298J0D01*
G01X1341809Y843677D01*
X1340968Y842082D01*
X1341007Y841994D01*
G02X1341118Y841467I-1186J-525D01*
G02X1338524I-1297J0D01*
G02X1339586Y842743I1298J0D01*
G01X1339681Y842761D01*
X1340522Y844356D01*
X1340483Y844444D01*
G02X1340372Y844971I1186J525D01*
G37*
G36*
G01X1347772D02*
G02X1350366I1297J0D01*
G02X1349304Y843695I-1298J0D01*
G01X1349209Y843677D01*
X1348368Y842082D01*
X1348407Y841994D01*
G02X1348518Y841467I-1186J-525D01*
G02X1345924I-1297J0D01*
G02X1346986Y842743I1298J0D01*
G01X1347081Y842761D01*
X1347922Y844356D01*
X1347883Y844444D01*
G02X1347772Y844971I1186J525D01*
G37*
G36*
G01X1355172D02*
G02X1357766I1297J0D01*
G02X1356704Y843695I-1298J0D01*
G01X1356609Y843677D01*
X1355768Y842082D01*
X1355807Y841994D01*
G02X1355918Y841467I-1186J-525D01*
G02X1353324I-1297J0D01*
G02X1354386Y842743I1298J0D01*
G01X1354481Y842761D01*
X1355322Y844356D01*
X1355283Y844444D01*
G02X1355172Y844971I1186J525D01*
G37*
G36*
G01X1362572D02*
G02X1365166I1297J0D01*
G02X1364104Y843695I-1298J0D01*
G01X1364009Y843677D01*
X1363168Y842082D01*
X1363207Y841994D01*
G02X1363318Y841467I-1186J-525D01*
G02X1360724I-1297J0D01*
G02X1361786Y842743I1298J0D01*
G01X1361881Y842761D01*
X1362722Y844356D01*
X1362683Y844444D01*
G02X1362572Y844971I1186J525D01*
G37*
G36*
G01X1369972D02*
G02X1372566I1297J0D01*
G02X1371504Y843695I-1298J0D01*
G01X1371409Y843677D01*
X1370568Y842082D01*
X1370607Y841994D01*
G02X1370718Y841467I-1186J-525D01*
G02X1368124I-1297J0D01*
G02X1369186Y842743I1298J0D01*
G01X1369281Y842761D01*
X1370122Y844356D01*
X1370083Y844444D01*
G02X1369972Y844971I1186J525D01*
G37*
G36*
G01X1377372D02*
G02X1379966I1297J0D01*
G02X1378904Y843695I-1298J0D01*
G01X1378809Y843677D01*
X1377968Y842082D01*
X1378007Y841994D01*
G02X1378118Y841467I-1186J-525D01*
G02X1375524I-1297J0D01*
G02X1376586Y842743I1298J0D01*
G01X1376681Y842761D01*
X1377522Y844356D01*
X1377483Y844444D01*
G02X1377372Y844971I1186J525D01*
G37*
G36*
G01X1384772D02*
G02X1387366I1297J0D01*
G02X1386304Y843695I-1298J0D01*
G01X1386209Y843677D01*
X1385368Y842082D01*
X1385407Y841994D01*
G02X1385518Y841467I-1186J-525D01*
G02X1382924I-1297J0D01*
G02X1383986Y842743I1298J0D01*
G01X1384081Y842761D01*
X1384922Y844356D01*
X1384883Y844444D01*
G02X1384772Y844971I1186J525D01*
G37*
G36*
G01X1392172D02*
G02X1394766I1297J0D01*
G02X1393704Y843695I-1298J0D01*
G01X1393609Y843677D01*
X1392768Y842082D01*
X1392807Y841994D01*
G02X1392918Y841467I-1186J-525D01*
G02X1390324I-1297J0D01*
G02X1391386Y842743I1298J0D01*
G01X1391481Y842761D01*
X1392322Y844356D01*
X1392283Y844444D01*
G02X1392172Y844971I1186J525D01*
G37*
G36*
G01X1399572D02*
G02X1402166I1297J0D01*
G02X1401104Y843695I-1298J0D01*
G01X1401009Y843677D01*
X1400168Y842082D01*
X1400207Y841994D01*
G02X1400318Y841467I-1186J-525D01*
G02X1397724I-1297J0D01*
G02X1398786Y842743I1298J0D01*
G01X1398881Y842761D01*
X1399722Y844356D01*
X1399683Y844444D01*
G02X1399572Y844971I1186J525D01*
G37*
G36*
G01X351280Y848176D02*
G02X353876I1298J0D01*
G02X353803Y847747I-1297J0D01*
G01X353772Y847661D01*
X354579Y846263D01*
X354669Y846246D01*
G02X355724Y844971I-243J-1275D01*
G02X353130I-1297J0D01*
G02X353202Y845400I1297J3D01*
G01X353233Y845486D01*
X352426Y846884D01*
X352336Y846901D01*
G02X351280Y848176I242J1275D01*
G37*
G36*
G01X358680D02*
G02X361276I1298J0D01*
G02X361203Y847747I-1297J0D01*
G01X361172Y847661D01*
X361979Y846263D01*
X362069Y846246D01*
G02X363124Y844971I-243J-1275D01*
G02X360530I-1297J0D01*
G02X360602Y845400I1297J3D01*
G01X360633Y845486D01*
X359826Y846884D01*
X359736Y846901D01*
G02X358680Y848176I242J1275D01*
G37*
G36*
G01X366080D02*
G02X368676I1298J0D01*
G02X368603Y847747I-1297J0D01*
G01X368572Y847661D01*
X369379Y846263D01*
X369469Y846246D01*
G02X370524Y844971I-243J-1275D01*
G02X367930I-1297J0D01*
G02X368002Y845400I1297J3D01*
G01X368033Y845486D01*
X367226Y846884D01*
X367136Y846901D01*
G02X366080Y848176I242J1275D01*
G37*
G36*
G01X373480D02*
G02X376076I1298J0D01*
G02X376003Y847747I-1297J0D01*
G01X375972Y847661D01*
X376779Y846263D01*
X376869Y846246D01*
G02X377924Y844971I-243J-1275D01*
G02X375330I-1297J0D01*
G02X375402Y845400I1297J3D01*
G01X375433Y845486D01*
X374626Y846884D01*
X374536Y846901D01*
G02X373480Y848176I242J1275D01*
G37*
G36*
G01X380880D02*
G02X383476I1298J0D01*
G02X383403Y847747I-1297J0D01*
G01X383372Y847661D01*
X384179Y846263D01*
X384269Y846246D01*
G02X385324Y844971I-243J-1275D01*
G02X382730I-1297J0D01*
G02X382802Y845400I1297J3D01*
G01X382833Y845486D01*
X382026Y846884D01*
X381936Y846901D01*
G02X380880Y848176I242J1275D01*
G37*
G36*
G01X388280D02*
G02X390876I1298J0D01*
G02X390803Y847747I-1297J0D01*
G01X390772Y847661D01*
X391579Y846263D01*
X391669Y846246D01*
G02X392724Y844971I-243J-1275D01*
G02X390130I-1297J0D01*
G02X390202Y845400I1297J3D01*
G01X390233Y845486D01*
X389426Y846884D01*
X389336Y846901D01*
G02X388280Y848176I242J1275D01*
G37*
G36*
G01X395680D02*
G02X398276I1298J0D01*
G02X398203Y847747I-1297J0D01*
G01X398172Y847661D01*
X398979Y846263D01*
X399069Y846246D01*
G02X400124Y844971I-243J-1275D01*
G02X397530I-1297J0D01*
G02X397602Y845400I1297J3D01*
G01X397633Y845486D01*
X396826Y846884D01*
X396736Y846901D01*
G02X395680Y848176I242J1275D01*
G37*
G36*
G01X403080D02*
G02X405676I1298J0D01*
G02X405603Y847747I-1297J0D01*
G01X405572Y847661D01*
X406379Y846263D01*
X406469Y846246D01*
G02X407524Y844971I-243J-1275D01*
G02X404930I-1297J0D01*
G02X405002Y845400I1297J3D01*
G01X405033Y845486D01*
X404226Y846884D01*
X404136Y846901D01*
G02X403080Y848176I242J1275D01*
G37*
G36*
G01X410480D02*
G02X413076I1298J0D01*
G02X413003Y847747I-1297J0D01*
G01X412972Y847661D01*
X413779Y846263D01*
X413869Y846246D01*
G02X414924Y844971I-243J-1275D01*
G02X412330I-1297J0D01*
G02X412402Y845400I1297J3D01*
G01X412433Y845486D01*
X411626Y846884D01*
X411536Y846901D01*
G02X410480Y848176I242J1275D01*
G37*
G36*
G01X417880D02*
G02X420476I1298J0D01*
G02X420403Y847747I-1297J0D01*
G01X420372Y847661D01*
X421179Y846263D01*
X421269Y846246D01*
G02X422324Y844971I-243J-1275D01*
G02X419730I-1297J0D01*
G02X419802Y845400I1297J3D01*
G01X419833Y845486D01*
X419026Y846884D01*
X418936Y846901D01*
G02X417880Y848176I242J1275D01*
G37*
G36*
G01X425280D02*
G02X427876I1298J0D01*
G02X427803Y847747I-1297J0D01*
G01X427772Y847661D01*
X428579Y846263D01*
X428669Y846246D01*
G02X429724Y844971I-243J-1275D01*
G02X427130I-1297J0D01*
G02X427202Y845400I1297J3D01*
G01X427233Y845486D01*
X426426Y846884D01*
X426336Y846901D01*
G02X425280Y848176I242J1275D01*
G37*
G36*
G01X430278Y849474D02*
G02X431317Y848954I0J-1298D01*
G01X432939D01*
G02X433978Y849474I1039J-778D01*
G02Y846878I0J-1298D01*
G02X432939Y847398I0J1298D01*
G01X431317D01*
G02X430278Y846878I-1039J778D01*
G02Y849474I0J1298D01*
G37*
G36*
G01X436380Y848176D02*
G02X438976I1298J0D01*
G02X437913Y846900I-1297J0D01*
G01X437818Y846882D01*
X436976Y845286D01*
X437015Y845197D01*
G02X437126Y844673I-1186J-525D01*
G01Y844671D01*
G02X434532I-1297J0D01*
G02X435594Y845947I1298J0D01*
G01X435689Y845965D01*
X436531Y847561D01*
X436492Y847650D01*
G02X436380Y848176I1186J527D01*
G37*
G36*
G01X447480D02*
G02X450076I1298J0D01*
G02X450003Y847748I-1298J1D01*
G01X449972Y847661D01*
X450780Y846263D01*
X450870Y846246D01*
G02X451926Y844971I-242J-1275D01*
G02X449330I-1298J0D01*
G02X449403Y845399I1298J-1D01*
G01X449434Y845486D01*
X448626Y846884D01*
X448536Y846901D01*
G02X447480Y848176I242J1275D01*
G37*
G36*
G01X454880D02*
G02X457476I1298J0D01*
G02X457403Y847747I-1297J0D01*
G01X457372Y847661D01*
X458179Y846263D01*
X458269Y846246D01*
G02X459324Y844971I-243J-1275D01*
G02X456730I-1297J0D01*
G02X456802Y845400I1297J3D01*
G01X456833Y845486D01*
X456026Y846884D01*
X455936Y846901D01*
G02X454880Y848176I242J1275D01*
G37*
G36*
G01X462280D02*
G02X464876I1298J0D01*
G02X464803Y847747I-1297J0D01*
G01X464772Y847661D01*
X465579Y846263D01*
X465669Y846246D01*
G02X466724Y844971I-243J-1275D01*
G02X464130I-1297J0D01*
G02X464202Y845400I1297J3D01*
G01X464233Y845486D01*
X463426Y846884D01*
X463336Y846901D01*
G02X462280Y848176I242J1275D01*
G37*
G36*
G01X469680D02*
G02X472276I1298J0D01*
G02X472203Y847747I-1297J0D01*
G01X472172Y847661D01*
X472979Y846263D01*
X473069Y846246D01*
G02X474124Y844971I-243J-1275D01*
G02X471530I-1297J0D01*
G02X471602Y845400I1297J3D01*
G01X471633Y845486D01*
X470826Y846884D01*
X470736Y846901D01*
G02X469680Y848176I242J1275D01*
G37*
G36*
G01X477080D02*
G02X479676I1298J0D01*
G02X479603Y847747I-1297J0D01*
G01X479572Y847661D01*
X480379Y846263D01*
X480469Y846246D01*
G02X481524Y844971I-243J-1275D01*
G02X478930I-1297J0D01*
G02X479002Y845400I1297J3D01*
G01X479033Y845486D01*
X478226Y846884D01*
X478136Y846901D01*
G02X477080Y848176I242J1275D01*
G37*
G36*
G01X484480D02*
G02X487076I1298J0D01*
G02X487003Y847747I-1297J0D01*
G01X486972Y847661D01*
X487779Y846263D01*
X487869Y846246D01*
G02X488924Y844971I-243J-1275D01*
G02X486330I-1297J0D01*
G02X486402Y845400I1297J3D01*
G01X486433Y845486D01*
X485626Y846884D01*
X485536Y846901D01*
G02X484480Y848176I242J1275D01*
G37*
G36*
G01X491880D02*
G02X494476I1298J0D01*
G02X494403Y847747I-1297J0D01*
G01X494372Y847661D01*
X495179Y846263D01*
X495269Y846246D01*
G02X496324Y844971I-243J-1275D01*
G02X493730I-1297J0D01*
G02X493802Y845400I1297J3D01*
G01X493833Y845486D01*
X493026Y846884D01*
X492936Y846901D01*
G02X491880Y848176I242J1275D01*
G37*
G36*
G01X499280D02*
G02X501876I1298J0D01*
G02X501803Y847747I-1297J0D01*
G01X501772Y847661D01*
X502579Y846263D01*
X502669Y846246D01*
G02X503724Y844971I-243J-1275D01*
G02X501130I-1297J0D01*
G02X501202Y845400I1297J3D01*
G01X501233Y845486D01*
X500426Y846884D01*
X500336Y846901D01*
G02X499280Y848176I242J1275D01*
G37*
G36*
G01X506680D02*
G02X509276I1298J0D01*
G02X509203Y847747I-1297J0D01*
G01X509172Y847661D01*
X509979Y846263D01*
X510069Y846246D01*
G02X511124Y844971I-243J-1275D01*
G02X508530I-1297J0D01*
G02X508602Y845400I1297J3D01*
G01X508633Y845486D01*
X507826Y846884D01*
X507736Y846901D01*
G02X506680Y848176I242J1275D01*
G37*
G36*
G01X514080D02*
G02X516676I1298J0D01*
G02X516603Y847747I-1297J0D01*
G01X516572Y847661D01*
X517379Y846263D01*
X517469Y846246D01*
G02X518524Y844971I-243J-1275D01*
G02X515930I-1297J0D01*
G02X516002Y845400I1297J3D01*
G01X516033Y845486D01*
X515226Y846884D01*
X515136Y846901D01*
G02X514080Y848176I242J1275D01*
G37*
G36*
G01X521480D02*
G02X524076I1298J0D01*
G02X524003Y847747I-1297J0D01*
G01X523972Y847661D01*
X524779Y846263D01*
X524869Y846246D01*
G02X525924Y844971I-243J-1275D01*
G02X523330I-1297J0D01*
G02X523402Y845400I1297J3D01*
G01X523433Y845486D01*
X522626Y846884D01*
X522536Y846901D01*
G02X521480Y848176I242J1275D01*
G37*
G36*
G01X526478Y849474D02*
G02X527517Y848954I0J-1298D01*
G01X529139D01*
G02X530178Y849474I1039J-778D01*
G02Y846878I0J-1298D01*
G02X529139Y847398I0J1298D01*
G01X527517D01*
G02X526478Y846878I-1039J778D01*
G02Y849474I0J1298D01*
G37*
G36*
G01X532580Y848176D02*
G02X535176I1298J0D01*
G02X534168Y846911I-1298J0D01*
G01X534079Y846891D01*
X533202Y845231D01*
X533236Y845145D01*
G02X533326Y844671I-1208J-475D01*
G02X530730I-1298J0D01*
G02X531738Y845936I1298J0D01*
G01X531827Y845956D01*
X532704Y847616D01*
X532670Y847702D01*
G02X532580Y848176I1208J475D01*
G37*
G36*
G01X1327422D02*
G02X1330018I1298J0D01*
G02X1329945Y847747I-1297J0D01*
G01X1329914Y847661D01*
X1330721Y846263D01*
X1330811Y846246D01*
G02X1331866Y844971I-243J-1275D01*
G02X1329272I-1297J0D01*
G02X1329344Y845400I1297J3D01*
G01X1329375Y845486D01*
X1328568Y846884D01*
X1328478Y846901D01*
G02X1327422Y848176I242J1275D01*
G37*
G36*
G01X1334822D02*
G02X1337418I1298J0D01*
G02X1337345Y847747I-1297J0D01*
G01X1337314Y847661D01*
X1338121Y846263D01*
X1338211Y846246D01*
G02X1339266Y844971I-243J-1275D01*
G02X1336672I-1297J0D01*
G02X1336744Y845400I1297J3D01*
G01X1336775Y845486D01*
X1335968Y846884D01*
X1335878Y846901D01*
G02X1334822Y848176I242J1275D01*
G37*
G36*
G01X1342222D02*
G02X1344818I1298J0D01*
G02X1344745Y847747I-1297J0D01*
G01X1344714Y847661D01*
X1345521Y846263D01*
X1345611Y846246D01*
G02X1346666Y844971I-243J-1275D01*
G02X1344072I-1297J0D01*
G02X1344144Y845400I1297J3D01*
G01X1344175Y845486D01*
X1343368Y846884D01*
X1343278Y846901D01*
G02X1342222Y848176I242J1275D01*
G37*
G36*
G01X1349622D02*
G02X1352218I1298J0D01*
G02X1352145Y847747I-1297J0D01*
G01X1352114Y847661D01*
X1352921Y846263D01*
X1353011Y846246D01*
G02X1354066Y844971I-243J-1275D01*
G02X1351472I-1297J0D01*
G02X1351544Y845400I1297J3D01*
G01X1351575Y845486D01*
X1350768Y846884D01*
X1350678Y846901D01*
G02X1349622Y848176I242J1275D01*
G37*
G36*
G01X1357022D02*
G02X1359618I1298J0D01*
G02X1359545Y847747I-1297J0D01*
G01X1359514Y847661D01*
X1360321Y846263D01*
X1360411Y846246D01*
G02X1361466Y844971I-243J-1275D01*
G02X1358872I-1297J0D01*
G02X1358944Y845400I1297J3D01*
G01X1358975Y845486D01*
X1358168Y846884D01*
X1358078Y846901D01*
G02X1357022Y848176I242J1275D01*
G37*
G36*
G01X1364422D02*
G02X1367018I1298J0D01*
G02X1366945Y847747I-1297J0D01*
G01X1366914Y847661D01*
X1367721Y846263D01*
X1367811Y846246D01*
G02X1368866Y844971I-243J-1275D01*
G02X1366272I-1297J0D01*
G02X1366344Y845400I1297J3D01*
G01X1366375Y845486D01*
X1365568Y846884D01*
X1365478Y846901D01*
G02X1364422Y848176I242J1275D01*
G37*
G36*
G01X1371822D02*
G02X1374418I1298J0D01*
G02X1374345Y847747I-1297J0D01*
G01X1374314Y847661D01*
X1375121Y846263D01*
X1375211Y846246D01*
G02X1376266Y844971I-243J-1275D01*
G02X1373672I-1297J0D01*
G02X1373744Y845400I1297J3D01*
G01X1373775Y845486D01*
X1372968Y846884D01*
X1372878Y846901D01*
G02X1371822Y848176I242J1275D01*
G37*
G36*
G01X1379222D02*
G02X1381818I1298J0D01*
G02X1381745Y847747I-1297J0D01*
G01X1381714Y847661D01*
X1382521Y846263D01*
X1382611Y846246D01*
G02X1383666Y844971I-243J-1275D01*
G02X1381072I-1297J0D01*
G02X1381144Y845400I1297J3D01*
G01X1381175Y845486D01*
X1380368Y846884D01*
X1380278Y846901D01*
G02X1379222Y848176I242J1275D01*
G37*
G36*
G01X1386622D02*
G02X1389218I1298J0D01*
G02X1389145Y847747I-1297J0D01*
G01X1389114Y847661D01*
X1389921Y846263D01*
X1390011Y846246D01*
G02X1391066Y844971I-243J-1275D01*
G02X1388472I-1297J0D01*
G02X1388544Y845400I1297J3D01*
G01X1388575Y845486D01*
X1387768Y846884D01*
X1387678Y846901D01*
G02X1386622Y848176I242J1275D01*
G37*
G36*
G01X1394022D02*
G02X1396618I1298J0D01*
G02X1396545Y847747I-1297J0D01*
G01X1396514Y847661D01*
X1397321Y846263D01*
X1397411Y846246D01*
G02X1398466Y844971I-243J-1275D01*
G02X1395872I-1297J0D01*
G02X1395944Y845400I1297J3D01*
G01X1395975Y845486D01*
X1395168Y846884D01*
X1395078Y846901D01*
G02X1394022Y848176I242J1275D01*
G37*
G36*
G01X1401422D02*
G02X1404018I1298J0D01*
G02X1403945Y847747I-1297J0D01*
G01X1403914Y847661D01*
X1404721Y846263D01*
X1404811Y846246D01*
G02X1405866Y844971I-243J-1275D01*
G02X1403272I-1297J0D01*
G02X1403344Y845400I1297J3D01*
G01X1403375Y845486D01*
X1402568Y846884D01*
X1402478Y846901D01*
G02X1401422Y848176I242J1275D01*
G37*
G36*
G01X1406420Y849474D02*
G02X1407459Y848954I0J-1298D01*
G01X1409081D01*
G02X1410120Y849474I1039J-778D01*
G02Y846878I0J-1298D01*
G02X1409081Y847398I0J1298D01*
G01X1407459D01*
G02X1406420Y846878I-1039J778D01*
G02Y849474I0J1298D01*
G37*
G36*
G01X1412522Y848176D02*
G02X1415118I1298J0D01*
G02X1414062Y846901I-1298J0D01*
G01X1413972Y846884D01*
X1413164Y845485D01*
X1413194Y845398D01*
G02X1413266Y844973I-1225J-426D01*
G01Y844971D01*
G02X1410672I-1297J0D01*
G02X1411728Y846246I1298J0D01*
G01X1411818Y846263D01*
X1412625Y847662D01*
X1412595Y847748D01*
G02X1412522Y848176I1225J429D01*
G37*
G36*
G01X349430Y851380D02*
G02X352024I1297J0D01*
G02X350969Y850105I-1298J0D01*
G01X350879Y850088D01*
X350072Y848691D01*
X350103Y848604D01*
G02X350176Y848176I-1225J-429D01*
G02X347580I-1298J0D01*
G02X348636Y849451I1298J0D01*
G01X348726Y849468D01*
X349533Y850865D01*
X349502Y850952D01*
G02X349430Y851380I1225J426D01*
G37*
G36*
G01X1325572D02*
G02X1328166I1297J0D01*
G02X1327111Y850105I-1298J0D01*
G01X1327021Y850088D01*
X1326214Y848691D01*
X1326245Y848604D01*
G02X1326318Y848176I-1225J-429D01*
G02X1323722I-1298J0D01*
G02X1324778Y849451I1298J0D01*
G01X1324868Y849468D01*
X1325675Y850865D01*
X1325644Y850952D01*
G02X1325572Y851380I1225J426D01*
G37*
G36*
G01X353132Y857789D02*
G02X355726I1297J0D01*
G02X355654Y857360I-1297J-3D01*
G01X355623Y857274D01*
X356430Y855876D01*
X356520Y855859D01*
G02X357576Y854584I-242J-1275D01*
G02X354980I-1298J0D01*
G02X355053Y855013I1297J0D01*
G01X355084Y855099D01*
X354277Y856497D01*
X354187Y856514D01*
G02X353132Y857789I243J1275D01*
G37*
G36*
G01X360532D02*
G02X363126I1297J0D01*
G02X363054Y857360I-1297J-3D01*
G01X363023Y857274D01*
X363830Y855876D01*
X363920Y855859D01*
G02X364976Y854584I-242J-1275D01*
G02X362380I-1298J0D01*
G02X362453Y855013I1297J0D01*
G01X362484Y855099D01*
X361677Y856497D01*
X361587Y856514D01*
G02X360532Y857789I243J1275D01*
G37*
G36*
G01X367932D02*
G02X370526I1297J0D01*
G02X370454Y857360I-1297J-3D01*
G01X370423Y857274D01*
X371230Y855876D01*
X371320Y855859D01*
G02X372376Y854584I-242J-1275D01*
G02X369780I-1298J0D01*
G02X369853Y855013I1297J0D01*
G01X369884Y855099D01*
X369077Y856497D01*
X368987Y856514D01*
G02X367932Y857789I243J1275D01*
G37*
G36*
G01X375332D02*
G02X377926I1297J0D01*
G02X377854Y857360I-1297J-3D01*
G01X377823Y857274D01*
X378630Y855876D01*
X378720Y855859D01*
G02X379776Y854584I-242J-1275D01*
G02X377180I-1298J0D01*
G02X377253Y855013I1297J0D01*
G01X377284Y855099D01*
X376477Y856497D01*
X376387Y856514D01*
G02X375332Y857789I243J1275D01*
G37*
G36*
G01X382732D02*
G02X385326I1297J0D01*
G02X385254Y857360I-1297J-3D01*
G01X385223Y857274D01*
X386030Y855876D01*
X386120Y855859D01*
G02X387176Y854584I-242J-1275D01*
G02X384580I-1298J0D01*
G02X384653Y855013I1297J0D01*
G01X384684Y855099D01*
X383877Y856497D01*
X383787Y856514D01*
G02X382732Y857789I243J1275D01*
G37*
G36*
G01X390132D02*
G02X392726I1297J0D01*
G02X392654Y857360I-1297J-3D01*
G01X392623Y857274D01*
X393430Y855876D01*
X393520Y855859D01*
G02X394576Y854584I-242J-1275D01*
G02X391980I-1298J0D01*
G02X392053Y855013I1297J0D01*
G01X392084Y855099D01*
X391277Y856497D01*
X391187Y856514D01*
G02X390132Y857789I243J1275D01*
G37*
G36*
G01X397532D02*
G02X400126I1297J0D01*
G02X400054Y857360I-1297J-3D01*
G01X400023Y857274D01*
X400830Y855876D01*
X400920Y855859D01*
G02X401976Y854584I-242J-1275D01*
G02X399380I-1298J0D01*
G02X399453Y855013I1297J0D01*
G01X399484Y855099D01*
X398677Y856497D01*
X398587Y856514D01*
G02X397532Y857789I243J1275D01*
G37*
G36*
G01X404932D02*
G02X407526I1297J0D01*
G02X407454Y857360I-1297J-3D01*
G01X407423Y857274D01*
X408230Y855876D01*
X408320Y855859D01*
G02X409376Y854584I-242J-1275D01*
G02X406780I-1298J0D01*
G02X406853Y855013I1297J0D01*
G01X406884Y855099D01*
X406077Y856497D01*
X405987Y856514D01*
G02X404932Y857789I243J1275D01*
G37*
G36*
G01X412332D02*
G02X414926I1297J0D01*
G02X414854Y857360I-1297J-3D01*
G01X414823Y857274D01*
X415630Y855876D01*
X415720Y855859D01*
G02X416776Y854584I-242J-1275D01*
G02X414180I-1298J0D01*
G02X414253Y855013I1297J0D01*
G01X414284Y855099D01*
X413477Y856497D01*
X413387Y856514D01*
G02X412332Y857789I243J1275D01*
G37*
G36*
G01X419732D02*
G02X422326I1297J0D01*
G02X422254Y857360I-1297J-3D01*
G01X422223Y857274D01*
X423030Y855876D01*
X423120Y855859D01*
G02X424176Y854584I-242J-1275D01*
G02X421580I-1298J0D01*
G02X421653Y855013I1297J0D01*
G01X421684Y855099D01*
X420877Y856497D01*
X420787Y856514D01*
G02X419732Y857789I243J1275D01*
G37*
G36*
G01X427132D02*
G02X429726I1297J0D01*
G02X429654Y857360I-1297J-3D01*
G01X429623Y857274D01*
X430430Y855876D01*
X430520Y855859D01*
G02X431576Y854584I-242J-1275D01*
G02X428980I-1298J0D01*
G02X429053Y855013I1297J0D01*
G01X429084Y855099D01*
X428277Y856497D01*
X428187Y856514D01*
G02X427132Y857789I243J1275D01*
G37*
G36*
G01X434532D02*
G02X437126I1297J0D01*
G02X437054Y857360I-1297J-3D01*
G01X437023Y857274D01*
X437830Y855876D01*
X437920Y855859D01*
G02X438976Y854584I-242J-1275D01*
G02X436382I-1297J0D01*
G02X436454Y855012I1297J2D01*
G01X436484Y855098D01*
X435677Y856497D01*
X435587Y856514D01*
G02X434532Y857789I243J1275D01*
G37*
G36*
G01X445632D02*
G02X448226I1297J0D01*
G02X447171Y856514I-1298J0D01*
G01X447081Y856497D01*
X446273Y855098D01*
X446303Y855011D01*
G02X446376Y854584I-1225J-429D01*
G02X443780I-1298J0D01*
G02X444838Y855859I1297J0D01*
G01X444928Y855876D01*
X445735Y857274D01*
X445704Y857361D01*
G02X445632Y857789I1225J426D01*
G37*
G36*
G01X453032D02*
G02X455626I1297J0D01*
G02X454571Y856514I-1298J0D01*
G01X454481Y856497D01*
X453673Y855098D01*
X453703Y855011D01*
G02X453776Y854584I-1225J-429D01*
G02X451180I-1298J0D01*
G02X452238Y855859I1297J0D01*
G01X452328Y855876D01*
X453135Y857274D01*
X453104Y857361D01*
G02X453032Y857789I1225J426D01*
G37*
G36*
G01X460432D02*
G02X463026I1297J0D01*
G02X461971Y856514I-1298J0D01*
G01X461881Y856497D01*
X461073Y855098D01*
X461103Y855011D01*
G02X461176Y854584I-1225J-429D01*
G02X458580I-1298J0D01*
G02X459638Y855859I1297J0D01*
G01X459728Y855876D01*
X460535Y857274D01*
X460504Y857361D01*
G02X460432Y857789I1225J426D01*
G37*
G36*
G01X467832D02*
G02X470426I1297J0D01*
G02X469371Y856514I-1298J0D01*
G01X469281Y856497D01*
X468473Y855098D01*
X468503Y855011D01*
G02X468576Y854584I-1225J-429D01*
G02X465980I-1298J0D01*
G02X467038Y855859I1297J0D01*
G01X467128Y855876D01*
X467935Y857274D01*
X467904Y857361D01*
G02X467832Y857789I1225J426D01*
G37*
G36*
G01X475232D02*
G02X477826I1297J0D01*
G02X476771Y856514I-1298J0D01*
G01X476681Y856497D01*
X475873Y855098D01*
X475903Y855011D01*
G02X475976Y854584I-1225J-429D01*
G02X473380I-1298J0D01*
G02X474438Y855859I1297J0D01*
G01X474528Y855876D01*
X475335Y857274D01*
X475304Y857361D01*
G02X475232Y857789I1225J426D01*
G37*
G36*
G01X482632D02*
G02X485226I1297J0D01*
G02X484171Y856514I-1298J0D01*
G01X484081Y856497D01*
X483273Y855098D01*
X483303Y855011D01*
G02X483376Y854584I-1225J-429D01*
G02X480780I-1298J0D01*
G02X481838Y855859I1297J0D01*
G01X481928Y855876D01*
X482735Y857274D01*
X482704Y857361D01*
G02X482632Y857789I1225J426D01*
G37*
G36*
G01X490032D02*
G02X492626I1297J0D01*
G02X491571Y856514I-1298J0D01*
G01X491481Y856497D01*
X490673Y855098D01*
X490703Y855011D01*
G02X490776Y854584I-1225J-429D01*
G02X488180I-1298J0D01*
G02X489238Y855859I1297J0D01*
G01X489328Y855876D01*
X490135Y857274D01*
X490104Y857361D01*
G02X490032Y857789I1225J426D01*
G37*
G36*
G01X497432D02*
G02X500026I1297J0D01*
G02X498971Y856514I-1298J0D01*
G01X498881Y856497D01*
X498073Y855098D01*
X498103Y855011D01*
G02X498176Y854584I-1225J-429D01*
G02X495580I-1298J0D01*
G02X496638Y855859I1297J0D01*
G01X496728Y855876D01*
X497535Y857274D01*
X497504Y857361D01*
G02X497432Y857789I1225J426D01*
G37*
G36*
G01X504832D02*
G02X507426I1297J0D01*
G02X506371Y856514I-1298J0D01*
G01X506281Y856497D01*
X505473Y855098D01*
X505503Y855011D01*
G02X505576Y854584I-1225J-429D01*
G02X502980I-1298J0D01*
G02X504038Y855859I1297J0D01*
G01X504128Y855876D01*
X504935Y857274D01*
X504904Y857361D01*
G02X504832Y857789I1225J426D01*
G37*
G36*
G01X512232D02*
G02X514826I1297J0D01*
G02X513771Y856514I-1298J0D01*
G01X513681Y856497D01*
X512873Y855098D01*
X512903Y855011D01*
G02X512976Y854584I-1225J-429D01*
G02X510380I-1298J0D01*
G02X511438Y855859I1297J0D01*
G01X511528Y855876D01*
X512335Y857274D01*
X512304Y857361D01*
G02X512232Y857789I1225J426D01*
G37*
G36*
G01X519632D02*
G02X522226I1297J0D01*
G02X521171Y856514I-1298J0D01*
G01X521081Y856497D01*
X520273Y855098D01*
X520303Y855011D01*
G02X520376Y854584I-1225J-429D01*
G02X517780I-1298J0D01*
G02X518838Y855859I1297J0D01*
G01X518928Y855876D01*
X519735Y857274D01*
X519704Y857361D01*
G02X519632Y857789I1225J426D01*
G37*
G36*
G01X527032D02*
G02X529626I1297J0D01*
G02X528571Y856514I-1298J0D01*
G01X528481Y856497D01*
X527673Y855098D01*
X527703Y855011D01*
G02X527776Y854584I-1225J-429D01*
G02X525180I-1298J0D01*
G02X526238Y855859I1297J0D01*
G01X526328Y855876D01*
X527135Y857274D01*
X527104Y857361D01*
G02X527032Y857789I1225J426D01*
G37*
G36*
G01X1329274D02*
G02X1331868I1297J0D01*
G02X1331796Y857360I-1297J-3D01*
G01X1331765Y857274D01*
X1332572Y855876D01*
X1332662Y855859D01*
G02X1333718Y854584I-242J-1275D01*
G02X1331122I-1298J0D01*
G02X1331195Y855013I1297J0D01*
G01X1331226Y855099D01*
X1330419Y856497D01*
X1330329Y856514D01*
G02X1329274Y857789I243J1275D01*
G37*
G36*
G01X1336674D02*
G02X1339268I1297J0D01*
G02X1339196Y857360I-1297J-3D01*
G01X1339165Y857274D01*
X1339972Y855876D01*
X1340062Y855859D01*
G02X1341118Y854584I-242J-1275D01*
G02X1338522I-1298J0D01*
G02X1338595Y855013I1297J0D01*
G01X1338626Y855099D01*
X1337819Y856497D01*
X1337729Y856514D01*
G02X1336674Y857789I243J1275D01*
G37*
G36*
G01X1344074D02*
G02X1346668I1297J0D01*
G02X1346596Y857360I-1297J-3D01*
G01X1346565Y857274D01*
X1347372Y855876D01*
X1347462Y855859D01*
G02X1348518Y854584I-242J-1275D01*
G02X1345922I-1298J0D01*
G02X1345995Y855013I1297J0D01*
G01X1346026Y855099D01*
X1345219Y856497D01*
X1345129Y856514D01*
G02X1344074Y857789I243J1275D01*
G37*
G36*
G01X1351474D02*
G02X1354068I1297J0D01*
G02X1353996Y857360I-1297J-3D01*
G01X1353965Y857274D01*
X1354772Y855876D01*
X1354862Y855859D01*
G02X1355918Y854584I-242J-1275D01*
G02X1353322I-1298J0D01*
G02X1353395Y855013I1297J0D01*
G01X1353426Y855099D01*
X1352619Y856497D01*
X1352529Y856514D01*
G02X1351474Y857789I243J1275D01*
G37*
G36*
G01X1358874D02*
G02X1361468I1297J0D01*
G02X1361396Y857360I-1297J-3D01*
G01X1361365Y857274D01*
X1362172Y855876D01*
X1362262Y855859D01*
G02X1363318Y854584I-242J-1275D01*
G02X1360722I-1298J0D01*
G02X1360795Y855013I1297J0D01*
G01X1360826Y855099D01*
X1360019Y856497D01*
X1359929Y856514D01*
G02X1358874Y857789I243J1275D01*
G37*
G36*
G01X1366274D02*
G02X1368868I1297J0D01*
G02X1368796Y857360I-1297J-3D01*
G01X1368765Y857274D01*
X1369572Y855876D01*
X1369662Y855859D01*
G02X1370718Y854584I-242J-1275D01*
G02X1368122I-1298J0D01*
G02X1368195Y855013I1297J0D01*
G01X1368226Y855099D01*
X1367419Y856497D01*
X1367329Y856514D01*
G02X1366274Y857789I243J1275D01*
G37*
G36*
G01X1373674D02*
G02X1376268I1297J0D01*
G02X1376196Y857360I-1297J-3D01*
G01X1376165Y857274D01*
X1376972Y855876D01*
X1377062Y855859D01*
G02X1378118Y854584I-242J-1275D01*
G02X1375522I-1298J0D01*
G02X1375595Y855013I1297J0D01*
G01X1375626Y855099D01*
X1374819Y856497D01*
X1374729Y856514D01*
G02X1373674Y857789I243J1275D01*
G37*
G36*
G01X1381074D02*
G02X1383668I1297J0D01*
G02X1383596Y857360I-1297J-3D01*
G01X1383565Y857274D01*
X1384372Y855876D01*
X1384462Y855859D01*
G02X1385518Y854584I-242J-1275D01*
G02X1382922I-1298J0D01*
G02X1382995Y855013I1297J0D01*
G01X1383026Y855099D01*
X1382219Y856497D01*
X1382129Y856514D01*
G02X1381074Y857789I243J1275D01*
G37*
G36*
G01X1388474D02*
G02X1391068I1297J0D01*
G02X1390996Y857360I-1297J-3D01*
G01X1390965Y857274D01*
X1391772Y855876D01*
X1391862Y855859D01*
G02X1392918Y854584I-242J-1275D01*
G02X1390322I-1298J0D01*
G02X1390395Y855013I1297J0D01*
G01X1390426Y855099D01*
X1389619Y856497D01*
X1389529Y856514D01*
G02X1388474Y857789I243J1275D01*
G37*
G36*
G01X1395874D02*
G02X1398468I1297J0D01*
G02X1398396Y857360I-1297J-3D01*
G01X1398365Y857274D01*
X1399172Y855876D01*
X1399262Y855859D01*
G02X1400318Y854584I-242J-1275D01*
G02X1397722I-1298J0D01*
G02X1397795Y855013I1297J0D01*
G01X1397826Y855099D01*
X1397019Y856497D01*
X1396929Y856514D01*
G02X1395874Y857789I243J1275D01*
G37*
G36*
G01X1403274D02*
G02X1405868I1297J0D01*
G02X1405796Y857360I-1297J-3D01*
G01X1405765Y857274D01*
X1406572Y855876D01*
X1406662Y855859D01*
G02X1407718Y854584I-242J-1275D01*
G02X1405122I-1298J0D01*
G02X1405195Y855013I1297J0D01*
G01X1405226Y855099D01*
X1404419Y856497D01*
X1404329Y856514D01*
G02X1403274Y857789I243J1275D01*
G37*
G36*
G01X1410674D02*
G02X1413268I1297J0D01*
G02X1413196Y857360I-1297J-3D01*
G01X1413165Y857274D01*
X1413972Y855876D01*
X1414062Y855859D01*
G02X1415118Y854584I-242J-1275D01*
G02X1412524I-1297J0D01*
G02X1412596Y855012I1297J2D01*
G01X1412626Y855098D01*
X1411819Y856497D01*
X1411729Y856514D01*
G02X1410674Y857789I243J1275D01*
G37*
G36*
G01X1421774D02*
G02X1424368I1297J0D01*
G02X1423313Y856514I-1298J0D01*
G01X1423223Y856497D01*
X1422415Y855098D01*
X1422445Y855011D01*
G02X1422518Y854584I-1225J-429D01*
G02X1419922I-1298J0D01*
G02X1420980Y855859I1297J0D01*
G01X1421070Y855876D01*
X1421877Y857274D01*
X1421846Y857361D01*
G02X1421774Y857789I1225J426D01*
G37*
G36*
G01X1429174D02*
G02X1431768I1297J0D01*
G02X1430713Y856514I-1298J0D01*
G01X1430623Y856497D01*
X1429815Y855098D01*
X1429845Y855011D01*
G02X1429918Y854584I-1225J-429D01*
G02X1427322I-1298J0D01*
G02X1428380Y855859I1297J0D01*
G01X1428470Y855876D01*
X1429277Y857274D01*
X1429246Y857361D01*
G02X1429174Y857789I1225J426D01*
G37*
G36*
G01X1436574D02*
G02X1439168I1297J0D01*
G02X1438113Y856514I-1298J0D01*
G01X1438023Y856497D01*
X1437215Y855098D01*
X1437245Y855011D01*
G02X1437318Y854584I-1225J-429D01*
G02X1434722I-1298J0D01*
G02X1435780Y855859I1297J0D01*
G01X1435870Y855876D01*
X1436677Y857274D01*
X1436646Y857361D01*
G02X1436574Y857789I1225J426D01*
G37*
G36*
G01X1443974D02*
G02X1446568I1297J0D01*
G02X1445513Y856514I-1298J0D01*
G01X1445423Y856497D01*
X1444615Y855098D01*
X1444645Y855011D01*
G02X1444718Y854584I-1225J-429D01*
G02X1442122I-1298J0D01*
G02X1443180Y855859I1297J0D01*
G01X1443270Y855876D01*
X1444077Y857274D01*
X1444046Y857361D01*
G02X1443974Y857789I1225J426D01*
G37*
G36*
G01X1451374D02*
G02X1453968I1297J0D01*
G02X1452913Y856514I-1298J0D01*
G01X1452823Y856497D01*
X1452015Y855098D01*
X1452045Y855011D01*
G02X1452118Y854584I-1225J-429D01*
G02X1449522I-1298J0D01*
G02X1450580Y855859I1297J0D01*
G01X1450670Y855876D01*
X1451477Y857274D01*
X1451446Y857361D01*
G02X1451374Y857789I1225J426D01*
G37*
G36*
G01X1458774D02*
G02X1461368I1297J0D01*
G02X1460313Y856514I-1298J0D01*
G01X1460223Y856497D01*
X1459415Y855098D01*
X1459445Y855011D01*
G02X1459518Y854584I-1225J-429D01*
G02X1456922I-1298J0D01*
G02X1457980Y855859I1297J0D01*
G01X1458070Y855876D01*
X1458877Y857274D01*
X1458846Y857361D01*
G02X1458774Y857789I1225J426D01*
G37*
G36*
G01X1466174D02*
G02X1468768I1297J0D01*
G02X1467713Y856514I-1298J0D01*
G01X1467623Y856497D01*
X1466815Y855098D01*
X1466845Y855011D01*
G02X1466918Y854584I-1225J-429D01*
G02X1464322I-1298J0D01*
G02X1465380Y855859I1297J0D01*
G01X1465470Y855876D01*
X1466277Y857274D01*
X1466246Y857361D01*
G02X1466174Y857789I1225J426D01*
G37*
G36*
G01X1473574D02*
G02X1476168I1297J0D01*
G02X1475113Y856514I-1298J0D01*
G01X1475023Y856497D01*
X1474215Y855098D01*
X1474245Y855011D01*
G02X1474318Y854584I-1225J-429D01*
G02X1471722I-1298J0D01*
G02X1472780Y855859I1297J0D01*
G01X1472870Y855876D01*
X1473677Y857274D01*
X1473646Y857361D01*
G02X1473574Y857789I1225J426D01*
G37*
G36*
G01X1480974D02*
G02X1483568I1297J0D01*
G02X1482513Y856514I-1298J0D01*
G01X1482423Y856497D01*
X1481615Y855098D01*
X1481645Y855011D01*
G02X1481718Y854584I-1225J-429D01*
G02X1479122I-1298J0D01*
G02X1480180Y855859I1297J0D01*
G01X1480270Y855876D01*
X1481077Y857274D01*
X1481046Y857361D01*
G02X1480974Y857789I1225J426D01*
G37*
G36*
G01X1488374D02*
G02X1490968I1297J0D01*
G02X1489913Y856514I-1298J0D01*
G01X1489823Y856497D01*
X1489015Y855098D01*
X1489045Y855011D01*
G02X1489118Y854584I-1225J-429D01*
G02X1486522I-1298J0D01*
G02X1487580Y855859I1297J0D01*
G01X1487670Y855876D01*
X1488477Y857274D01*
X1488446Y857361D01*
G02X1488374Y857789I1225J426D01*
G37*
G36*
G01X1495774D02*
G02X1498368I1297J0D01*
G02X1497313Y856514I-1298J0D01*
G01X1497223Y856497D01*
X1496415Y855098D01*
X1496445Y855011D01*
G02X1496518Y854584I-1225J-429D01*
G02X1493922I-1298J0D01*
G02X1494980Y855859I1297J0D01*
G01X1495070Y855876D01*
X1495877Y857274D01*
X1495846Y857361D01*
G02X1495774Y857789I1225J426D01*
G37*
G36*
G01X1503174D02*
G02X1505768I1297J0D01*
G02X1504713Y856514I-1298J0D01*
G01X1504623Y856497D01*
X1503815Y855098D01*
X1503845Y855011D01*
G02X1503918Y854584I-1225J-429D01*
G02X1501322I-1298J0D01*
G02X1502380Y855859I1297J0D01*
G01X1502470Y855876D01*
X1503277Y857274D01*
X1503246Y857361D01*
G02X1503174Y857789I1225J426D01*
G37*
G36*
G01X351280Y860993D02*
G02X353876I1298J0D01*
G02X352820Y859718I-1298J0D01*
G01X352730Y859701D01*
X351923Y858304D01*
X351954Y858217D01*
G02X352026Y857789I-1225J-426D01*
G02X349432I-1297J0D01*
G02X350487Y859064I1298J0D01*
G01X350577Y859081D01*
X351384Y860478D01*
X351353Y860565D01*
G02X351280Y860993I1225J429D01*
G37*
G36*
G01X358680D02*
G02X361276I1298J0D01*
G02X360220Y859718I-1298J0D01*
G01X360130Y859701D01*
X359323Y858304D01*
X359354Y858217D01*
G02X359426Y857789I-1225J-426D01*
G02X356832I-1297J0D01*
G02X357887Y859064I1298J0D01*
G01X357977Y859081D01*
X358784Y860478D01*
X358753Y860565D01*
G02X358680Y860993I1225J429D01*
G37*
G36*
G01X366080D02*
G02X368676I1298J0D01*
G02X367620Y859718I-1298J0D01*
G01X367530Y859701D01*
X366723Y858304D01*
X366754Y858217D01*
G02X366826Y857789I-1225J-426D01*
G02X364232I-1297J0D01*
G02X365287Y859064I1298J0D01*
G01X365377Y859081D01*
X366184Y860478D01*
X366153Y860565D01*
G02X366080Y860993I1225J429D01*
G37*
G36*
G01X373480D02*
G02X376076I1298J0D01*
G02X375020Y859718I-1298J0D01*
G01X374930Y859701D01*
X374123Y858304D01*
X374154Y858217D01*
G02X374226Y857789I-1225J-426D01*
G02X371632I-1297J0D01*
G02X372687Y859064I1298J0D01*
G01X372777Y859081D01*
X373584Y860478D01*
X373553Y860565D01*
G02X373480Y860993I1225J429D01*
G37*
G36*
G01X380880D02*
G02X383476I1298J0D01*
G02X382420Y859718I-1298J0D01*
G01X382330Y859701D01*
X381523Y858304D01*
X381554Y858217D01*
G02X381626Y857789I-1225J-426D01*
G02X379032I-1297J0D01*
G02X380087Y859064I1298J0D01*
G01X380177Y859081D01*
X380984Y860478D01*
X380953Y860565D01*
G02X380880Y860993I1225J429D01*
G37*
G36*
G01X388280D02*
G02X390876I1298J0D01*
G02X389820Y859718I-1298J0D01*
G01X389730Y859701D01*
X388923Y858304D01*
X388954Y858217D01*
G02X389026Y857789I-1225J-426D01*
G02X386432I-1297J0D01*
G02X387487Y859064I1298J0D01*
G01X387577Y859081D01*
X388384Y860478D01*
X388353Y860565D01*
G02X388280Y860993I1225J429D01*
G37*
G36*
G01X395680D02*
G02X398276I1298J0D01*
G02X397220Y859718I-1298J0D01*
G01X397130Y859701D01*
X396323Y858304D01*
X396354Y858217D01*
G02X396426Y857789I-1225J-426D01*
G02X393832I-1297J0D01*
G02X394887Y859064I1298J0D01*
G01X394977Y859081D01*
X395784Y860478D01*
X395753Y860565D01*
G02X395680Y860993I1225J429D01*
G37*
G36*
G01X403080D02*
G02X405676I1298J0D01*
G02X404620Y859718I-1298J0D01*
G01X404530Y859701D01*
X403723Y858304D01*
X403754Y858217D01*
G02X403826Y857789I-1225J-426D01*
G02X401232I-1297J0D01*
G02X402287Y859064I1298J0D01*
G01X402377Y859081D01*
X403184Y860478D01*
X403153Y860565D01*
G02X403080Y860993I1225J429D01*
G37*
G36*
G01X410480D02*
G02X413076I1298J0D01*
G02X412020Y859718I-1298J0D01*
G01X411930Y859701D01*
X411123Y858304D01*
X411154Y858217D01*
G02X411226Y857789I-1225J-426D01*
G02X408632I-1297J0D01*
G02X409687Y859064I1298J0D01*
G01X409777Y859081D01*
X410584Y860478D01*
X410553Y860565D01*
G02X410480Y860993I1225J429D01*
G37*
G36*
G01X417880D02*
G02X420476I1298J0D01*
G02X419420Y859718I-1298J0D01*
G01X419330Y859701D01*
X418523Y858304D01*
X418554Y858217D01*
G02X418626Y857789I-1225J-426D01*
G02X416032I-1297J0D01*
G02X417087Y859064I1298J0D01*
G01X417177Y859081D01*
X417984Y860478D01*
X417953Y860565D01*
G02X417880Y860993I1225J429D01*
G37*
G36*
G01X425280D02*
G02X427876I1298J0D01*
G02X426820Y859718I-1298J0D01*
G01X426730Y859701D01*
X425923Y858304D01*
X425954Y858217D01*
G02X426026Y857789I-1225J-426D01*
G02X423432I-1297J0D01*
G02X424487Y859064I1298J0D01*
G01X424577Y859081D01*
X425384Y860478D01*
X425353Y860565D01*
G02X425280Y860993I1225J429D01*
G37*
G36*
G01X432682D02*
G02X435276I1297J0D01*
G02X434221Y859718I-1298J0D01*
G01X434131Y859701D01*
X433324Y858303D01*
X433354Y858217D01*
G02X433426Y857789I-1225J-426D01*
G02X430832I-1297J0D01*
G02X431888Y859064I1298J0D01*
G01X431978Y859081D01*
X432785Y860478D01*
X432754Y860565D01*
G02X432682Y860993I1225J426D01*
G37*
G36*
G01X440080D02*
G02X442676I1298J0D01*
G02X442603Y860564I-1297J0D01*
G01X442572Y860478D01*
X443378Y859081D01*
X443468Y859064D01*
G02X444526Y857789I-239J-1275D01*
G02X441932I-1297J0D01*
G02X442003Y858215I1297J3D01*
G01X442034Y858302D01*
X441226Y859701D01*
X441136Y859718D01*
G02X440080Y860993I242J1275D01*
G37*
G36*
G01X447482D02*
G02X450076I1297J0D01*
G02X450004Y860564I-1297J-3D01*
G01X449973Y860478D01*
X450779Y859081D01*
X450869Y859064D01*
G02X451926Y857789I-240J-1275D01*
G02X449332I-1297J0D01*
G01Y857791D01*
G02X449404Y858216I1297J-1D01*
G01X449434Y858303D01*
X448627Y859701D01*
X448537Y859718D01*
G02X447482Y860993I243J1275D01*
G37*
G36*
G01X454880D02*
G02X457476I1298J0D01*
G02X457403Y860564I-1297J0D01*
G01X457372Y860478D01*
X458178Y859081D01*
X458268Y859064D01*
G02X459326Y857789I-239J-1275D01*
G02X456732I-1297J0D01*
G02X456803Y858215I1297J3D01*
G01X456834Y858302D01*
X456026Y859701D01*
X455936Y859718D01*
G02X454880Y860993I242J1275D01*
G37*
G36*
G01X462280D02*
G02X464876I1298J0D01*
G02X464803Y860564I-1297J0D01*
G01X464772Y860478D01*
X465578Y859081D01*
X465668Y859064D01*
G02X466726Y857789I-239J-1275D01*
G02X464132I-1297J0D01*
G02X464203Y858215I1297J3D01*
G01X464234Y858302D01*
X463426Y859701D01*
X463336Y859718D01*
G02X462280Y860993I242J1275D01*
G37*
G36*
G01X469680D02*
G02X472276I1298J0D01*
G02X472203Y860564I-1297J0D01*
G01X472172Y860478D01*
X472978Y859081D01*
X473068Y859064D01*
G02X474126Y857789I-239J-1275D01*
G02X471532I-1297J0D01*
G02X471603Y858215I1297J3D01*
G01X471634Y858302D01*
X470826Y859701D01*
X470736Y859718D01*
G02X469680Y860993I242J1275D01*
G37*
G36*
G01X477080D02*
G02X479676I1298J0D01*
G02X479603Y860564I-1297J0D01*
G01X479572Y860478D01*
X480378Y859081D01*
X480468Y859064D01*
G02X481526Y857789I-239J-1275D01*
G02X478932I-1297J0D01*
G02X479003Y858215I1297J3D01*
G01X479034Y858302D01*
X478226Y859701D01*
X478136Y859718D01*
G02X477080Y860993I242J1275D01*
G37*
G36*
G01X484480D02*
G02X487076I1298J0D01*
G02X487003Y860564I-1297J0D01*
G01X486972Y860478D01*
X487778Y859081D01*
X487868Y859064D01*
G02X488926Y857789I-239J-1275D01*
G02X486332I-1297J0D01*
G02X486403Y858215I1297J3D01*
G01X486434Y858302D01*
X485626Y859701D01*
X485536Y859718D01*
G02X484480Y860993I242J1275D01*
G37*
G36*
G01X491880D02*
G02X494476I1298J0D01*
G02X494403Y860564I-1297J0D01*
G01X494372Y860478D01*
X495178Y859081D01*
X495268Y859064D01*
G02X496326Y857789I-239J-1275D01*
G02X493732I-1297J0D01*
G02X493803Y858215I1297J3D01*
G01X493834Y858302D01*
X493026Y859701D01*
X492936Y859718D01*
G02X491880Y860993I242J1275D01*
G37*
G36*
G01X499280D02*
G02X501876I1298J0D01*
G02X501803Y860564I-1297J0D01*
G01X501772Y860478D01*
X502578Y859081D01*
X502668Y859064D01*
G02X503726Y857789I-239J-1275D01*
G02X501132I-1297J0D01*
G02X501203Y858215I1297J3D01*
G01X501234Y858302D01*
X500426Y859701D01*
X500336Y859718D01*
G02X499280Y860993I242J1275D01*
G37*
G36*
G01X506680D02*
G02X509276I1298J0D01*
G02X509203Y860564I-1297J0D01*
G01X509172Y860478D01*
X509978Y859081D01*
X510068Y859064D01*
G02X511126Y857789I-239J-1275D01*
G02X508532I-1297J0D01*
G02X508603Y858215I1297J3D01*
G01X508634Y858302D01*
X507826Y859701D01*
X507736Y859718D01*
G02X506680Y860993I242J1275D01*
G37*
G36*
G01X514080D02*
G02X516676I1298J0D01*
G02X516603Y860564I-1297J0D01*
G01X516572Y860478D01*
X517378Y859081D01*
X517468Y859064D01*
G02X518526Y857789I-239J-1275D01*
G02X515932I-1297J0D01*
G02X516003Y858215I1297J3D01*
G01X516034Y858302D01*
X515226Y859701D01*
X515136Y859718D01*
G02X514080Y860993I242J1275D01*
G37*
G36*
G01X521480D02*
G02X524076I1298J0D01*
G02X524003Y860564I-1297J0D01*
G01X523972Y860478D01*
X524778Y859081D01*
X524868Y859064D01*
G02X525926Y857789I-239J-1275D01*
G02X523332I-1297J0D01*
G02X523403Y858215I1297J3D01*
G01X523434Y858302D01*
X522626Y859701D01*
X522536Y859718D01*
G02X521480Y860993I242J1275D01*
G37*
G36*
G01X1327422D02*
G02X1330018I1298J0D01*
G02X1328962Y859718I-1298J0D01*
G01X1328872Y859701D01*
X1328065Y858304D01*
X1328096Y858217D01*
G02X1328168Y857789I-1225J-426D01*
G02X1325574I-1297J0D01*
G02X1326629Y859064I1298J0D01*
G01X1326719Y859081D01*
X1327526Y860478D01*
X1327495Y860565D01*
G02X1327422Y860993I1225J429D01*
G37*
G36*
G01X1334822D02*
G02X1337418I1298J0D01*
G02X1336362Y859718I-1298J0D01*
G01X1336272Y859701D01*
X1335465Y858304D01*
X1335496Y858217D01*
G02X1335568Y857789I-1225J-426D01*
G02X1332974I-1297J0D01*
G02X1334029Y859064I1298J0D01*
G01X1334119Y859081D01*
X1334926Y860478D01*
X1334895Y860565D01*
G02X1334822Y860993I1225J429D01*
G37*
G36*
G01X1342222D02*
G02X1344818I1298J0D01*
G02X1343762Y859718I-1298J0D01*
G01X1343672Y859701D01*
X1342865Y858304D01*
X1342896Y858217D01*
G02X1342968Y857789I-1225J-426D01*
G02X1340374I-1297J0D01*
G02X1341429Y859064I1298J0D01*
G01X1341519Y859081D01*
X1342326Y860478D01*
X1342295Y860565D01*
G02X1342222Y860993I1225J429D01*
G37*
G36*
G01X1349622D02*
G02X1352218I1298J0D01*
G02X1351162Y859718I-1298J0D01*
G01X1351072Y859701D01*
X1350265Y858304D01*
X1350296Y858217D01*
G02X1350368Y857789I-1225J-426D01*
G02X1347774I-1297J0D01*
G02X1348829Y859064I1298J0D01*
G01X1348919Y859081D01*
X1349726Y860478D01*
X1349695Y860565D01*
G02X1349622Y860993I1225J429D01*
G37*
G36*
G01X1357022D02*
G02X1359618I1298J0D01*
G02X1358562Y859718I-1298J0D01*
G01X1358472Y859701D01*
X1357665Y858304D01*
X1357696Y858217D01*
G02X1357768Y857789I-1225J-426D01*
G02X1355174I-1297J0D01*
G02X1356229Y859064I1298J0D01*
G01X1356319Y859081D01*
X1357126Y860478D01*
X1357095Y860565D01*
G02X1357022Y860993I1225J429D01*
G37*
G36*
G01X1364422D02*
G02X1367018I1298J0D01*
G02X1365962Y859718I-1298J0D01*
G01X1365872Y859701D01*
X1365065Y858304D01*
X1365096Y858217D01*
G02X1365168Y857789I-1225J-426D01*
G02X1362574I-1297J0D01*
G02X1363629Y859064I1298J0D01*
G01X1363719Y859081D01*
X1364526Y860478D01*
X1364495Y860565D01*
G02X1364422Y860993I1225J429D01*
G37*
G36*
G01X1371822D02*
G02X1374418I1298J0D01*
G02X1373362Y859718I-1298J0D01*
G01X1373272Y859701D01*
X1372465Y858304D01*
X1372496Y858217D01*
G02X1372568Y857789I-1225J-426D01*
G02X1369974I-1297J0D01*
G02X1371029Y859064I1298J0D01*
G01X1371119Y859081D01*
X1371926Y860478D01*
X1371895Y860565D01*
G02X1371822Y860993I1225J429D01*
G37*
G36*
G01X1379222D02*
G02X1381818I1298J0D01*
G02X1380762Y859718I-1298J0D01*
G01X1380672Y859701D01*
X1379865Y858304D01*
X1379896Y858217D01*
G02X1379968Y857789I-1225J-426D01*
G02X1377374I-1297J0D01*
G02X1378429Y859064I1298J0D01*
G01X1378519Y859081D01*
X1379326Y860478D01*
X1379295Y860565D01*
G02X1379222Y860993I1225J429D01*
G37*
G36*
G01X1386622D02*
G02X1389218I1298J0D01*
G02X1388162Y859718I-1298J0D01*
G01X1388072Y859701D01*
X1387265Y858304D01*
X1387296Y858217D01*
G02X1387368Y857789I-1225J-426D01*
G02X1384774I-1297J0D01*
G02X1385829Y859064I1298J0D01*
G01X1385919Y859081D01*
X1386726Y860478D01*
X1386695Y860565D01*
G02X1386622Y860993I1225J429D01*
G37*
G36*
G01X1394022D02*
G02X1396618I1298J0D01*
G02X1395562Y859718I-1298J0D01*
G01X1395472Y859701D01*
X1394665Y858304D01*
X1394696Y858217D01*
G02X1394768Y857789I-1225J-426D01*
G02X1392174I-1297J0D01*
G02X1393229Y859064I1298J0D01*
G01X1393319Y859081D01*
X1394126Y860478D01*
X1394095Y860565D01*
G02X1394022Y860993I1225J429D01*
G37*
G36*
G01X1401422D02*
G02X1404018I1298J0D01*
G02X1402962Y859718I-1298J0D01*
G01X1402872Y859701D01*
X1402065Y858304D01*
X1402096Y858217D01*
G02X1402168Y857789I-1225J-426D01*
G02X1399574I-1297J0D01*
G02X1400629Y859064I1298J0D01*
G01X1400719Y859081D01*
X1401526Y860478D01*
X1401495Y860565D01*
G02X1401422Y860993I1225J429D01*
G37*
G36*
G01X1408824D02*
G02X1411418I1297J0D01*
G02X1410363Y859718I-1298J0D01*
G01X1410273Y859701D01*
X1409466Y858303D01*
X1409496Y858217D01*
G02X1409568Y857789I-1225J-426D01*
G02X1406974I-1297J0D01*
G02X1408030Y859064I1298J0D01*
G01X1408120Y859081D01*
X1408927Y860478D01*
X1408896Y860565D01*
G02X1408824Y860993I1225J426D01*
G37*
G36*
G01X1416222D02*
G02X1418818I1298J0D01*
G02X1418745Y860564I-1297J0D01*
G01X1418714Y860478D01*
X1419520Y859081D01*
X1419610Y859064D01*
G02X1420668Y857789I-239J-1275D01*
G02X1418074I-1297J0D01*
G02X1418145Y858215I1297J3D01*
G01X1418176Y858302D01*
X1417368Y859701D01*
X1417278Y859718D01*
G02X1416222Y860993I242J1275D01*
G37*
G36*
G01X1423624D02*
G02X1426218I1297J0D01*
G02X1426146Y860564I-1297J-3D01*
G01X1426115Y860478D01*
X1426921Y859081D01*
X1427011Y859064D01*
G02X1428068Y857789I-240J-1275D01*
G02X1425474I-1297J0D01*
G01Y857791D01*
G02X1425546Y858216I1297J-1D01*
G01X1425576Y858303D01*
X1424769Y859701D01*
X1424679Y859718D01*
G02X1423624Y860993I243J1275D01*
G37*
G36*
G01X1431022D02*
G02X1433618I1298J0D01*
G02X1433545Y860564I-1297J0D01*
G01X1433514Y860478D01*
X1434320Y859081D01*
X1434410Y859064D01*
G02X1435468Y857789I-239J-1275D01*
G02X1432874I-1297J0D01*
G02X1432945Y858215I1297J3D01*
G01X1432976Y858302D01*
X1432168Y859701D01*
X1432078Y859718D01*
G02X1431022Y860993I242J1275D01*
G37*
G36*
G01X1438422D02*
G02X1441018I1298J0D01*
G02X1440945Y860564I-1297J0D01*
G01X1440914Y860478D01*
X1441720Y859081D01*
X1441810Y859064D01*
G02X1442868Y857789I-239J-1275D01*
G02X1440274I-1297J0D01*
G02X1440345Y858215I1297J3D01*
G01X1440376Y858302D01*
X1439568Y859701D01*
X1439478Y859718D01*
G02X1438422Y860993I242J1275D01*
G37*
G36*
G01X1445822D02*
G02X1448418I1298J0D01*
G02X1448345Y860564I-1297J0D01*
G01X1448314Y860478D01*
X1449120Y859081D01*
X1449210Y859064D01*
G02X1450268Y857789I-239J-1275D01*
G02X1447674I-1297J0D01*
G02X1447745Y858215I1297J3D01*
G01X1447776Y858302D01*
X1446968Y859701D01*
X1446878Y859718D01*
G02X1445822Y860993I242J1275D01*
G37*
G36*
G01X1453222D02*
G02X1455818I1298J0D01*
G02X1455745Y860564I-1297J0D01*
G01X1455714Y860478D01*
X1456520Y859081D01*
X1456610Y859064D01*
G02X1457668Y857789I-239J-1275D01*
G02X1455074I-1297J0D01*
G02X1455145Y858215I1297J3D01*
G01X1455176Y858302D01*
X1454368Y859701D01*
X1454278Y859718D01*
G02X1453222Y860993I242J1275D01*
G37*
G36*
G01X1460622D02*
G02X1463218I1298J0D01*
G02X1463145Y860564I-1297J0D01*
G01X1463114Y860478D01*
X1463920Y859081D01*
X1464010Y859064D01*
G02X1465068Y857789I-239J-1275D01*
G02X1462474I-1297J0D01*
G02X1462545Y858215I1297J3D01*
G01X1462576Y858302D01*
X1461768Y859701D01*
X1461678Y859718D01*
G02X1460622Y860993I242J1275D01*
G37*
G36*
G01X1468022D02*
G02X1470618I1298J0D01*
G02X1470545Y860564I-1297J0D01*
G01X1470514Y860478D01*
X1471320Y859081D01*
X1471410Y859064D01*
G02X1472468Y857789I-239J-1275D01*
G02X1469874I-1297J0D01*
G02X1469945Y858215I1297J3D01*
G01X1469976Y858302D01*
X1469168Y859701D01*
X1469078Y859718D01*
G02X1468022Y860993I242J1275D01*
G37*
G36*
G01X1475422D02*
G02X1478018I1298J0D01*
G02X1477945Y860564I-1297J0D01*
G01X1477914Y860478D01*
X1478720Y859081D01*
X1478810Y859064D01*
G02X1479868Y857789I-239J-1275D01*
G02X1477274I-1297J0D01*
G02X1477345Y858215I1297J3D01*
G01X1477376Y858302D01*
X1476568Y859701D01*
X1476478Y859718D01*
G02X1475422Y860993I242J1275D01*
G37*
G36*
G01X1482822D02*
G02X1485418I1298J0D01*
G02X1485345Y860564I-1297J0D01*
G01X1485314Y860478D01*
X1486120Y859081D01*
X1486210Y859064D01*
G02X1487268Y857789I-239J-1275D01*
G02X1484674I-1297J0D01*
G02X1484745Y858215I1297J3D01*
G01X1484776Y858302D01*
X1483968Y859701D01*
X1483878Y859718D01*
G02X1482822Y860993I242J1275D01*
G37*
G36*
G01X1490222D02*
G02X1492818I1298J0D01*
G02X1492745Y860564I-1297J0D01*
G01X1492714Y860478D01*
X1493520Y859081D01*
X1493610Y859064D01*
G02X1494668Y857789I-239J-1275D01*
G02X1492074I-1297J0D01*
G02X1492145Y858215I1297J3D01*
G01X1492176Y858302D01*
X1491368Y859701D01*
X1491278Y859718D01*
G02X1490222Y860993I242J1275D01*
G37*
G36*
G01X1497622D02*
G02X1500218I1298J0D01*
G02X1500145Y860564I-1297J0D01*
G01X1500114Y860478D01*
X1500920Y859081D01*
X1501010Y859064D01*
G02X1502068Y857789I-239J-1275D01*
G02X1499474I-1297J0D01*
G02X1499545Y858215I1297J3D01*
G01X1499576Y858302D01*
X1498768Y859701D01*
X1498678Y859718D01*
G02X1497622Y860993I242J1275D01*
G37*
G36*
G01X353132Y870606D02*
G02X355726I1297J0D01*
G02X355654Y870177I-1297J-3D01*
G01X355623Y870091D01*
X356430Y868693D01*
X356520Y868676D01*
G02X357576Y867401I-242J-1275D01*
G02X354980I-1298J0D01*
G02X355053Y867830I1297J0D01*
G01X355084Y867916D01*
X354277Y869314D01*
X354187Y869331D01*
G02X353132Y870606I243J1275D01*
G37*
G36*
G01X360532D02*
G02X363126I1297J0D01*
G02X363054Y870177I-1297J-3D01*
G01X363023Y870091D01*
X363830Y868693D01*
X363920Y868676D01*
G02X364976Y867401I-242J-1275D01*
G02X362380I-1298J0D01*
G02X362453Y867830I1297J0D01*
G01X362484Y867916D01*
X361677Y869314D01*
X361587Y869331D01*
G02X360532Y870606I243J1275D01*
G37*
G36*
G01X367932D02*
G02X370526I1297J0D01*
G02X370454Y870177I-1297J-3D01*
G01X370423Y870091D01*
X371230Y868693D01*
X371320Y868676D01*
G02X372376Y867401I-242J-1275D01*
G02X369780I-1298J0D01*
G02X369853Y867830I1297J0D01*
G01X369884Y867916D01*
X369077Y869314D01*
X368987Y869331D01*
G02X367932Y870606I243J1275D01*
G37*
G36*
G01X375332D02*
G02X377926I1297J0D01*
G02X377854Y870177I-1297J-3D01*
G01X377823Y870091D01*
X378630Y868693D01*
X378720Y868676D01*
G02X379776Y867401I-242J-1275D01*
G02X377180I-1298J0D01*
G02X377253Y867830I1297J0D01*
G01X377284Y867916D01*
X376477Y869314D01*
X376387Y869331D01*
G02X375332Y870606I243J1275D01*
G37*
G36*
G01X382732D02*
G02X385326I1297J0D01*
G02X385254Y870177I-1297J-3D01*
G01X385223Y870091D01*
X386030Y868693D01*
X386120Y868676D01*
G02X387176Y867401I-242J-1275D01*
G02X384580I-1298J0D01*
G02X384653Y867830I1297J0D01*
G01X384684Y867916D01*
X383877Y869314D01*
X383787Y869331D01*
G02X382732Y870606I243J1275D01*
G37*
G36*
G01X390132D02*
G02X392726I1297J0D01*
G02X392654Y870177I-1297J-3D01*
G01X392623Y870091D01*
X393430Y868693D01*
X393520Y868676D01*
G02X394576Y867401I-242J-1275D01*
G02X391980I-1298J0D01*
G02X392053Y867830I1297J0D01*
G01X392084Y867916D01*
X391277Y869314D01*
X391187Y869331D01*
G02X390132Y870606I243J1275D01*
G37*
G36*
G01X397532D02*
G02X400126I1297J0D01*
G02X400054Y870177I-1297J-3D01*
G01X400023Y870091D01*
X400830Y868693D01*
X400920Y868676D01*
G02X401976Y867401I-242J-1275D01*
G02X399380I-1298J0D01*
G02X399453Y867830I1297J0D01*
G01X399484Y867916D01*
X398677Y869314D01*
X398587Y869331D01*
G02X397532Y870606I243J1275D01*
G37*
G36*
G01X404932D02*
G02X407526I1297J0D01*
G02X407454Y870177I-1297J-3D01*
G01X407423Y870091D01*
X408230Y868693D01*
X408320Y868676D01*
G02X409376Y867401I-242J-1275D01*
G02X406780I-1298J0D01*
G02X406853Y867830I1297J0D01*
G01X406884Y867916D01*
X406077Y869314D01*
X405987Y869331D01*
G02X404932Y870606I243J1275D01*
G37*
G36*
G01X416032D02*
G02X418626I1297J0D01*
G02X417571Y869331I-1298J0D01*
G01X417481Y869314D01*
X416673Y867915D01*
X416703Y867828D01*
G02X416776Y867401I-1225J-429D01*
G02X414180I-1298J0D01*
G02X415238Y868676I1297J0D01*
G01X415328Y868693D01*
X416135Y870091D01*
X416104Y870178D01*
G02X416032Y870606I1225J426D01*
G37*
G36*
G01X423432D02*
G02X426026I1297J0D01*
G02X424971Y869331I-1298J0D01*
G01X424881Y869314D01*
X424073Y867915D01*
X424103Y867828D01*
G02X424176Y867401I-1225J-429D01*
G02X421580I-1298J0D01*
G02X422638Y868676I1297J0D01*
G01X422728Y868693D01*
X423535Y870091D01*
X423504Y870178D01*
G02X423432Y870606I1225J426D01*
G37*
G36*
G01X430832D02*
G02X433426I1297J0D01*
G02X432371Y869331I-1298J0D01*
G01X432281Y869314D01*
X431473Y867915D01*
X431503Y867828D01*
G02X431576Y867401I-1225J-429D01*
G02X428980I-1298J0D01*
G02X430038Y868676I1297J0D01*
G01X430128Y868693D01*
X430935Y870091D01*
X430904Y870178D01*
G02X430832Y870606I1225J426D01*
G37*
G36*
G01X438232D02*
G02X440826I1297J0D01*
G02X439771Y869331I-1298J0D01*
G01X439681Y869314D01*
X438873Y867915D01*
X438903Y867828D01*
G02X438976Y867401I-1225J-429D01*
G02X436380I-1298J0D01*
G02X437438Y868676I1297J0D01*
G01X437528Y868693D01*
X438335Y870091D01*
X438304Y870178D01*
G02X438232Y870606I1225J426D01*
G37*
G36*
G01X445632D02*
G02X448226I1297J0D01*
G02X447171Y869331I-1298J0D01*
G01X447081Y869314D01*
X446273Y867915D01*
X446303Y867828D01*
G02X446376Y867401I-1225J-429D01*
G02X443780I-1298J0D01*
G02X444838Y868676I1297J0D01*
G01X444928Y868693D01*
X445735Y870091D01*
X445704Y870178D01*
G02X445632Y870606I1225J426D01*
G37*
G36*
G01X453032D02*
G02X455626I1297J0D01*
G02X454571Y869331I-1298J0D01*
G01X454481Y869314D01*
X453673Y867915D01*
X453703Y867828D01*
G02X453776Y867401I-1225J-429D01*
G02X451180I-1298J0D01*
G02X452238Y868676I1297J0D01*
G01X452328Y868693D01*
X453135Y870091D01*
X453104Y870178D01*
G02X453032Y870606I1225J426D01*
G37*
G36*
G01X460432D02*
G02X463026I1297J0D01*
G02X461971Y869331I-1298J0D01*
G01X461881Y869314D01*
X461073Y867915D01*
X461103Y867828D01*
G02X461176Y867401I-1225J-429D01*
G02X458580I-1298J0D01*
G02X459638Y868676I1297J0D01*
G01X459728Y868693D01*
X460535Y870091D01*
X460504Y870178D01*
G02X460432Y870606I1225J426D01*
G37*
G36*
G01X467832D02*
G02X470426I1297J0D01*
G02X469371Y869331I-1298J0D01*
G01X469281Y869314D01*
X468473Y867915D01*
X468503Y867828D01*
G02X468576Y867401I-1225J-429D01*
G02X465980I-1298J0D01*
G02X467038Y868676I1297J0D01*
G01X467128Y868693D01*
X467935Y870091D01*
X467904Y870178D01*
G02X467832Y870606I1225J426D01*
G37*
G36*
G01X475232D02*
G02X477826I1297J0D01*
G02X476771Y869331I-1298J0D01*
G01X476681Y869314D01*
X475873Y867915D01*
X475903Y867828D01*
G02X475976Y867401I-1225J-429D01*
G02X473380I-1298J0D01*
G02X474438Y868676I1297J0D01*
G01X474528Y868693D01*
X475335Y870091D01*
X475304Y870178D01*
G02X475232Y870606I1225J426D01*
G37*
G36*
G01X482632D02*
G02X485226I1297J0D01*
G02X484171Y869331I-1298J0D01*
G01X484081Y869314D01*
X483273Y867915D01*
X483303Y867828D01*
G02X483376Y867401I-1225J-429D01*
G02X480780I-1298J0D01*
G02X481838Y868676I1297J0D01*
G01X481928Y868693D01*
X482735Y870091D01*
X482704Y870178D01*
G02X482632Y870606I1225J426D01*
G37*
G36*
G01X490032D02*
G02X492626I1297J0D01*
G02X491571Y869331I-1298J0D01*
G01X491481Y869314D01*
X490673Y867915D01*
X490703Y867828D01*
G02X490776Y867401I-1225J-429D01*
G02X488180I-1298J0D01*
G02X489238Y868676I1297J0D01*
G01X489328Y868693D01*
X490135Y870091D01*
X490104Y870178D01*
G02X490032Y870606I1225J426D01*
G37*
G36*
G01X497432D02*
G02X500026I1297J0D01*
G02X498971Y869331I-1298J0D01*
G01X498881Y869314D01*
X498073Y867915D01*
X498103Y867828D01*
G02X498176Y867401I-1225J-429D01*
G02X495580I-1298J0D01*
G02X496638Y868676I1297J0D01*
G01X496728Y868693D01*
X497535Y870091D01*
X497504Y870178D01*
G02X497432Y870606I1225J426D01*
G37*
G36*
G01X504832D02*
G02X507426I1297J0D01*
G02X506371Y869331I-1298J0D01*
G01X506281Y869314D01*
X505473Y867915D01*
X505503Y867828D01*
G02X505576Y867401I-1225J-429D01*
G02X502980I-1298J0D01*
G02X504038Y868676I1297J0D01*
G01X504128Y868693D01*
X504935Y870091D01*
X504904Y870178D01*
G02X504832Y870606I1225J426D01*
G37*
G36*
G01X512232D02*
G02X514826I1297J0D01*
G02X513771Y869331I-1298J0D01*
G01X513681Y869314D01*
X512873Y867915D01*
X512903Y867828D01*
G02X512976Y867401I-1225J-429D01*
G02X510380I-1298J0D01*
G02X511438Y868676I1297J0D01*
G01X511528Y868693D01*
X512335Y870091D01*
X512304Y870178D01*
G02X512232Y870606I1225J426D01*
G37*
G36*
G01X519632D02*
G02X522226I1297J0D01*
G02X521171Y869331I-1298J0D01*
G01X521081Y869314D01*
X520273Y867915D01*
X520303Y867828D01*
G02X520376Y867401I-1225J-429D01*
G02X517780I-1298J0D01*
G02X518838Y868676I1297J0D01*
G01X518928Y868693D01*
X519735Y870091D01*
X519704Y870178D01*
G02X519632Y870606I1225J426D01*
G37*
G36*
G01X527032D02*
G02X529626I1297J0D01*
G02X528571Y869331I-1298J0D01*
G01X528481Y869314D01*
X527674Y867916D01*
X527704Y867829D01*
G02X527776Y867401I-1225J-426D01*
G02X525182I-1297J0D01*
G02X526238Y868676I1298J0D01*
G01X526328Y868693D01*
X527135Y870091D01*
X527104Y870178D01*
G02X527032Y870606I1225J426D01*
G37*
G36*
G01X1329274D02*
G02X1331868I1297J0D01*
G02X1331796Y870177I-1297J-3D01*
G01X1331765Y870091D01*
X1332572Y868693D01*
X1332662Y868676D01*
G02X1333718Y867401I-242J-1275D01*
G02X1331122I-1298J0D01*
G02X1331195Y867830I1297J0D01*
G01X1331226Y867916D01*
X1330419Y869314D01*
X1330329Y869331D01*
G02X1329274Y870606I243J1275D01*
G37*
G36*
G01X1336674D02*
G02X1339268I1297J0D01*
G02X1339196Y870177I-1297J-3D01*
G01X1339165Y870091D01*
X1339972Y868693D01*
X1340062Y868676D01*
G02X1341118Y867401I-242J-1275D01*
G02X1338522I-1298J0D01*
G02X1338595Y867830I1297J0D01*
G01X1338626Y867916D01*
X1337819Y869314D01*
X1337729Y869331D01*
G02X1336674Y870606I243J1275D01*
G37*
G36*
G01X1344074D02*
G02X1346668I1297J0D01*
G02X1346596Y870177I-1297J-3D01*
G01X1346565Y870091D01*
X1347372Y868693D01*
X1347462Y868676D01*
G02X1348518Y867401I-242J-1275D01*
G02X1345922I-1298J0D01*
G02X1345995Y867830I1297J0D01*
G01X1346026Y867916D01*
X1345219Y869314D01*
X1345129Y869331D01*
G02X1344074Y870606I243J1275D01*
G37*
G36*
G01X1351474D02*
G02X1354068I1297J0D01*
G02X1353996Y870177I-1297J-3D01*
G01X1353965Y870091D01*
X1354772Y868693D01*
X1354862Y868676D01*
G02X1355918Y867401I-242J-1275D01*
G02X1353322I-1298J0D01*
G02X1353395Y867830I1297J0D01*
G01X1353426Y867916D01*
X1352619Y869314D01*
X1352529Y869331D01*
G02X1351474Y870606I243J1275D01*
G37*
G36*
G01X1358874D02*
G02X1361468I1297J0D01*
G02X1361396Y870177I-1297J-3D01*
G01X1361365Y870091D01*
X1362172Y868693D01*
X1362262Y868676D01*
G02X1363318Y867401I-242J-1275D01*
G02X1360722I-1298J0D01*
G02X1360795Y867830I1297J0D01*
G01X1360826Y867916D01*
X1360019Y869314D01*
X1359929Y869331D01*
G02X1358874Y870606I243J1275D01*
G37*
G36*
G01X1366274D02*
G02X1368868I1297J0D01*
G02X1368796Y870177I-1297J-3D01*
G01X1368765Y870091D01*
X1369572Y868693D01*
X1369662Y868676D01*
G02X1370718Y867401I-242J-1275D01*
G02X1368122I-1298J0D01*
G02X1368195Y867830I1297J0D01*
G01X1368226Y867916D01*
X1367419Y869314D01*
X1367329Y869331D01*
G02X1366274Y870606I243J1275D01*
G37*
G36*
G01X1373674D02*
G02X1376268I1297J0D01*
G02X1376196Y870177I-1297J-3D01*
G01X1376165Y870091D01*
X1376972Y868693D01*
X1377062Y868676D01*
G02X1378118Y867401I-242J-1275D01*
G02X1375522I-1298J0D01*
G02X1375595Y867830I1297J0D01*
G01X1375626Y867916D01*
X1374819Y869314D01*
X1374729Y869331D01*
G02X1373674Y870606I243J1275D01*
G37*
G36*
G01X1381074D02*
G02X1383668I1297J0D01*
G02X1383596Y870177I-1297J-3D01*
G01X1383565Y870091D01*
X1384372Y868693D01*
X1384462Y868676D01*
G02X1385518Y867401I-242J-1275D01*
G02X1382922I-1298J0D01*
G02X1382995Y867830I1297J0D01*
G01X1383026Y867916D01*
X1382219Y869314D01*
X1382129Y869331D01*
G02X1381074Y870606I243J1275D01*
G37*
G36*
G01X1392174D02*
G02X1394768I1297J0D01*
G02X1393713Y869331I-1298J0D01*
G01X1393623Y869314D01*
X1392815Y867915D01*
X1392845Y867828D01*
G02X1392918Y867401I-1225J-429D01*
G02X1390322I-1298J0D01*
G02X1391380Y868676I1297J0D01*
G01X1391470Y868693D01*
X1392277Y870091D01*
X1392246Y870178D01*
G02X1392174Y870606I1225J426D01*
G37*
G36*
G01X1399574D02*
G02X1402168I1297J0D01*
G02X1401113Y869331I-1298J0D01*
G01X1401023Y869314D01*
X1400215Y867915D01*
X1400245Y867828D01*
G02X1400318Y867401I-1225J-429D01*
G02X1397722I-1298J0D01*
G02X1398780Y868676I1297J0D01*
G01X1398870Y868693D01*
X1399677Y870091D01*
X1399646Y870178D01*
G02X1399574Y870606I1225J426D01*
G37*
G36*
G01X1406974D02*
G02X1409568I1297J0D01*
G02X1408513Y869331I-1298J0D01*
G01X1408423Y869314D01*
X1407615Y867915D01*
X1407645Y867828D01*
G02X1407718Y867401I-1225J-429D01*
G02X1405122I-1298J0D01*
G02X1406180Y868676I1297J0D01*
G01X1406270Y868693D01*
X1407077Y870091D01*
X1407046Y870178D01*
G02X1406974Y870606I1225J426D01*
G37*
G36*
G01X1414374D02*
G02X1416968I1297J0D01*
G02X1415913Y869331I-1298J0D01*
G01X1415823Y869314D01*
X1415015Y867915D01*
X1415045Y867828D01*
G02X1415118Y867401I-1225J-429D01*
G02X1412522I-1298J0D01*
G02X1413580Y868676I1297J0D01*
G01X1413670Y868693D01*
X1414477Y870091D01*
X1414446Y870178D01*
G02X1414374Y870606I1225J426D01*
G37*
G36*
G01X1421774D02*
G02X1424368I1297J0D01*
G02X1423313Y869331I-1298J0D01*
G01X1423223Y869314D01*
X1422415Y867915D01*
X1422445Y867828D01*
G02X1422518Y867401I-1225J-429D01*
G02X1419922I-1298J0D01*
G02X1420980Y868676I1297J0D01*
G01X1421070Y868693D01*
X1421877Y870091D01*
X1421846Y870178D01*
G02X1421774Y870606I1225J426D01*
G37*
G36*
G01X1429174D02*
G02X1431768I1297J0D01*
G02X1430713Y869331I-1298J0D01*
G01X1430623Y869314D01*
X1429815Y867915D01*
X1429845Y867828D01*
G02X1429918Y867401I-1225J-429D01*
G02X1427322I-1298J0D01*
G02X1428380Y868676I1297J0D01*
G01X1428470Y868693D01*
X1429277Y870091D01*
X1429246Y870178D01*
G02X1429174Y870606I1225J426D01*
G37*
G36*
G01X1436574D02*
G02X1439168I1297J0D01*
G02X1438113Y869331I-1298J0D01*
G01X1438023Y869314D01*
X1437215Y867915D01*
X1437245Y867828D01*
G02X1437318Y867401I-1225J-429D01*
G02X1434722I-1298J0D01*
G02X1435780Y868676I1297J0D01*
G01X1435870Y868693D01*
X1436677Y870091D01*
X1436646Y870178D01*
G02X1436574Y870606I1225J426D01*
G37*
G36*
G01X1443974D02*
G02X1446568I1297J0D01*
G02X1445513Y869331I-1298J0D01*
G01X1445423Y869314D01*
X1444615Y867915D01*
X1444645Y867828D01*
G02X1444718Y867401I-1225J-429D01*
G02X1442122I-1298J0D01*
G02X1443180Y868676I1297J0D01*
G01X1443270Y868693D01*
X1444077Y870091D01*
X1444046Y870178D01*
G02X1443974Y870606I1225J426D01*
G37*
G36*
G01X1451374D02*
G02X1453968I1297J0D01*
G02X1452913Y869331I-1298J0D01*
G01X1452823Y869314D01*
X1452015Y867915D01*
X1452045Y867828D01*
G02X1452118Y867401I-1225J-429D01*
G02X1449522I-1298J0D01*
G02X1450580Y868676I1297J0D01*
G01X1450670Y868693D01*
X1451477Y870091D01*
X1451446Y870178D01*
G02X1451374Y870606I1225J426D01*
G37*
G36*
G01X1458774D02*
G02X1461368I1297J0D01*
G02X1460313Y869331I-1298J0D01*
G01X1460223Y869314D01*
X1459415Y867915D01*
X1459445Y867828D01*
G02X1459518Y867401I-1225J-429D01*
G02X1456922I-1298J0D01*
G02X1457980Y868676I1297J0D01*
G01X1458070Y868693D01*
X1458877Y870091D01*
X1458846Y870178D01*
G02X1458774Y870606I1225J426D01*
G37*
G36*
G01X1466174D02*
G02X1468768I1297J0D01*
G02X1467713Y869331I-1298J0D01*
G01X1467623Y869314D01*
X1466815Y867915D01*
X1466845Y867828D01*
G02X1466918Y867401I-1225J-429D01*
G02X1464322I-1298J0D01*
G02X1465380Y868676I1297J0D01*
G01X1465470Y868693D01*
X1466277Y870091D01*
X1466246Y870178D01*
G02X1466174Y870606I1225J426D01*
G37*
G36*
G01X1473574D02*
G02X1476168I1297J0D01*
G02X1475113Y869331I-1298J0D01*
G01X1475023Y869314D01*
X1474215Y867915D01*
X1474245Y867828D01*
G02X1474318Y867401I-1225J-429D01*
G02X1471722I-1298J0D01*
G02X1472780Y868676I1297J0D01*
G01X1472870Y868693D01*
X1473677Y870091D01*
X1473646Y870178D01*
G02X1473574Y870606I1225J426D01*
G37*
G36*
G01X1480974D02*
G02X1483568I1297J0D01*
G02X1482513Y869331I-1298J0D01*
G01X1482423Y869314D01*
X1481615Y867915D01*
X1481645Y867828D01*
G02X1481718Y867401I-1225J-429D01*
G02X1479122I-1298J0D01*
G02X1480180Y868676I1297J0D01*
G01X1480270Y868693D01*
X1481077Y870091D01*
X1481046Y870178D01*
G02X1480974Y870606I1225J426D01*
G37*
G36*
G01X1488374D02*
G02X1490968I1297J0D01*
G02X1489913Y869331I-1298J0D01*
G01X1489823Y869314D01*
X1489015Y867915D01*
X1489045Y867828D01*
G02X1489118Y867401I-1225J-429D01*
G02X1486522I-1298J0D01*
G02X1487580Y868676I1297J0D01*
G01X1487670Y868693D01*
X1488477Y870091D01*
X1488446Y870178D01*
G02X1488374Y870606I1225J426D01*
G37*
G36*
G01X1495774D02*
G02X1498368I1297J0D01*
G02X1497313Y869331I-1298J0D01*
G01X1497223Y869314D01*
X1496415Y867915D01*
X1496445Y867828D01*
G02X1496518Y867401I-1225J-429D01*
G02X1493922I-1298J0D01*
G02X1494980Y868676I1297J0D01*
G01X1495070Y868693D01*
X1495877Y870091D01*
X1495846Y870178D01*
G02X1495774Y870606I1225J426D01*
G37*
G36*
G01X1503174D02*
G02X1505768I1297J0D01*
G02X1504713Y869331I-1298J0D01*
G01X1504623Y869314D01*
X1503816Y867916D01*
X1503846Y867829D01*
G02X1503918Y867401I-1225J-426D01*
G02X1501324I-1297J0D01*
G02X1502380Y868676I1298J0D01*
G01X1502470Y868693D01*
X1503277Y870091D01*
X1503246Y870178D01*
G02X1503174Y870606I1225J426D01*
G37*
G36*
G01X351280Y873810D02*
G02X353876I1298J0D01*
G02X352820Y872535I-1298J0D01*
G01X352730Y872518D01*
X351923Y871121D01*
X351954Y871034D01*
G02X352026Y870606I-1225J-426D01*
G02X349432I-1297J0D01*
G02X350487Y871881I1298J0D01*
G01X350577Y871898D01*
X351384Y873295D01*
X351353Y873382D01*
G02X351280Y873810I1225J429D01*
G37*
G36*
G01X358680D02*
G02X361276I1298J0D01*
G02X360220Y872535I-1298J0D01*
G01X360130Y872518D01*
X359323Y871121D01*
X359354Y871034D01*
G02X359426Y870606I-1225J-426D01*
G02X356832I-1297J0D01*
G02X357887Y871881I1298J0D01*
G01X357977Y871898D01*
X358784Y873295D01*
X358753Y873382D01*
G02X358680Y873810I1225J429D01*
G37*
G36*
G01X366080D02*
G02X368676I1298J0D01*
G02X367620Y872535I-1298J0D01*
G01X367530Y872518D01*
X366723Y871121D01*
X366754Y871034D01*
G02X366826Y870606I-1225J-426D01*
G02X364232I-1297J0D01*
G02X365287Y871881I1298J0D01*
G01X365377Y871898D01*
X366184Y873295D01*
X366153Y873382D01*
G02X366080Y873810I1225J429D01*
G37*
G36*
G01X373480D02*
G02X376076I1298J0D01*
G02X375020Y872535I-1298J0D01*
G01X374930Y872518D01*
X374123Y871121D01*
X374154Y871034D01*
G02X374226Y870606I-1225J-426D01*
G02X371632I-1297J0D01*
G02X372687Y871881I1298J0D01*
G01X372777Y871898D01*
X373584Y873295D01*
X373553Y873382D01*
G02X373480Y873810I1225J429D01*
G37*
G36*
G01X380880D02*
G02X383476I1298J0D01*
G02X382420Y872535I-1298J0D01*
G01X382330Y872518D01*
X381523Y871121D01*
X381554Y871034D01*
G02X381626Y870606I-1225J-426D01*
G02X379032I-1297J0D01*
G02X380087Y871881I1298J0D01*
G01X380177Y871898D01*
X380984Y873295D01*
X380953Y873382D01*
G02X380880Y873810I1225J429D01*
G37*
G36*
G01X388280D02*
G02X390876I1298J0D01*
G02X389820Y872535I-1298J0D01*
G01X389730Y872518D01*
X388923Y871121D01*
X388954Y871034D01*
G02X389026Y870606I-1225J-426D01*
G02X386432I-1297J0D01*
G02X387487Y871881I1298J0D01*
G01X387577Y871898D01*
X388384Y873295D01*
X388353Y873382D01*
G02X388280Y873810I1225J429D01*
G37*
G36*
G01X395680D02*
G02X398276I1298J0D01*
G02X397220Y872535I-1298J0D01*
G01X397130Y872518D01*
X396323Y871121D01*
X396354Y871034D01*
G02X396426Y870606I-1225J-426D01*
G02X393832I-1297J0D01*
G02X394887Y871881I1298J0D01*
G01X394977Y871898D01*
X395784Y873295D01*
X395753Y873382D01*
G02X395680Y873810I1225J429D01*
G37*
G36*
G01X403080D02*
G02X405676I1298J0D01*
G02X404620Y872535I-1298J0D01*
G01X404530Y872518D01*
X403723Y871121D01*
X403754Y871034D01*
G02X403826Y870606I-1225J-426D01*
G02X401232I-1297J0D01*
G02X402287Y871881I1298J0D01*
G01X402377Y871898D01*
X403184Y873295D01*
X403153Y873382D01*
G02X403080Y873810I1225J429D01*
G37*
G36*
G01X410480D02*
G02X413076I1298J0D01*
G02X413003Y873381I-1297J0D01*
G01X412972Y873295D01*
X413778Y871898D01*
X413868Y871881D01*
G02X414926Y870606I-239J-1275D01*
G02X412332I-1297J0D01*
G02X412403Y871032I1297J3D01*
G01X412434Y871119D01*
X411626Y872518D01*
X411536Y872535D01*
G02X410480Y873810I242J1275D01*
G37*
G36*
G01X417880D02*
G02X420476I1298J0D01*
G02X420403Y873381I-1297J0D01*
G01X420372Y873295D01*
X421178Y871898D01*
X421268Y871881D01*
G02X422326Y870606I-239J-1275D01*
G02X419732I-1297J0D01*
G02X419803Y871032I1297J3D01*
G01X419834Y871119D01*
X419026Y872518D01*
X418936Y872535D01*
G02X417880Y873810I242J1275D01*
G37*
G36*
G01X425280D02*
G02X427876I1298J0D01*
G02X427803Y873381I-1297J0D01*
G01X427772Y873295D01*
X428578Y871898D01*
X428668Y871881D01*
G02X429726Y870606I-239J-1275D01*
G02X427132I-1297J0D01*
G02X427203Y871032I1297J3D01*
G01X427234Y871119D01*
X426426Y872518D01*
X426336Y872535D01*
G02X425280Y873810I242J1275D01*
G37*
G36*
G01X432682D02*
G02X435276I1297J0D01*
G02X435204Y873381I-1297J-3D01*
G01X435173Y873295D01*
X435979Y871898D01*
X436069Y871881D01*
G02X437126Y870606I-240J-1275D01*
G02X434532I-1297J0D01*
G01Y870608D01*
G02X434604Y871033I1297J-1D01*
G01X434634Y871120D01*
X433827Y872518D01*
X433737Y872535D01*
G02X432682Y873810I243J1275D01*
G37*
G36*
G01X440080D02*
G02X442676I1298J0D01*
G02X442603Y873381I-1297J0D01*
G01X442572Y873295D01*
X443378Y871898D01*
X443468Y871881D01*
G02X444526Y870606I-239J-1275D01*
G02X441932I-1297J0D01*
G02X442003Y871032I1297J3D01*
G01X442034Y871119D01*
X441226Y872518D01*
X441136Y872535D01*
G02X440080Y873810I242J1275D01*
G37*
G36*
G01X447482D02*
G02X450076I1297J0D01*
G02X450004Y873381I-1297J-3D01*
G01X449973Y873295D01*
X450779Y871898D01*
X450869Y871881D01*
G02X451926Y870606I-240J-1275D01*
G02X449332I-1297J0D01*
G01Y870608D01*
G02X449404Y871033I1297J-1D01*
G01X449434Y871120D01*
X448627Y872518D01*
X448537Y872535D01*
G02X447482Y873810I243J1275D01*
G37*
G36*
G01X454880D02*
G02X457476I1298J0D01*
G02X457403Y873381I-1297J0D01*
G01X457372Y873295D01*
X458178Y871898D01*
X458268Y871881D01*
G02X459326Y870606I-239J-1275D01*
G02X456732I-1297J0D01*
G02X456803Y871032I1297J3D01*
G01X456834Y871119D01*
X456026Y872518D01*
X455936Y872535D01*
G02X454880Y873810I242J1275D01*
G37*
G36*
G01X462280D02*
G02X464876I1298J0D01*
G02X464803Y873381I-1297J0D01*
G01X464772Y873295D01*
X465578Y871898D01*
X465668Y871881D01*
G02X466726Y870606I-239J-1275D01*
G02X464132I-1297J0D01*
G02X464203Y871032I1297J3D01*
G01X464234Y871119D01*
X463426Y872518D01*
X463336Y872535D01*
G02X462280Y873810I242J1275D01*
G37*
G36*
G01X477080D02*
G02X479676I1298J0D01*
G02X479603Y873381I-1297J0D01*
G01X479572Y873295D01*
X480378Y871898D01*
X480468Y871881D01*
G02X481526Y870606I-239J-1275D01*
G02X478932I-1297J0D01*
G02X479003Y871032I1297J3D01*
G01X479034Y871119D01*
X478226Y872518D01*
X478136Y872535D01*
G02X477080Y873810I242J1275D01*
G37*
G36*
G01X484480D02*
G02X487076I1298J0D01*
G02X487003Y873381I-1297J0D01*
G01X486972Y873295D01*
X487778Y871898D01*
X487868Y871881D01*
G02X488926Y870606I-239J-1275D01*
G02X486332I-1297J0D01*
G02X486403Y871032I1297J3D01*
G01X486434Y871119D01*
X485626Y872518D01*
X485536Y872535D01*
G02X484480Y873810I242J1275D01*
G37*
G36*
G01X491880D02*
G02X494476I1298J0D01*
G02X494403Y873381I-1297J0D01*
G01X494372Y873295D01*
X495178Y871898D01*
X495268Y871881D01*
G02X496326Y870606I-239J-1275D01*
G02X493732I-1297J0D01*
G02X493803Y871032I1297J3D01*
G01X493834Y871119D01*
X493026Y872518D01*
X492936Y872535D01*
G02X491880Y873810I242J1275D01*
G37*
G36*
G01X499280D02*
G02X501876I1298J0D01*
G02X501803Y873381I-1297J0D01*
G01X501772Y873295D01*
X502578Y871898D01*
X502668Y871881D01*
G02X503726Y870606I-239J-1275D01*
G02X501132I-1297J0D01*
G02X501203Y871032I1297J3D01*
G01X501234Y871119D01*
X500426Y872518D01*
X500336Y872535D01*
G02X499280Y873810I242J1275D01*
G37*
G36*
G01X506680D02*
G02X509276I1298J0D01*
G02X509203Y873381I-1297J0D01*
G01X509172Y873295D01*
X509978Y871898D01*
X510068Y871881D01*
G02X511126Y870606I-239J-1275D01*
G02X508532I-1297J0D01*
G02X508603Y871032I1297J3D01*
G01X508634Y871119D01*
X507826Y872518D01*
X507736Y872535D01*
G02X506680Y873810I242J1275D01*
G37*
G36*
G01X514080D02*
G02X516676I1298J0D01*
G02X516603Y873381I-1297J0D01*
G01X516572Y873295D01*
X517378Y871898D01*
X517468Y871881D01*
G02X518526Y870606I-239J-1275D01*
G02X515932I-1297J0D01*
G02X516003Y871032I1297J3D01*
G01X516034Y871119D01*
X515226Y872518D01*
X515136Y872535D01*
G02X514080Y873810I242J1275D01*
G37*
G36*
G01X1327422D02*
G02X1330018I1298J0D01*
G02X1328962Y872535I-1298J0D01*
G01X1328872Y872518D01*
X1328065Y871121D01*
X1328096Y871034D01*
G02X1328168Y870606I-1225J-426D01*
G02X1325574I-1297J0D01*
G02X1326629Y871881I1298J0D01*
G01X1326719Y871898D01*
X1327526Y873295D01*
X1327495Y873382D01*
G02X1327422Y873810I1225J429D01*
G37*
G36*
G01X1334822D02*
G02X1337418I1298J0D01*
G02X1336362Y872535I-1298J0D01*
G01X1336272Y872518D01*
X1335465Y871121D01*
X1335496Y871034D01*
G02X1335568Y870606I-1225J-426D01*
G02X1332974I-1297J0D01*
G02X1334029Y871881I1298J0D01*
G01X1334119Y871898D01*
X1334926Y873295D01*
X1334895Y873382D01*
G02X1334822Y873810I1225J429D01*
G37*
G36*
G01X1342222D02*
G02X1344818I1298J0D01*
G02X1343762Y872535I-1298J0D01*
G01X1343672Y872518D01*
X1342865Y871121D01*
X1342896Y871034D01*
G02X1342968Y870606I-1225J-426D01*
G02X1340374I-1297J0D01*
G02X1341429Y871881I1298J0D01*
G01X1341519Y871898D01*
X1342326Y873295D01*
X1342295Y873382D01*
G02X1342222Y873810I1225J429D01*
G37*
G36*
G01X1349622D02*
G02X1352218I1298J0D01*
G02X1351162Y872535I-1298J0D01*
G01X1351072Y872518D01*
X1350265Y871121D01*
X1350296Y871034D01*
G02X1350368Y870606I-1225J-426D01*
G02X1347774I-1297J0D01*
G02X1348829Y871881I1298J0D01*
G01X1348919Y871898D01*
X1349726Y873295D01*
X1349695Y873382D01*
G02X1349622Y873810I1225J429D01*
G37*
G36*
G01X1357022D02*
G02X1359618I1298J0D01*
G02X1358562Y872535I-1298J0D01*
G01X1358472Y872518D01*
X1357665Y871121D01*
X1357696Y871034D01*
G02X1357768Y870606I-1225J-426D01*
G02X1355174I-1297J0D01*
G02X1356229Y871881I1298J0D01*
G01X1356319Y871898D01*
X1357126Y873295D01*
X1357095Y873382D01*
G02X1357022Y873810I1225J429D01*
G37*
G36*
G01X1364422D02*
G02X1367018I1298J0D01*
G02X1365962Y872535I-1298J0D01*
G01X1365872Y872518D01*
X1365065Y871121D01*
X1365096Y871034D01*
G02X1365168Y870606I-1225J-426D01*
G02X1362574I-1297J0D01*
G02X1363629Y871881I1298J0D01*
G01X1363719Y871898D01*
X1364526Y873295D01*
X1364495Y873382D01*
G02X1364422Y873810I1225J429D01*
G37*
G36*
G01X1371822D02*
G02X1374418I1298J0D01*
G02X1373362Y872535I-1298J0D01*
G01X1373272Y872518D01*
X1372465Y871121D01*
X1372496Y871034D01*
G02X1372568Y870606I-1225J-426D01*
G02X1369974I-1297J0D01*
G02X1371029Y871881I1298J0D01*
G01X1371119Y871898D01*
X1371926Y873295D01*
X1371895Y873382D01*
G02X1371822Y873810I1225J429D01*
G37*
G36*
G01X1379222D02*
G02X1381818I1298J0D01*
G02X1380762Y872535I-1298J0D01*
G01X1380672Y872518D01*
X1379865Y871121D01*
X1379896Y871034D01*
G02X1379968Y870606I-1225J-426D01*
G02X1377374I-1297J0D01*
G02X1378429Y871881I1298J0D01*
G01X1378519Y871898D01*
X1379326Y873295D01*
X1379295Y873382D01*
G02X1379222Y873810I1225J429D01*
G37*
G36*
G01X1386622D02*
G02X1389218I1298J0D01*
G02X1389145Y873381I-1297J0D01*
G01X1389114Y873295D01*
X1389920Y871898D01*
X1390010Y871881D01*
G02X1391068Y870606I-239J-1275D01*
G02X1388474I-1297J0D01*
G02X1388545Y871032I1297J3D01*
G01X1388576Y871119D01*
X1387768Y872518D01*
X1387678Y872535D01*
G02X1386622Y873810I242J1275D01*
G37*
G36*
G01X1394022D02*
G02X1396618I1298J0D01*
G02X1396545Y873381I-1297J0D01*
G01X1396514Y873295D01*
X1397320Y871898D01*
X1397410Y871881D01*
G02X1398468Y870606I-239J-1275D01*
G02X1395874I-1297J0D01*
G02X1395945Y871032I1297J3D01*
G01X1395976Y871119D01*
X1395168Y872518D01*
X1395078Y872535D01*
G02X1394022Y873810I242J1275D01*
G37*
G36*
G01X1401422D02*
G02X1404018I1298J0D01*
G02X1403945Y873381I-1297J0D01*
G01X1403914Y873295D01*
X1404720Y871898D01*
X1404810Y871881D01*
G02X1405868Y870606I-239J-1275D01*
G02X1403274I-1297J0D01*
G02X1403345Y871032I1297J3D01*
G01X1403376Y871119D01*
X1402568Y872518D01*
X1402478Y872535D01*
G02X1401422Y873810I242J1275D01*
G37*
G36*
G01X1408824D02*
G02X1411418I1297J0D01*
G02X1411346Y873381I-1297J-3D01*
G01X1411315Y873295D01*
X1412121Y871898D01*
X1412211Y871881D01*
G02X1413268Y870606I-240J-1275D01*
G02X1410674I-1297J0D01*
G01Y870608D01*
G02X1410746Y871033I1297J-1D01*
G01X1410776Y871120D01*
X1409969Y872518D01*
X1409879Y872535D01*
G02X1408824Y873810I243J1275D01*
G37*
G36*
G01X1416222D02*
G02X1418818I1298J0D01*
G02X1418745Y873381I-1297J0D01*
G01X1418714Y873295D01*
X1419520Y871898D01*
X1419610Y871881D01*
G02X1420668Y870606I-239J-1275D01*
G02X1418074I-1297J0D01*
G02X1418145Y871032I1297J3D01*
G01X1418176Y871119D01*
X1417368Y872518D01*
X1417278Y872535D01*
G02X1416222Y873810I242J1275D01*
G37*
G36*
G01X1423624D02*
G02X1426218I1297J0D01*
G02X1426146Y873381I-1297J-3D01*
G01X1426115Y873295D01*
X1426921Y871898D01*
X1427011Y871881D01*
G02X1428068Y870606I-240J-1275D01*
G02X1425474I-1297J0D01*
G01Y870608D01*
G02X1425546Y871033I1297J-1D01*
G01X1425576Y871120D01*
X1424769Y872518D01*
X1424679Y872535D01*
G02X1423624Y873810I243J1275D01*
G37*
G36*
G01X1431022D02*
G02X1433618I1298J0D01*
G02X1433545Y873381I-1297J0D01*
G01X1433514Y873295D01*
X1434320Y871898D01*
X1434410Y871881D01*
G02X1435468Y870606I-239J-1275D01*
G02X1432874I-1297J0D01*
G02X1432945Y871032I1297J3D01*
G01X1432976Y871119D01*
X1432168Y872518D01*
X1432078Y872535D01*
G02X1431022Y873810I242J1275D01*
G37*
G36*
G01X1438422D02*
G02X1441018I1298J0D01*
G02X1440945Y873381I-1297J0D01*
G01X1440914Y873295D01*
X1441720Y871898D01*
X1441810Y871881D01*
G02X1442868Y870606I-239J-1275D01*
G02X1440274I-1297J0D01*
G02X1440345Y871032I1297J3D01*
G01X1440376Y871119D01*
X1439568Y872518D01*
X1439478Y872535D01*
G02X1438422Y873810I242J1275D01*
G37*
G36*
G01X1453222D02*
G02X1455818I1298J0D01*
G02X1455745Y873381I-1297J0D01*
G01X1455714Y873295D01*
X1456520Y871898D01*
X1456610Y871881D01*
G02X1457668Y870606I-239J-1275D01*
G02X1455074I-1297J0D01*
G02X1455145Y871032I1297J3D01*
G01X1455176Y871119D01*
X1454368Y872518D01*
X1454278Y872535D01*
G02X1453222Y873810I242J1275D01*
G37*
G36*
G01X1460622D02*
G02X1463218I1298J0D01*
G02X1463145Y873381I-1297J0D01*
G01X1463114Y873295D01*
X1463920Y871898D01*
X1464010Y871881D01*
G02X1465068Y870606I-239J-1275D01*
G02X1462474I-1297J0D01*
G02X1462545Y871032I1297J3D01*
G01X1462576Y871119D01*
X1461768Y872518D01*
X1461678Y872535D01*
G02X1460622Y873810I242J1275D01*
G37*
G36*
G01X1468022D02*
G02X1470618I1298J0D01*
G02X1470545Y873381I-1297J0D01*
G01X1470514Y873295D01*
X1471320Y871898D01*
X1471410Y871881D01*
G02X1472468Y870606I-239J-1275D01*
G02X1469874I-1297J0D01*
G02X1469945Y871032I1297J3D01*
G01X1469976Y871119D01*
X1469168Y872518D01*
X1469078Y872535D01*
G02X1468022Y873810I242J1275D01*
G37*
G36*
G01X1475422D02*
G02X1478018I1298J0D01*
G02X1477945Y873381I-1297J0D01*
G01X1477914Y873295D01*
X1478720Y871898D01*
X1478810Y871881D01*
G02X1479868Y870606I-239J-1275D01*
G02X1477274I-1297J0D01*
G02X1477345Y871032I1297J3D01*
G01X1477376Y871119D01*
X1476568Y872518D01*
X1476478Y872535D01*
G02X1475422Y873810I242J1275D01*
G37*
G36*
G01X1482822D02*
G02X1485418I1298J0D01*
G02X1485345Y873381I-1297J0D01*
G01X1485314Y873295D01*
X1486120Y871898D01*
X1486210Y871881D01*
G02X1487268Y870606I-239J-1275D01*
G02X1484674I-1297J0D01*
G02X1484745Y871032I1297J3D01*
G01X1484776Y871119D01*
X1483968Y872518D01*
X1483878Y872535D01*
G02X1482822Y873810I242J1275D01*
G37*
G36*
G01X1490222D02*
G02X1492818I1298J0D01*
G02X1492745Y873381I-1297J0D01*
G01X1492714Y873295D01*
X1493520Y871898D01*
X1493610Y871881D01*
G02X1494668Y870606I-239J-1275D01*
G02X1492074I-1297J0D01*
G02X1492145Y871032I1297J3D01*
G01X1492176Y871119D01*
X1491368Y872518D01*
X1491278Y872535D01*
G02X1490222Y873810I242J1275D01*
G37*
G36*
G01X367932Y883423D02*
G02X370526I1297J0D01*
G02X370454Y882994I-1297J-3D01*
G01X370423Y882908D01*
X371229Y881511D01*
X371319Y881494D01*
G02X372376Y880219I-240J-1275D01*
G02X369780I-1298J0D01*
G02X369853Y880647I1298J-1D01*
G01X369883Y880734D01*
X369077Y882131D01*
X368987Y882148D01*
G02X367932Y883423I243J1275D01*
G37*
G36*
G01X375332D02*
G02X377926I1297J0D01*
G02X377854Y882994I-1297J-3D01*
G01X377823Y882908D01*
X378629Y881511D01*
X378719Y881494D01*
G02X379776Y880219I-240J-1275D01*
G02X377180I-1298J0D01*
G02X377253Y880647I1298J-1D01*
G01X377283Y880734D01*
X376477Y882131D01*
X376387Y882148D01*
G02X375332Y883423I243J1275D01*
G37*
G36*
G01X382732D02*
G02X385326I1297J0D01*
G02X385254Y882994I-1297J-3D01*
G01X385223Y882908D01*
X386029Y881511D01*
X386119Y881494D01*
G02X387176Y880219I-240J-1275D01*
G02X384580I-1298J0D01*
G02X384653Y880647I1298J-1D01*
G01X384683Y880734D01*
X383877Y882131D01*
X383787Y882148D01*
G02X382732Y883423I243J1275D01*
G37*
G36*
G01X390132D02*
G02X392726I1297J0D01*
G02X392654Y882994I-1297J-3D01*
G01X392623Y882908D01*
X393429Y881511D01*
X393519Y881494D01*
G02X394576Y880219I-240J-1275D01*
G02X391980I-1298J0D01*
G02X392053Y880647I1298J-1D01*
G01X392083Y880734D01*
X391277Y882131D01*
X391187Y882148D01*
G02X390132Y883423I243J1275D01*
G37*
G36*
G01X397532D02*
G02X400126I1297J0D01*
G02X400054Y882994I-1297J-3D01*
G01X400023Y882908D01*
X400829Y881511D01*
X400919Y881494D01*
G02X401976Y880219I-240J-1275D01*
G02X399380I-1298J0D01*
G02X399453Y880647I1298J-1D01*
G01X399483Y880734D01*
X398677Y882131D01*
X398587Y882148D01*
G02X397532Y883423I243J1275D01*
G37*
G36*
G01X404932D02*
G02X407526I1297J0D01*
G02X407454Y882994I-1297J-3D01*
G01X407423Y882908D01*
X408229Y881511D01*
X408319Y881494D01*
G02X409376Y880219I-240J-1275D01*
G02X406780I-1298J0D01*
G02X406853Y880647I1298J-1D01*
G01X406883Y880734D01*
X406077Y882131D01*
X405987Y882148D01*
G02X404932Y883423I243J1275D01*
G37*
G36*
G01X412332D02*
G02X414926I1297J0D01*
G02X414854Y882994I-1297J-3D01*
G01X414823Y882908D01*
X415629Y881511D01*
X415719Y881494D01*
G02X416776Y880219I-240J-1275D01*
G02X414180I-1298J0D01*
G02X414253Y880647I1298J-1D01*
G01X414283Y880734D01*
X413477Y882131D01*
X413387Y882148D01*
G02X412332Y883423I243J1275D01*
G37*
G36*
G01X419732D02*
G02X422326I1297J0D01*
G02X422254Y882994I-1297J-3D01*
G01X422223Y882908D01*
X423029Y881511D01*
X423119Y881494D01*
G02X424176Y880219I-240J-1275D01*
G02X421580I-1298J0D01*
G02X421653Y880647I1298J-1D01*
G01X421683Y880734D01*
X420877Y882131D01*
X420787Y882148D01*
G02X419732Y883423I243J1275D01*
G37*
G36*
G01X427132D02*
G02X429726I1297J0D01*
G02X429654Y882994I-1297J-3D01*
G01X429623Y882908D01*
X430429Y881511D01*
X430519Y881494D01*
G02X431576Y880219I-240J-1275D01*
G02X428980I-1298J0D01*
G02X429053Y880647I1298J-1D01*
G01X429083Y880734D01*
X428277Y882131D01*
X428187Y882148D01*
G02X427132Y883423I243J1275D01*
G37*
G36*
G01X434532D02*
G02X437126I1297J0D01*
G02X437054Y882994I-1297J-3D01*
G01X437023Y882908D01*
X437829Y881511D01*
X437919Y881494D01*
G02X438976Y880219I-240J-1275D01*
G02X436380I-1298J0D01*
G02X436453Y880647I1298J-1D01*
G01X436483Y880734D01*
X435677Y882131D01*
X435587Y882148D01*
G02X434532Y883423I243J1275D01*
G37*
G36*
G01X441932D02*
G02X444526I1297J0D01*
G02X444454Y882994I-1297J-3D01*
G01X444423Y882908D01*
X445229Y881511D01*
X445319Y881494D01*
G02X446376Y880219I-240J-1275D01*
G02X443780I-1298J0D01*
G02X443853Y880647I1298J-1D01*
G01X443883Y880734D01*
X443077Y882131D01*
X442987Y882148D01*
G02X441932Y883423I243J1275D01*
G37*
G36*
G01X449332D02*
G02X451926I1297J0D01*
G02X451854Y882994I-1297J-3D01*
G01X451823Y882908D01*
X452629Y881511D01*
X452719Y881494D01*
G02X453776Y880219I-240J-1275D01*
G02X451182I-1297J0D01*
G01Y880221D01*
G02X451254Y880646I1297J-1D01*
G01X451284Y880733D01*
X450477Y882131D01*
X450387Y882148D01*
G02X449332Y883423I243J1275D01*
G37*
G36*
G01X456732D02*
G02X459326I1297J0D01*
G02X459254Y882994I-1297J-3D01*
G01X459223Y882908D01*
X460029Y881511D01*
X460119Y881494D01*
G02X461176Y880219I-240J-1275D01*
G02X458580I-1298J0D01*
G02X458653Y880647I1298J-1D01*
G01X458683Y880734D01*
X457877Y882131D01*
X457787Y882148D01*
G02X456732Y883423I243J1275D01*
G37*
G36*
G01X464132D02*
G02X466726I1297J0D01*
G02X466654Y882994I-1297J-3D01*
G01X466623Y882908D01*
X467429Y881511D01*
X467519Y881494D01*
G02X468576Y880219I-240J-1275D01*
G02X465980I-1298J0D01*
G02X466053Y880647I1298J-1D01*
G01X466083Y880734D01*
X465277Y882131D01*
X465187Y882148D01*
G02X464132Y883423I243J1275D01*
G37*
G36*
G01X471532D02*
G02X474126I1297J0D01*
G02X474054Y882994I-1297J-3D01*
G01X474023Y882908D01*
X474829Y881511D01*
X474919Y881494D01*
G02X475976Y880219I-240J-1275D01*
G02X473380I-1298J0D01*
G02X473453Y880647I1298J-1D01*
G01X473483Y880734D01*
X472677Y882131D01*
X472587Y882148D01*
G02X471532Y883423I243J1275D01*
G37*
G36*
G01X478932D02*
G02X481526I1297J0D01*
G02X481454Y882994I-1297J-3D01*
G01X481423Y882908D01*
X482229Y881511D01*
X482319Y881494D01*
G02X483376Y880219I-240J-1275D01*
G02X480780I-1298J0D01*
G02X480853Y880647I1298J-1D01*
G01X480883Y880734D01*
X480077Y882131D01*
X479987Y882148D01*
G02X478932Y883423I243J1275D01*
G37*
G36*
G01X486332D02*
G02X488926I1297J0D01*
G02X488854Y882994I-1297J-3D01*
G01X488823Y882908D01*
X489629Y881511D01*
X489719Y881494D01*
G02X490776Y880219I-240J-1275D01*
G02X488180I-1298J0D01*
G02X488253Y880647I1298J-1D01*
G01X488283Y880734D01*
X487477Y882131D01*
X487387Y882148D01*
G02X486332Y883423I243J1275D01*
G37*
G36*
G01X493732D02*
G02X496326I1297J0D01*
G02X496254Y882994I-1297J-3D01*
G01X496223Y882908D01*
X497029Y881511D01*
X497119Y881494D01*
G02X498176Y880219I-240J-1275D01*
G02X495580I-1298J0D01*
G02X495653Y880647I1298J-1D01*
G01X495683Y880734D01*
X494877Y882131D01*
X494787Y882148D01*
G02X493732Y883423I243J1275D01*
G37*
G36*
G01X501132D02*
G02X503726I1297J0D01*
G02X503654Y882994I-1297J-3D01*
G01X503623Y882908D01*
X504429Y881511D01*
X504519Y881494D01*
G02X505576Y880219I-240J-1275D01*
G02X502980I-1298J0D01*
G02X503053Y880647I1298J-1D01*
G01X503083Y880734D01*
X502277Y882131D01*
X502187Y882148D01*
G02X501132Y883423I243J1275D01*
G37*
G36*
G01X508532D02*
G02X511126I1297J0D01*
G02X511054Y882994I-1297J-3D01*
G01X511023Y882908D01*
X511829Y881511D01*
X511919Y881494D01*
G02X512976Y880219I-240J-1275D01*
G02X510380I-1298J0D01*
G02X510453Y880647I1298J-1D01*
G01X510483Y880734D01*
X509677Y882131D01*
X509587Y882148D01*
G02X508532Y883423I243J1275D01*
G37*
G36*
G01X1344074D02*
G02X1346668I1297J0D01*
G02X1346596Y882994I-1297J-3D01*
G01X1346565Y882908D01*
X1347371Y881511D01*
X1347461Y881494D01*
G02X1348518Y880219I-240J-1275D01*
G02X1345922I-1298J0D01*
G02X1345995Y880647I1298J-1D01*
G01X1346025Y880734D01*
X1345219Y882131D01*
X1345129Y882148D01*
G02X1344074Y883423I243J1275D01*
G37*
G36*
G01X1351474D02*
G02X1354068I1297J0D01*
G02X1353996Y882994I-1297J-3D01*
G01X1353965Y882908D01*
X1354771Y881511D01*
X1354861Y881494D01*
G02X1355918Y880219I-240J-1275D01*
G02X1353322I-1298J0D01*
G02X1353395Y880647I1298J-1D01*
G01X1353425Y880734D01*
X1352619Y882131D01*
X1352529Y882148D01*
G02X1351474Y883423I243J1275D01*
G37*
G36*
G01X1358874D02*
G02X1361468I1297J0D01*
G02X1361396Y882994I-1297J-3D01*
G01X1361365Y882908D01*
X1362171Y881511D01*
X1362261Y881494D01*
G02X1363318Y880219I-240J-1275D01*
G02X1360722I-1298J0D01*
G02X1360795Y880647I1298J-1D01*
G01X1360825Y880734D01*
X1360019Y882131D01*
X1359929Y882148D01*
G02X1358874Y883423I243J1275D01*
G37*
G36*
G01X1366274D02*
G02X1368868I1297J0D01*
G02X1368796Y882994I-1297J-3D01*
G01X1368765Y882908D01*
X1369571Y881511D01*
X1369661Y881494D01*
G02X1370718Y880219I-240J-1275D01*
G02X1368122I-1298J0D01*
G02X1368195Y880647I1298J-1D01*
G01X1368225Y880734D01*
X1367419Y882131D01*
X1367329Y882148D01*
G02X1366274Y883423I243J1275D01*
G37*
G36*
G01X1373674D02*
G02X1376268I1297J0D01*
G02X1376196Y882994I-1297J-3D01*
G01X1376165Y882908D01*
X1376971Y881511D01*
X1377061Y881494D01*
G02X1378118Y880219I-240J-1275D01*
G02X1375522I-1298J0D01*
G02X1375595Y880647I1298J-1D01*
G01X1375625Y880734D01*
X1374819Y882131D01*
X1374729Y882148D01*
G02X1373674Y883423I243J1275D01*
G37*
G36*
G01X1381074D02*
G02X1383668I1297J0D01*
G02X1383596Y882994I-1297J-3D01*
G01X1383565Y882908D01*
X1384371Y881511D01*
X1384461Y881494D01*
G02X1385518Y880219I-240J-1275D01*
G02X1382922I-1298J0D01*
G02X1382995Y880647I1298J-1D01*
G01X1383025Y880734D01*
X1382219Y882131D01*
X1382129Y882148D01*
G02X1381074Y883423I243J1275D01*
G37*
G36*
G01X1388474D02*
G02X1391068I1297J0D01*
G02X1390996Y882994I-1297J-3D01*
G01X1390965Y882908D01*
X1391771Y881511D01*
X1391861Y881494D01*
G02X1392918Y880219I-240J-1275D01*
G02X1390322I-1298J0D01*
G02X1390395Y880647I1298J-1D01*
G01X1390425Y880734D01*
X1389619Y882131D01*
X1389529Y882148D01*
G02X1388474Y883423I243J1275D01*
G37*
G36*
G01X1395874D02*
G02X1398468I1297J0D01*
G02X1398396Y882994I-1297J-3D01*
G01X1398365Y882908D01*
X1399171Y881511D01*
X1399261Y881494D01*
G02X1400318Y880219I-240J-1275D01*
G02X1397722I-1298J0D01*
G02X1397795Y880647I1298J-1D01*
G01X1397825Y880734D01*
X1397019Y882131D01*
X1396929Y882148D01*
G02X1395874Y883423I243J1275D01*
G37*
G36*
G01X1403274D02*
G02X1405868I1297J0D01*
G02X1405796Y882994I-1297J-3D01*
G01X1405765Y882908D01*
X1406571Y881511D01*
X1406661Y881494D01*
G02X1407718Y880219I-240J-1275D01*
G02X1405122I-1298J0D01*
G02X1405195Y880647I1298J-1D01*
G01X1405225Y880734D01*
X1404419Y882131D01*
X1404329Y882148D01*
G02X1403274Y883423I243J1275D01*
G37*
G36*
G01X1410674D02*
G02X1413268I1297J0D01*
G02X1413196Y882994I-1297J-3D01*
G01X1413165Y882908D01*
X1413971Y881511D01*
X1414061Y881494D01*
G02X1415118Y880219I-240J-1275D01*
G02X1412522I-1298J0D01*
G02X1412595Y880647I1298J-1D01*
G01X1412625Y880734D01*
X1411819Y882131D01*
X1411729Y882148D01*
G02X1410674Y883423I243J1275D01*
G37*
G36*
G01X1418074D02*
G02X1420668I1297J0D01*
G02X1420596Y882994I-1297J-3D01*
G01X1420565Y882908D01*
X1421371Y881511D01*
X1421461Y881494D01*
G02X1422518Y880219I-240J-1275D01*
G02X1419922I-1298J0D01*
G02X1419995Y880647I1298J-1D01*
G01X1420025Y880734D01*
X1419219Y882131D01*
X1419129Y882148D01*
G02X1418074Y883423I243J1275D01*
G37*
G36*
G01X1425474D02*
G02X1428068I1297J0D01*
G02X1427996Y882994I-1297J-3D01*
G01X1427965Y882908D01*
X1428771Y881511D01*
X1428861Y881494D01*
G02X1429918Y880219I-240J-1275D01*
G02X1427324I-1297J0D01*
G01Y880221D01*
G02X1427396Y880646I1297J-1D01*
G01X1427426Y880733D01*
X1426619Y882131D01*
X1426529Y882148D01*
G02X1425474Y883423I243J1275D01*
G37*
G36*
G01X1432874D02*
G02X1435468I1297J0D01*
G02X1435396Y882994I-1297J-3D01*
G01X1435365Y882908D01*
X1436171Y881511D01*
X1436261Y881494D01*
G02X1437318Y880219I-240J-1275D01*
G02X1434722I-1298J0D01*
G02X1434795Y880647I1298J-1D01*
G01X1434825Y880734D01*
X1434019Y882131D01*
X1433929Y882148D01*
G02X1432874Y883423I243J1275D01*
G37*
G36*
G01X1440274D02*
G02X1442868I1297J0D01*
G02X1442796Y882994I-1297J-3D01*
G01X1442765Y882908D01*
X1443571Y881511D01*
X1443661Y881494D01*
G02X1444718Y880219I-240J-1275D01*
G02X1442122I-1298J0D01*
G02X1442195Y880647I1298J-1D01*
G01X1442225Y880734D01*
X1441419Y882131D01*
X1441329Y882148D01*
G02X1440274Y883423I243J1275D01*
G37*
G36*
G01X1447674D02*
G02X1450268I1297J0D01*
G02X1450196Y882994I-1297J-3D01*
G01X1450165Y882908D01*
X1450971Y881511D01*
X1451061Y881494D01*
G02X1452118Y880219I-240J-1275D01*
G02X1449522I-1298J0D01*
G02X1449595Y880647I1298J-1D01*
G01X1449625Y880734D01*
X1448819Y882131D01*
X1448729Y882148D01*
G02X1447674Y883423I243J1275D01*
G37*
G36*
G01X1455074D02*
G02X1457668I1297J0D01*
G02X1457596Y882994I-1297J-3D01*
G01X1457565Y882908D01*
X1458371Y881511D01*
X1458461Y881494D01*
G02X1459518Y880219I-240J-1275D01*
G02X1456922I-1298J0D01*
G02X1456995Y880647I1298J-1D01*
G01X1457025Y880734D01*
X1456219Y882131D01*
X1456129Y882148D01*
G02X1455074Y883423I243J1275D01*
G37*
G36*
G01X1462474D02*
G02X1465068I1297J0D01*
G02X1464996Y882994I-1297J-3D01*
G01X1464965Y882908D01*
X1465771Y881511D01*
X1465861Y881494D01*
G02X1466918Y880219I-240J-1275D01*
G02X1464322I-1298J0D01*
G02X1464395Y880647I1298J-1D01*
G01X1464425Y880734D01*
X1463619Y882131D01*
X1463529Y882148D01*
G02X1462474Y883423I243J1275D01*
G37*
G36*
G01X1469874D02*
G02X1472468I1297J0D01*
G02X1472396Y882994I-1297J-3D01*
G01X1472365Y882908D01*
X1473171Y881511D01*
X1473261Y881494D01*
G02X1474318Y880219I-240J-1275D01*
G02X1471722I-1298J0D01*
G02X1471795Y880647I1298J-1D01*
G01X1471825Y880734D01*
X1471019Y882131D01*
X1470929Y882148D01*
G02X1469874Y883423I243J1275D01*
G37*
G36*
G01X1477274D02*
G02X1479868I1297J0D01*
G02X1479796Y882994I-1297J-3D01*
G01X1479765Y882908D01*
X1480571Y881511D01*
X1480661Y881494D01*
G02X1481718Y880219I-240J-1275D01*
G02X1479122I-1298J0D01*
G02X1479195Y880647I1298J-1D01*
G01X1479225Y880734D01*
X1478419Y882131D01*
X1478329Y882148D01*
G02X1477274Y883423I243J1275D01*
G37*
G36*
G01X1484674D02*
G02X1487268I1297J0D01*
G02X1487196Y882994I-1297J-3D01*
G01X1487165Y882908D01*
X1487971Y881511D01*
X1488061Y881494D01*
G02X1489118Y880219I-240J-1275D01*
G02X1486522I-1298J0D01*
G02X1486595Y880647I1298J-1D01*
G01X1486625Y880734D01*
X1485819Y882131D01*
X1485729Y882148D01*
G02X1484674Y883423I243J1275D01*
G37*
G36*
G01X373480Y886627D02*
G02X376076I1298J0D01*
G02X375020Y885352I-1298J0D01*
G01X374930Y885335D01*
X374123Y883938D01*
X374154Y883851D01*
G02X374226Y883423I-1225J-426D01*
G02X371632I-1297J0D01*
G02X372687Y884698I1298J0D01*
G01X372777Y884715D01*
X373584Y886112D01*
X373553Y886199D01*
G02X373480Y886627I1225J429D01*
G37*
G36*
G01X380880D02*
G02X383476I1298J0D01*
G02X382420Y885352I-1298J0D01*
G01X382330Y885335D01*
X381523Y883938D01*
X381554Y883851D01*
G02X381626Y883423I-1225J-426D01*
G02X379032I-1297J0D01*
G02X380087Y884698I1298J0D01*
G01X380177Y884715D01*
X380984Y886112D01*
X380953Y886199D01*
G02X380880Y886627I1225J429D01*
G37*
G36*
G01X388280D02*
G02X390876I1298J0D01*
G02X389820Y885352I-1298J0D01*
G01X389730Y885335D01*
X388923Y883938D01*
X388954Y883851D01*
G02X389026Y883423I-1225J-426D01*
G02X386432I-1297J0D01*
G02X387487Y884698I1298J0D01*
G01X387577Y884715D01*
X388384Y886112D01*
X388353Y886199D01*
G02X388280Y886627I1225J429D01*
G37*
G36*
G01X395680D02*
G02X398276I1298J0D01*
G02X397220Y885352I-1298J0D01*
G01X397130Y885335D01*
X396323Y883938D01*
X396354Y883851D01*
G02X396426Y883423I-1225J-426D01*
G02X393832I-1297J0D01*
G02X394887Y884698I1298J0D01*
G01X394977Y884715D01*
X395784Y886112D01*
X395753Y886199D01*
G02X395680Y886627I1225J429D01*
G37*
G36*
G01X403080D02*
G02X405676I1298J0D01*
G02X404620Y885352I-1298J0D01*
G01X404530Y885335D01*
X403723Y883938D01*
X403754Y883851D01*
G02X403826Y883423I-1225J-426D01*
G02X401232I-1297J0D01*
G02X402287Y884698I1298J0D01*
G01X402377Y884715D01*
X403184Y886112D01*
X403153Y886199D01*
G02X403080Y886627I1225J429D01*
G37*
G36*
G01X410480D02*
G02X413076I1298J0D01*
G02X412020Y885352I-1298J0D01*
G01X411930Y885335D01*
X411123Y883938D01*
X411154Y883851D01*
G02X411226Y883423I-1225J-426D01*
G02X408632I-1297J0D01*
G02X409687Y884698I1298J0D01*
G01X409777Y884715D01*
X410584Y886112D01*
X410553Y886199D01*
G02X410480Y886627I1225J429D01*
G37*
G36*
G01X417880D02*
G02X420476I1298J0D01*
G02X419420Y885352I-1298J0D01*
G01X419330Y885335D01*
X418523Y883938D01*
X418554Y883851D01*
G02X418626Y883423I-1225J-426D01*
G02X416032I-1297J0D01*
G02X417087Y884698I1298J0D01*
G01X417177Y884715D01*
X417984Y886112D01*
X417953Y886199D01*
G02X417880Y886627I1225J429D01*
G37*
G36*
G01X425280D02*
G02X427876I1298J0D01*
G02X426820Y885352I-1298J0D01*
G01X426730Y885335D01*
X425923Y883938D01*
X425954Y883851D01*
G02X426026Y883423I-1225J-426D01*
G02X423432I-1297J0D01*
G02X424487Y884698I1298J0D01*
G01X424577Y884715D01*
X425384Y886112D01*
X425353Y886199D01*
G02X425280Y886627I1225J429D01*
G37*
G36*
G01X432680D02*
G02X435276I1298J0D01*
G02X434220Y885352I-1298J0D01*
G01X434130Y885335D01*
X433323Y883938D01*
X433354Y883851D01*
G02X433426Y883423I-1225J-426D01*
G02X430832I-1297J0D01*
G02X431887Y884698I1298J0D01*
G01X431977Y884715D01*
X432784Y886112D01*
X432753Y886199D01*
G02X432680Y886627I1225J429D01*
G37*
G36*
G01X440080D02*
G02X442676I1298J0D01*
G02X441620Y885352I-1298J0D01*
G01X441530Y885335D01*
X440723Y883938D01*
X440754Y883851D01*
G02X440826Y883423I-1225J-426D01*
G02X438232I-1297J0D01*
G02X439287Y884698I1298J0D01*
G01X439377Y884715D01*
X440184Y886112D01*
X440153Y886199D01*
G02X440080Y886627I1225J429D01*
G37*
G36*
G01X447480D02*
G02X450076I1298J0D01*
G02X449020Y885352I-1298J0D01*
G01X448930Y885335D01*
X448123Y883938D01*
X448154Y883851D01*
G02X448226Y883423I-1225J-426D01*
G02X445632I-1297J0D01*
G02X446687Y884698I1298J0D01*
G01X446777Y884715D01*
X447584Y886112D01*
X447553Y886199D01*
G02X447480Y886627I1225J429D01*
G37*
G36*
G01X454880D02*
G02X457476I1298J0D01*
G02X456420Y885352I-1298J0D01*
G01X456330Y885335D01*
X455523Y883938D01*
X455554Y883851D01*
G02X455626Y883423I-1225J-426D01*
G02X453032I-1297J0D01*
G02X454087Y884698I1298J0D01*
G01X454177Y884715D01*
X454984Y886112D01*
X454953Y886199D01*
G02X454880Y886627I1225J429D01*
G37*
G36*
G01X462280D02*
G02X464876I1298J0D01*
G02X463820Y885352I-1298J0D01*
G01X463730Y885335D01*
X462923Y883938D01*
X462954Y883851D01*
G02X463026Y883423I-1225J-426D01*
G02X460432I-1297J0D01*
G02X461487Y884698I1298J0D01*
G01X461577Y884715D01*
X462384Y886112D01*
X462353Y886199D01*
G02X462280Y886627I1225J429D01*
G37*
G36*
G01X469680D02*
G02X472276I1298J0D01*
G02X471220Y885352I-1298J0D01*
G01X471130Y885335D01*
X470323Y883938D01*
X470354Y883851D01*
G02X470426Y883423I-1225J-426D01*
G02X467832I-1297J0D01*
G02X468887Y884698I1298J0D01*
G01X468977Y884715D01*
X469784Y886112D01*
X469753Y886199D01*
G02X469680Y886627I1225J429D01*
G37*
G36*
G01X477080D02*
G02X479676I1298J0D01*
G02X478620Y885352I-1298J0D01*
G01X478530Y885335D01*
X477723Y883938D01*
X477754Y883851D01*
G02X477826Y883423I-1225J-426D01*
G02X475232I-1297J0D01*
G02X476287Y884698I1298J0D01*
G01X476377Y884715D01*
X477184Y886112D01*
X477153Y886199D01*
G02X477080Y886627I1225J429D01*
G37*
G36*
G01X484480D02*
G02X487076I1298J0D01*
G02X486020Y885352I-1298J0D01*
G01X485930Y885335D01*
X485123Y883938D01*
X485154Y883851D01*
G02X485226Y883423I-1225J-426D01*
G02X482632I-1297J0D01*
G02X483687Y884698I1298J0D01*
G01X483777Y884715D01*
X484584Y886112D01*
X484553Y886199D01*
G02X484480Y886627I1225J429D01*
G37*
G36*
G01X491880D02*
G02X494476I1298J0D01*
G02X493420Y885352I-1298J0D01*
G01X493330Y885335D01*
X492523Y883938D01*
X492554Y883851D01*
G02X492626Y883423I-1225J-426D01*
G02X490032I-1297J0D01*
G02X491087Y884698I1298J0D01*
G01X491177Y884715D01*
X491984Y886112D01*
X491953Y886199D01*
G02X491880Y886627I1225J429D01*
G37*
G36*
G01X499280D02*
G02X501876I1298J0D01*
G02X500820Y885352I-1298J0D01*
G01X500730Y885335D01*
X499923Y883938D01*
X499954Y883851D01*
G02X500026Y883423I-1225J-426D01*
G02X497432I-1297J0D01*
G02X498487Y884698I1298J0D01*
G01X498577Y884715D01*
X499384Y886112D01*
X499353Y886199D01*
G02X499280Y886627I1225J429D01*
G37*
G36*
G01X506680D02*
G02X509276I1298J0D01*
G02X508220Y885352I-1298J0D01*
G01X508130Y885335D01*
X507323Y883938D01*
X507354Y883851D01*
G02X507426Y883423I-1225J-426D01*
G02X504832I-1297J0D01*
G02X505887Y884698I1298J0D01*
G01X505977Y884715D01*
X506784Y886112D01*
X506753Y886199D01*
G02X506680Y886627I1225J429D01*
G37*
G36*
G01X514080D02*
G02X516676I1298J0D01*
G02X515620Y885352I-1298J0D01*
G01X515530Y885335D01*
X514723Y883938D01*
X514754Y883851D01*
G02X514826Y883423I-1225J-426D01*
G02X512232I-1297J0D01*
G02X513287Y884698I1298J0D01*
G01X513377Y884715D01*
X514184Y886112D01*
X514153Y886199D01*
G02X514080Y886627I1225J429D01*
G37*
G36*
G01X521480D02*
G02X524076I1298J0D01*
G02X523020Y885352I-1298J0D01*
G01X522930Y885335D01*
X522123Y883938D01*
X522154Y883851D01*
G02X522226Y883423I-1225J-426D01*
G02X519632I-1297J0D01*
G02X520687Y884698I1298J0D01*
G01X520777Y884715D01*
X521584Y886112D01*
X521553Y886199D01*
G02X521480Y886627I1225J429D01*
G37*
G36*
G01X1349622D02*
G02X1352218I1298J0D01*
G02X1351162Y885352I-1298J0D01*
G01X1351072Y885335D01*
X1350265Y883938D01*
X1350296Y883851D01*
G02X1350368Y883423I-1225J-426D01*
G02X1347774I-1297J0D01*
G02X1348829Y884698I1298J0D01*
G01X1348919Y884715D01*
X1349726Y886112D01*
X1349695Y886199D01*
G02X1349622Y886627I1225J429D01*
G37*
G36*
G01X1357022D02*
G02X1359618I1298J0D01*
G02X1358562Y885352I-1298J0D01*
G01X1358472Y885335D01*
X1357665Y883938D01*
X1357696Y883851D01*
G02X1357768Y883423I-1225J-426D01*
G02X1355174I-1297J0D01*
G02X1356229Y884698I1298J0D01*
G01X1356319Y884715D01*
X1357126Y886112D01*
X1357095Y886199D01*
G02X1357022Y886627I1225J429D01*
G37*
G36*
G01X1364422D02*
G02X1367018I1298J0D01*
G02X1365962Y885352I-1298J0D01*
G01X1365872Y885335D01*
X1365065Y883938D01*
X1365096Y883851D01*
G02X1365168Y883423I-1225J-426D01*
G02X1362574I-1297J0D01*
G02X1363629Y884698I1298J0D01*
G01X1363719Y884715D01*
X1364526Y886112D01*
X1364495Y886199D01*
G02X1364422Y886627I1225J429D01*
G37*
G36*
G01X1371822D02*
G02X1374418I1298J0D01*
G02X1373362Y885352I-1298J0D01*
G01X1373272Y885335D01*
X1372465Y883938D01*
X1372496Y883851D01*
G02X1372568Y883423I-1225J-426D01*
G02X1369974I-1297J0D01*
G02X1371029Y884698I1298J0D01*
G01X1371119Y884715D01*
X1371926Y886112D01*
X1371895Y886199D01*
G02X1371822Y886627I1225J429D01*
G37*
G36*
G01X1379222D02*
G02X1381818I1298J0D01*
G02X1380762Y885352I-1298J0D01*
G01X1380672Y885335D01*
X1379865Y883938D01*
X1379896Y883851D01*
G02X1379968Y883423I-1225J-426D01*
G02X1377374I-1297J0D01*
G02X1378429Y884698I1298J0D01*
G01X1378519Y884715D01*
X1379326Y886112D01*
X1379295Y886199D01*
G02X1379222Y886627I1225J429D01*
G37*
G36*
G01X1386622D02*
G02X1389218I1298J0D01*
G02X1388162Y885352I-1298J0D01*
G01X1388072Y885335D01*
X1387265Y883938D01*
X1387296Y883851D01*
G02X1387368Y883423I-1225J-426D01*
G02X1384774I-1297J0D01*
G02X1385829Y884698I1298J0D01*
G01X1385919Y884715D01*
X1386726Y886112D01*
X1386695Y886199D01*
G02X1386622Y886627I1225J429D01*
G37*
G36*
G01X1394022D02*
G02X1396618I1298J0D01*
G02X1395562Y885352I-1298J0D01*
G01X1395472Y885335D01*
X1394665Y883938D01*
X1394696Y883851D01*
G02X1394768Y883423I-1225J-426D01*
G02X1392174I-1297J0D01*
G02X1393229Y884698I1298J0D01*
G01X1393319Y884715D01*
X1394126Y886112D01*
X1394095Y886199D01*
G02X1394022Y886627I1225J429D01*
G37*
G36*
G01X1401422D02*
G02X1404018I1298J0D01*
G02X1402962Y885352I-1298J0D01*
G01X1402872Y885335D01*
X1402065Y883938D01*
X1402096Y883851D01*
G02X1402168Y883423I-1225J-426D01*
G02X1399574I-1297J0D01*
G02X1400629Y884698I1298J0D01*
G01X1400719Y884715D01*
X1401526Y886112D01*
X1401495Y886199D01*
G02X1401422Y886627I1225J429D01*
G37*
G36*
G01X1408822D02*
G02X1411418I1298J0D01*
G02X1410362Y885352I-1298J0D01*
G01X1410272Y885335D01*
X1409465Y883938D01*
X1409496Y883851D01*
G02X1409568Y883423I-1225J-426D01*
G02X1406974I-1297J0D01*
G02X1408029Y884698I1298J0D01*
G01X1408119Y884715D01*
X1408926Y886112D01*
X1408895Y886199D01*
G02X1408822Y886627I1225J429D01*
G37*
G36*
G01X1416222D02*
G02X1418818I1298J0D01*
G02X1417762Y885352I-1298J0D01*
G01X1417672Y885335D01*
X1416865Y883938D01*
X1416896Y883851D01*
G02X1416968Y883423I-1225J-426D01*
G02X1414374I-1297J0D01*
G02X1415429Y884698I1298J0D01*
G01X1415519Y884715D01*
X1416326Y886112D01*
X1416295Y886199D01*
G02X1416222Y886627I1225J429D01*
G37*
G36*
G01X1423622D02*
G02X1426218I1298J0D01*
G02X1425162Y885352I-1298J0D01*
G01X1425072Y885335D01*
X1424265Y883938D01*
X1424296Y883851D01*
G02X1424368Y883423I-1225J-426D01*
G02X1421774I-1297J0D01*
G02X1422829Y884698I1298J0D01*
G01X1422919Y884715D01*
X1423726Y886112D01*
X1423695Y886199D01*
G02X1423622Y886627I1225J429D01*
G37*
G36*
G01X1431022D02*
G02X1433618I1298J0D01*
G02X1432562Y885352I-1298J0D01*
G01X1432472Y885335D01*
X1431665Y883938D01*
X1431696Y883851D01*
G02X1431768Y883423I-1225J-426D01*
G02X1429174I-1297J0D01*
G02X1430229Y884698I1298J0D01*
G01X1430319Y884715D01*
X1431126Y886112D01*
X1431095Y886199D01*
G02X1431022Y886627I1225J429D01*
G37*
G36*
G01X1438422D02*
G02X1441018I1298J0D01*
G02X1439962Y885352I-1298J0D01*
G01X1439872Y885335D01*
X1439065Y883938D01*
X1439096Y883851D01*
G02X1439168Y883423I-1225J-426D01*
G02X1436574I-1297J0D01*
G02X1437629Y884698I1298J0D01*
G01X1437719Y884715D01*
X1438526Y886112D01*
X1438495Y886199D01*
G02X1438422Y886627I1225J429D01*
G37*
G36*
G01X1445822D02*
G02X1448418I1298J0D01*
G02X1447362Y885352I-1298J0D01*
G01X1447272Y885335D01*
X1446465Y883938D01*
X1446496Y883851D01*
G02X1446568Y883423I-1225J-426D01*
G02X1443974I-1297J0D01*
G02X1445029Y884698I1298J0D01*
G01X1445119Y884715D01*
X1445926Y886112D01*
X1445895Y886199D01*
G02X1445822Y886627I1225J429D01*
G37*
G36*
G01X1453222D02*
G02X1455818I1298J0D01*
G02X1454762Y885352I-1298J0D01*
G01X1454672Y885335D01*
X1453865Y883938D01*
X1453896Y883851D01*
G02X1453968Y883423I-1225J-426D01*
G02X1451374I-1297J0D01*
G02X1452429Y884698I1298J0D01*
G01X1452519Y884715D01*
X1453326Y886112D01*
X1453295Y886199D01*
G02X1453222Y886627I1225J429D01*
G37*
G36*
G01X1460622D02*
G02X1463218I1298J0D01*
G02X1462162Y885352I-1298J0D01*
G01X1462072Y885335D01*
X1461265Y883938D01*
X1461296Y883851D01*
G02X1461368Y883423I-1225J-426D01*
G02X1458774I-1297J0D01*
G02X1459829Y884698I1298J0D01*
G01X1459919Y884715D01*
X1460726Y886112D01*
X1460695Y886199D01*
G02X1460622Y886627I1225J429D01*
G37*
G36*
G01X1468022D02*
G02X1470618I1298J0D01*
G02X1469562Y885352I-1298J0D01*
G01X1469472Y885335D01*
X1468665Y883938D01*
X1468696Y883851D01*
G02X1468768Y883423I-1225J-426D01*
G02X1466174I-1297J0D01*
G02X1467229Y884698I1298J0D01*
G01X1467319Y884715D01*
X1468126Y886112D01*
X1468095Y886199D01*
G02X1468022Y886627I1225J429D01*
G37*
G36*
G01X1475422D02*
G02X1478018I1298J0D01*
G02X1476962Y885352I-1298J0D01*
G01X1476872Y885335D01*
X1476065Y883938D01*
X1476096Y883851D01*
G02X1476168Y883423I-1225J-426D01*
G02X1473574I-1297J0D01*
G02X1474629Y884698I1298J0D01*
G01X1474719Y884715D01*
X1475526Y886112D01*
X1475495Y886199D01*
G02X1475422Y886627I1225J429D01*
G37*
G36*
G01X1482822D02*
G02X1485418I1298J0D01*
G02X1484362Y885352I-1298J0D01*
G01X1484272Y885335D01*
X1483465Y883938D01*
X1483496Y883851D01*
G02X1483568Y883423I-1225J-426D01*
G02X1480974I-1297J0D01*
G02X1482029Y884698I1298J0D01*
G01X1482119Y884715D01*
X1482926Y886112D01*
X1482895Y886199D01*
G02X1482822Y886627I1225J429D01*
G37*
G36*
G01X1490222D02*
G02X1492818I1298J0D01*
G02X1491762Y885352I-1298J0D01*
G01X1491672Y885335D01*
X1490865Y883938D01*
X1490896Y883851D01*
G02X1490968Y883423I-1225J-426D01*
G02X1488374I-1297J0D01*
G02X1489429Y884698I1298J0D01*
G01X1489519Y884715D01*
X1490326Y886112D01*
X1490295Y886199D01*
G02X1490222Y886627I1225J429D01*
G37*
G36*
G01X1497622D02*
G02X1500218I1298J0D01*
G02X1499162Y885352I-1298J0D01*
G01X1499072Y885335D01*
X1498265Y883938D01*
X1498296Y883851D01*
G02X1498368Y883423I-1225J-426D01*
G02X1495774I-1297J0D01*
G02X1496829Y884698I1298J0D01*
G01X1496919Y884715D01*
X1497726Y886112D01*
X1497695Y886199D01*
G02X1497622Y886627I1225J429D01*
G37*
G36*
G01X429414Y1079791D02*
G02X432008I1297J0D01*
G02X430953Y1078516I-1298J0D01*
G01X430863Y1078499D01*
X430056Y1077101D01*
X430086Y1077015D01*
G02X430158Y1076587I-1225J-426D01*
G02X427564I-1297J0D01*
G02X428620Y1077862I1298J0D01*
G01X428710Y1077879D01*
X429517Y1079276D01*
X429486Y1079363D01*
G02X429414Y1079791I1225J426D01*
G37*
G36*
G01X1405556D02*
G02X1408150I1297J0D01*
G02X1407095Y1078516I-1298J0D01*
G01X1407005Y1078499D01*
X1406198Y1077101D01*
X1406228Y1077015D01*
G02X1406300Y1076587I-1225J-426D01*
G02X1403706I-1297J0D01*
G02X1404762Y1077862I1298J0D01*
G01X1404852Y1077879D01*
X1405659Y1079276D01*
X1405628Y1079363D01*
G02X1405556Y1079791I1225J426D01*
G37*
G36*
G01X402962Y1084292D02*
G02X404001Y1083772I0J-1298D01*
G01X405623D01*
G02X406662Y1084292I1039J-778D01*
G02Y1081698I0J-1297D01*
G02X405623Y1082218I0J1298D01*
G01X404001D01*
G02X402962Y1081698I-1039J778D01*
G02Y1084292I0J1297D01*
G37*
G36*
G01X409064Y1082995D02*
G02X411660I1298J0D01*
G02X410604Y1081720I-1298J0D01*
G01X410514Y1081703D01*
X409706Y1080304D01*
X409736Y1080218D01*
G02X409808Y1079793I-1225J-426D01*
G01Y1079791D01*
G02X407214I-1297J0D01*
G02X408271Y1081066I1297J0D01*
G01X408361Y1081083D01*
X409168Y1082480D01*
X409137Y1082567D01*
G02X409064Y1082995I1225J429D01*
G37*
G36*
G01X1379104Y1084292D02*
G02X1380143Y1083772I0J-1298D01*
G01X1381765D01*
G02X1382804Y1084292I1039J-778D01*
G02Y1081698I0J-1297D01*
G02X1381765Y1082218I0J1298D01*
G01X1380143D01*
G02X1379104Y1081698I-1039J778D01*
G02Y1084292I0J1297D01*
G37*
G36*
G01X1385206Y1082995D02*
G02X1387802I1298J0D01*
G02X1386746Y1081720I-1298J0D01*
G01X1386656Y1081703D01*
X1385848Y1080304D01*
X1385878Y1080218D01*
G02X1385950Y1079793I-1225J-426D01*
G01Y1079791D01*
G02X1383356I-1297J0D01*
G02X1384413Y1081066I1297J0D01*
G01X1384503Y1081083D01*
X1385310Y1082480D01*
X1385279Y1082567D01*
G02X1385206Y1082995I1225J429D01*
G37*
G36*
G01X410914Y1086200D02*
G02X413508I1297J0D01*
G02X413436Y1085772I-1297J-2D01*
G01X413405Y1085685D01*
X414212Y1084287D01*
X414303Y1084270D01*
G02X415360Y1082995I-240J-1275D01*
G02X412764I-1298J0D01*
G02X412837Y1083422I1298J-2D01*
G01X412867Y1083509D01*
X412059Y1084908D01*
X411969Y1084925D01*
G02X410914Y1086200I243J1275D01*
G37*
G36*
G01X419611Y1087498D02*
G02X420650Y1086978I0J-1298D01*
G01X422272D01*
G02X423311Y1087498I1039J-778D01*
G02Y1084902I0J-1298D01*
G02X422272Y1085422I0J1298D01*
G01X420650D01*
G02X419611Y1084902I-1039J778D01*
G02Y1087498I0J1298D01*
G37*
G36*
G01X425714Y1086200D02*
G02X428310I1298J0D01*
G02X427254Y1084925I-1298J0D01*
G01X427164Y1084908D01*
X426356Y1083510D01*
X426387Y1083423D01*
G02X426460Y1082995I-1225J-429D01*
G02X423864I-1298J0D01*
G02X424920Y1084270I1298J0D01*
G01X425010Y1084287D01*
X425818Y1085685D01*
X425787Y1085772D01*
G02X425714Y1086200I1225J429D01*
G37*
G36*
G01X1387056D02*
G02X1389650I1297J0D01*
G02X1389578Y1085772I-1297J-2D01*
G01X1389547Y1085685D01*
X1390354Y1084287D01*
X1390445Y1084270D01*
G02X1391502Y1082995I-240J-1275D01*
G02X1388906I-1298J0D01*
G02X1388979Y1083422I1298J-2D01*
G01X1389009Y1083509D01*
X1388201Y1084908D01*
X1388111Y1084925D01*
G02X1387056Y1086200I243J1275D01*
G37*
G36*
G01X1395753Y1087498D02*
G02X1396792Y1086978I0J-1298D01*
G01X1398414D01*
G02X1399453Y1087498I1039J-778D01*
G02Y1084902I0J-1298D01*
G02X1398414Y1085422I0J1298D01*
G01X1396792D01*
G02X1395753Y1084902I-1039J778D01*
G02Y1087498I0J1298D01*
G37*
G36*
G01X1401856Y1086200D02*
G02X1404452I1298J0D01*
G02X1403396Y1084925I-1298J0D01*
G01X1403306Y1084908D01*
X1402498Y1083510D01*
X1402529Y1083423D01*
G02X1402602Y1082995I-1225J-429D01*
G02X1400006I-1298J0D01*
G02X1401062Y1084270I1298J0D01*
G01X1401152Y1084287D01*
X1401960Y1085685D01*
X1401929Y1085772D01*
G02X1401856Y1086200I1225J429D01*
G37*
G36*
G01X401664Y1089404D02*
G02X404258I1297J0D01*
G02X404186Y1088976I-1297J-2D01*
G01X404155Y1088889D01*
X404962Y1087492D01*
X405052Y1087475D01*
G02X406108Y1086200I-242J-1275D01*
G02X403514I-1297J0D01*
G02X403586Y1086628I1297J2D01*
G01X403616Y1086714D01*
X402809Y1088112D01*
X402719Y1088129D01*
G02X401664Y1089404I243J1275D01*
G37*
G36*
G01X410362Y1090702D02*
G02X411401Y1090182I0J-1298D01*
G01X413023D01*
G02X414062Y1090702I1039J-778D01*
G02Y1088106I0J-1298D01*
G02X413023Y1088626I0J1298D01*
G01X411401D01*
G02X410362Y1088106I-1039J778D01*
G02Y1090702I0J1298D01*
G37*
G36*
G01X427564Y1089404D02*
G02X430158I1297J0D01*
G02X430086Y1088976I-1297J-2D01*
G01X430055Y1088889D01*
X430862Y1087492D01*
X430952Y1087475D01*
G02X432008Y1086200I-242J-1275D01*
G02X429412I-1298J0D01*
G02X429485Y1086629I1297J0D01*
G01X429516Y1086715D01*
X428709Y1088112D01*
X428619Y1088129D01*
G02X427564Y1089404I243J1275D01*
G37*
G36*
G01X1377806D02*
G02X1380400I1297J0D01*
G02X1380328Y1088976I-1297J-2D01*
G01X1380297Y1088889D01*
X1381104Y1087492D01*
X1381194Y1087475D01*
G02X1382250Y1086200I-242J-1275D01*
G02X1379656I-1297J0D01*
G02X1379728Y1086628I1297J2D01*
G01X1379758Y1086714D01*
X1378951Y1088112D01*
X1378861Y1088129D01*
G02X1377806Y1089404I243J1275D01*
G37*
G36*
G01X1386504Y1090702D02*
G02X1387543Y1090182I0J-1298D01*
G01X1389165D01*
G02X1390204Y1090702I1039J-778D01*
G02Y1088106I0J-1298D01*
G02X1389165Y1088626I0J1298D01*
G01X1387543D01*
G02X1386504Y1088106I-1039J778D01*
G02Y1090702I0J1298D01*
G37*
G36*
G01X1403706Y1089404D02*
G02X1406300I1297J0D01*
G02X1406228Y1088976I-1297J-2D01*
G01X1406197Y1088889D01*
X1407004Y1087492D01*
X1407094Y1087475D01*
G02X1408150Y1086200I-242J-1275D01*
G02X1405554I-1298J0D01*
G02X1405627Y1086629I1297J0D01*
G01X1405658Y1086715D01*
X1404851Y1088112D01*
X1404761Y1088129D01*
G02X1403706Y1089404I243J1275D01*
G37*
G36*
G01X407214Y1092608D02*
G02X409808I1297J0D01*
G02X408753Y1091333I-1298J0D01*
G01X408663Y1091316D01*
X407856Y1089919D01*
X407887Y1089833D01*
G02X407960Y1089404I-1224J-429D01*
G02X405364I-1298J0D01*
G02X406420Y1090679I1298J0D01*
G01X406510Y1090696D01*
X407317Y1092093D01*
X407286Y1092180D01*
G02X407214Y1092608I1225J426D01*
G37*
G36*
G01X418314D02*
G02X420908I1297J0D01*
G02X420836Y1092180I-1297J-2D01*
G01X420805Y1092093D01*
X421612Y1090696D01*
X421702Y1090679D01*
G02X422760Y1089404I-239J-1275D01*
G02X420164I-1298J0D01*
G02X420237Y1089831I1298J-2D01*
G01X420267Y1089917D01*
X419459Y1091316D01*
X419369Y1091333D01*
G02X418314Y1092608I243J1275D01*
G37*
G36*
G01X427011Y1093906D02*
G02X428050Y1093386I0J-1298D01*
G01X429672D01*
G02X430711Y1093906I1039J-778D01*
G02Y1091310I0J-1298D01*
G02X429672Y1091830I0J1298D01*
G01X428050D01*
G02X427011Y1091310I-1039J778D01*
G02Y1093906I0J1298D01*
G37*
G36*
G01X1383356Y1092608D02*
G02X1385950I1297J0D01*
G02X1384895Y1091333I-1298J0D01*
G01X1384805Y1091316D01*
X1383998Y1089919D01*
X1384029Y1089833D01*
G02X1384102Y1089404I-1224J-429D01*
G02X1381506I-1298J0D01*
G02X1382562Y1090679I1298J0D01*
G01X1382652Y1090696D01*
X1383459Y1092093D01*
X1383428Y1092180D01*
G02X1383356Y1092608I1225J426D01*
G37*
G36*
G01X1394456D02*
G02X1397050I1297J0D01*
G02X1396978Y1092180I-1297J-2D01*
G01X1396947Y1092093D01*
X1397754Y1090696D01*
X1397844Y1090679D01*
G02X1398902Y1089404I-239J-1275D01*
G02X1396306I-1298J0D01*
G02X1396379Y1089831I1298J-2D01*
G01X1396409Y1089917D01*
X1395601Y1091316D01*
X1395511Y1091333D01*
G02X1394456Y1092608I243J1275D01*
G37*
G36*
G01X1403153Y1093906D02*
G02X1404192Y1093386I0J-1298D01*
G01X1405814D01*
G02X1406853Y1093906I1039J-778D01*
G02Y1091310I0J-1298D01*
G02X1405814Y1091830I0J1298D01*
G01X1404192D01*
G02X1403153Y1091310I-1039J778D01*
G02Y1093906I0J1298D01*
G37*
G36*
G01X423864Y1095813D02*
G02X426460I1298J0D01*
G02X425404Y1094538I-1298J0D01*
G01X425314Y1094521D01*
X424506Y1093122D01*
X424536Y1093035D01*
G02X424608Y1092610I-1225J-426D01*
G01Y1092608D01*
G02X422014I-1297J0D01*
G02X423070Y1093883I1298J0D01*
G01X423161Y1093900D01*
X423968Y1095298D01*
X423937Y1095385D01*
G02X423864Y1095813I1225J429D01*
G37*
G36*
G01X1400006D02*
G02X1402602I1298J0D01*
G02X1401546Y1094538I-1298J0D01*
G01X1401456Y1094521D01*
X1400648Y1093122D01*
X1400678Y1093035D01*
G02X1400750Y1092610I-1225J-426D01*
G01Y1092608D01*
G02X1398156I-1297J0D01*
G02X1399212Y1093883I1298J0D01*
G01X1399303Y1093900D01*
X1400110Y1095298D01*
X1400079Y1095385D01*
G02X1400006Y1095813I1225J429D01*
G37*
G36*
G01X404811Y1100314D02*
G02X405850Y1099794I0J-1298D01*
G01X407472D01*
G02X408511Y1100314I1039J-778D01*
G02Y1097720I0J-1297D01*
G02X407472Y1098240I0J1298D01*
G01X405850D01*
G02X404811Y1097720I-1039J778D01*
G02Y1100314I0J1297D01*
G37*
G36*
G01X1380953D02*
G02X1381992Y1099794I0J-1298D01*
G01X1383614D01*
G02X1384653Y1100314I1039J-778D01*
G02Y1097720I0J-1297D01*
G02X1383614Y1098240I0J1298D01*
G01X1381992D01*
G02X1380953Y1097720I-1039J778D01*
G02Y1100314I0J1297D01*
G37*
G36*
G01X351161Y1103518D02*
G02X352200Y1102998I0J-1298D01*
G01X353822D01*
G02X354861Y1103518I1039J-778D01*
G02Y1100924I0J-1297D01*
G02X353822Y1101444I0J1298D01*
G01X352200D01*
G02X351161Y1100924I-1039J778D01*
G02Y1103518I0J1297D01*
G37*
G36*
G01X401664Y1102221D02*
G02X404260I1298J0D01*
G02X403204Y1100946I-1298J0D01*
G01X403114Y1100929D01*
X402306Y1099530D01*
X402336Y1099444D01*
G02X402408Y1099019I-1225J-426D01*
G01Y1099017D01*
G02X399814I-1297J0D01*
G02X400871Y1100292I1297J0D01*
G01X400961Y1100309D01*
X401768Y1101706D01*
X401737Y1101793D01*
G02X401664Y1102221I1225J429D01*
G37*
G36*
G01X1327303Y1103518D02*
G02X1328342Y1102998I0J-1298D01*
G01X1329964D01*
G02X1331003Y1103518I1039J-778D01*
G02Y1100924I0J-1297D01*
G02X1329964Y1101444I0J1298D01*
G01X1328342D01*
G02X1327303Y1100924I-1039J778D01*
G02Y1103518I0J1297D01*
G37*
G36*
G01X1377806Y1102221D02*
G02X1380402I1298J0D01*
G02X1379346Y1100946I-1298J0D01*
G01X1379256Y1100929D01*
X1378448Y1099530D01*
X1378478Y1099444D01*
G02X1378550Y1099019I-1225J-426D01*
G01Y1099017D01*
G02X1375956I-1297J0D01*
G02X1377013Y1100292I1297J0D01*
G01X1377103Y1100309D01*
X1377910Y1101706D01*
X1377879Y1101793D01*
G02X1377806Y1102221I1225J429D01*
G37*
G36*
G01X375211Y1106724D02*
G02X376250Y1106204I0J-1298D01*
G01X377873D01*
G02X378912Y1106724I1039J-778D01*
G02Y1104128I0J-1298D01*
G02X377873Y1104648I0J1298D01*
G01X376250D01*
G02X375211Y1104128I-1039J778D01*
G02Y1106724I0J1298D01*
G37*
G36*
G01X381314Y1105426D02*
G02X383908I1297J0D01*
G02X382853Y1104151I-1298J0D01*
G01X382763Y1104134D01*
X381956Y1102737D01*
X381986Y1102650D01*
G02X382060Y1102221I-1223J-432D01*
G02X379464I-1298J0D01*
G02X380519Y1103496I1298J0D01*
G01X380609Y1103513D01*
X381417Y1104911D01*
X381386Y1104998D01*
G02X381314Y1105426I1225J426D01*
G37*
G36*
G01X410914D02*
G02X413508I1297J0D01*
G02X413436Y1104998I-1297J-2D01*
G01X413405Y1104911D01*
X414212Y1103513D01*
X414303Y1103496D01*
G02X415360Y1102221I-240J-1275D01*
G02X412764I-1298J0D01*
G02X412837Y1102648I1298J-2D01*
G01X412867Y1102735D01*
X412059Y1104134D01*
X411969Y1104151D01*
G02X410914Y1105426I243J1275D01*
G37*
G36*
G01X415911Y1106724D02*
G02X416950Y1106204I0J-1298D01*
G01X418572D01*
G02X419611Y1106724I1039J-778D01*
G02Y1104128I0J-1298D01*
G02X418572Y1104648I0J1298D01*
G01X416950D01*
G02X415911Y1104128I-1039J778D01*
G02Y1106724I0J1298D01*
G37*
G36*
G01X1351353D02*
G02X1352392Y1106204I0J-1298D01*
G01X1354015D01*
G02X1355054Y1106724I1039J-778D01*
G02Y1104128I0J-1298D01*
G02X1354015Y1104648I0J1298D01*
G01X1352392D01*
G02X1351353Y1104128I-1039J778D01*
G02Y1106724I0J1298D01*
G37*
G36*
G01X1357456Y1105426D02*
G02X1360050I1297J0D01*
G02X1358995Y1104151I-1298J0D01*
G01X1358905Y1104134D01*
X1358098Y1102737D01*
X1358128Y1102650D01*
G02X1358202Y1102221I-1223J-432D01*
G02X1355606I-1298J0D01*
G02X1356661Y1103496I1298J0D01*
G01X1356751Y1103513D01*
X1357559Y1104911D01*
X1357528Y1104998D01*
G02X1357456Y1105426I1225J426D01*
G37*
G36*
G01X1387056D02*
G02X1389650I1297J0D01*
G02X1389578Y1104998I-1297J-2D01*
G01X1389547Y1104911D01*
X1390354Y1103513D01*
X1390445Y1103496D01*
G02X1391502Y1102221I-240J-1275D01*
G02X1388906I-1298J0D01*
G02X1388979Y1102648I1298J-2D01*
G01X1389009Y1102735D01*
X1388201Y1104134D01*
X1388111Y1104151D01*
G02X1387056Y1105426I243J1275D01*
G37*
G36*
G01X1392053Y1106724D02*
G02X1393092Y1106204I0J-1298D01*
G01X1394714D01*
G02X1395753Y1106724I1039J-778D01*
G02Y1104128I0J-1298D01*
G02X1394714Y1104648I0J1298D01*
G01X1393092D01*
G02X1392053Y1104128I-1039J778D01*
G02Y1106724I0J1298D01*
G37*
G36*
G01X358561Y1109928D02*
G02X359600Y1109408I0J-1298D01*
G01X361222D01*
G02X362261Y1109928I1039J-778D01*
G02Y1107332I0J-1298D01*
G02X361222Y1107852I0J1298D01*
G01X359600D01*
G02X358561Y1107332I-1039J778D01*
G02Y1109928I0J1298D01*
G37*
G36*
G01X383164Y1108630D02*
G02X385760I1298J0D01*
G02X385687Y1108202I-1298J1D01*
G01X385656Y1108115D01*
X386463Y1106718D01*
X386553Y1106701D01*
G02X387608Y1105426I-243J-1275D01*
G02X385014I-1297J0D01*
G02X385086Y1105855I1297J3D01*
G01X385117Y1105941D01*
X384310Y1107338D01*
X384220Y1107355D01*
G02X383164Y1108630I242J1275D01*
G37*
G36*
G01X391862Y1109928D02*
G02X392901Y1109408I0J-1298D01*
G01X394523D01*
G02X395562Y1109928I1039J-778D01*
G02Y1107332I0J-1298D01*
G02X394523Y1107852I0J1298D01*
G01X392901D01*
G02X391862Y1107332I-1039J778D01*
G02Y1109928I0J1298D01*
G37*
G36*
G01X397964Y1108630D02*
G02X400560I1298J0D01*
G02X399504Y1107355I-1298J0D01*
G01X399414Y1107338D01*
X398606Y1105939D01*
X398636Y1105853D01*
G02X398708Y1105428I-1225J-426D01*
G01Y1105426D01*
G02X396114I-1297J0D01*
G02X397171Y1106701I1297J0D01*
G01X397261Y1106718D01*
X398068Y1108115D01*
X398037Y1108202D01*
G02X397964Y1108630I1225J429D01*
G37*
G36*
G01X409064D02*
G02X411660I1298J0D01*
G02X410604Y1107355I-1298J0D01*
G01X410514Y1107338D01*
X409706Y1105939D01*
X409736Y1105853D01*
G02X409808Y1105428I-1225J-426D01*
G01Y1105426D01*
G02X407214I-1297J0D01*
G02X408271Y1106701I1297J0D01*
G01X408361Y1106718D01*
X409168Y1108115D01*
X409137Y1108202D01*
G02X409064Y1108630I1225J429D01*
G37*
G36*
G01X1334703Y1109928D02*
G02X1335742Y1109408I0J-1298D01*
G01X1337364D01*
G02X1338403Y1109928I1039J-778D01*
G02Y1107332I0J-1298D01*
G02X1337364Y1107852I0J1298D01*
G01X1335742D01*
G02X1334703Y1107332I-1039J778D01*
G02Y1109928I0J1298D01*
G37*
G36*
G01X1359306Y1108630D02*
G02X1361902I1298J0D01*
G02X1361829Y1108202I-1298J1D01*
G01X1361798Y1108115D01*
X1362605Y1106718D01*
X1362695Y1106701D01*
G02X1363750Y1105426I-243J-1275D01*
G02X1361156I-1297J0D01*
G02X1361228Y1105855I1297J3D01*
G01X1361259Y1105941D01*
X1360452Y1107338D01*
X1360362Y1107355D01*
G02X1359306Y1108630I242J1275D01*
G37*
G36*
G01X1368004Y1109928D02*
G02X1369043Y1109408I0J-1298D01*
G01X1370665D01*
G02X1371704Y1109928I1039J-778D01*
G02Y1107332I0J-1298D01*
G02X1370665Y1107852I0J1298D01*
G01X1369043D01*
G02X1368004Y1107332I-1039J778D01*
G02Y1109928I0J1298D01*
G37*
G36*
G01X1374106Y1108630D02*
G02X1376702I1298J0D01*
G02X1375646Y1107355I-1298J0D01*
G01X1375556Y1107338D01*
X1374748Y1105939D01*
X1374778Y1105853D01*
G02X1374850Y1105428I-1225J-426D01*
G01Y1105426D01*
G02X1372256I-1297J0D01*
G02X1373313Y1106701I1297J0D01*
G01X1373403Y1106718D01*
X1374210Y1108115D01*
X1374179Y1108202D01*
G02X1374106Y1108630I1225J429D01*
G37*
G36*
G01X1385206D02*
G02X1387802I1298J0D01*
G02X1386746Y1107355I-1298J0D01*
G01X1386656Y1107338D01*
X1385848Y1105939D01*
X1385878Y1105853D01*
G02X1385950Y1105428I-1225J-426D01*
G01Y1105426D01*
G02X1383356I-1297J0D01*
G02X1384413Y1106701I1297J0D01*
G01X1384503Y1106718D01*
X1385310Y1108115D01*
X1385279Y1108202D01*
G02X1385206Y1108630I1225J429D01*
G37*
G36*
G01X366514Y1111834D02*
G02X369110I1298J0D01*
G02X369037Y1111406I-1298J1D01*
G01X369006Y1111319D01*
X369813Y1109922D01*
X369903Y1109905D01*
G02X370958Y1108630I-243J-1275D01*
G02X368364I-1297J0D01*
G02X368436Y1109059I1297J3D01*
G01X368467Y1109145D01*
X367660Y1110542D01*
X367570Y1110559D01*
G02X366514Y1111834I242J1275D01*
G37*
G36*
G01X373914D02*
G02X376508I1297J0D01*
G02X376436Y1111406I-1297J-2D01*
G01X376405Y1111319D01*
X377212Y1109922D01*
X377302Y1109905D01*
G02X378360Y1108630I-239J-1275D01*
G02X375764I-1298J0D01*
G02X375837Y1109057I1298J-2D01*
G01X375867Y1109143D01*
X375059Y1110542D01*
X374969Y1110559D01*
G02X373914Y1111834I243J1275D01*
G37*
G36*
G01X382611Y1113132D02*
G02X383650Y1112612I0J-1298D01*
G01X385272D01*
G02X386311Y1113132I1039J-778D01*
G02Y1110536I0J-1298D01*
G02X385272Y1111056I0J1298D01*
G01X383650D01*
G02X382611Y1110536I-1039J778D01*
G02Y1113132I0J1298D01*
G37*
G36*
G01X399814Y1111834D02*
G02X402408I1297J0D01*
G02X402336Y1111406I-1297J-2D01*
G01X402305Y1111319D01*
X403112Y1109922D01*
X403202Y1109905D01*
G02X404260Y1108630I-239J-1275D01*
G02X401664I-1298J0D01*
G02X401737Y1109057I1298J-2D01*
G01X401767Y1109143D01*
X400959Y1110542D01*
X400869Y1110559D01*
G02X399814Y1111834I243J1275D01*
G37*
G36*
G01X408511Y1113132D02*
G02X409550Y1112612I0J-1298D01*
G01X411172D01*
G02X412211Y1113132I1039J-778D01*
G02Y1110536I0J-1298D01*
G02X411172Y1111056I0J1298D01*
G01X409550D01*
G02X408511Y1110536I-1039J778D01*
G02Y1113132I0J1298D01*
G37*
G36*
G01X418314Y1111834D02*
G02X420908I1297J0D01*
G02X419853Y1110559I-1298J0D01*
G01X419763Y1110542D01*
X418956Y1109145D01*
X418987Y1109059D01*
G02X419060Y1108630I-1224J-429D01*
G02X416464I-1298J0D01*
G02X417520Y1109905I1298J0D01*
G01X417610Y1109922D01*
X418417Y1111319D01*
X418386Y1111406D01*
G02X418314Y1111834I1225J426D01*
G37*
G36*
G01X1342656D02*
G02X1345252I1298J0D01*
G02X1345179Y1111406I-1298J1D01*
G01X1345148Y1111319D01*
X1345955Y1109922D01*
X1346045Y1109905D01*
G02X1347100Y1108630I-243J-1275D01*
G02X1344506I-1297J0D01*
G02X1344578Y1109059I1297J3D01*
G01X1344609Y1109145D01*
X1343802Y1110542D01*
X1343712Y1110559D01*
G02X1342656Y1111834I242J1275D01*
G37*
G36*
G01X1350056D02*
G02X1352650I1297J0D01*
G02X1352578Y1111406I-1297J-2D01*
G01X1352547Y1111319D01*
X1353354Y1109922D01*
X1353444Y1109905D01*
G02X1354502Y1108630I-239J-1275D01*
G02X1351906I-1298J0D01*
G02X1351979Y1109057I1298J-2D01*
G01X1352009Y1109143D01*
X1351201Y1110542D01*
X1351111Y1110559D01*
G02X1350056Y1111834I243J1275D01*
G37*
G36*
G01X1358753Y1113132D02*
G02X1359792Y1112612I0J-1298D01*
G01X1361414D01*
G02X1362453Y1113132I1039J-778D01*
G02Y1110536I0J-1298D01*
G02X1361414Y1111056I0J1298D01*
G01X1359792D01*
G02X1358753Y1110536I-1039J778D01*
G02Y1113132I0J1298D01*
G37*
G36*
G01X1375956Y1111834D02*
G02X1378550I1297J0D01*
G02X1378478Y1111406I-1297J-2D01*
G01X1378447Y1111319D01*
X1379254Y1109922D01*
X1379344Y1109905D01*
G02X1380402Y1108630I-239J-1275D01*
G02X1377806I-1298J0D01*
G02X1377879Y1109057I1298J-2D01*
G01X1377909Y1109143D01*
X1377101Y1110542D01*
X1377011Y1110559D01*
G02X1375956Y1111834I243J1275D01*
G37*
G36*
G01X1384653Y1113132D02*
G02X1385692Y1112612I0J-1298D01*
G01X1387314D01*
G02X1388353Y1113132I1039J-778D01*
G02Y1110536I0J-1298D01*
G02X1387314Y1111056I0J1298D01*
G01X1385692D01*
G02X1384653Y1110536I-1039J778D01*
G02Y1113132I0J1298D01*
G37*
G36*
G01X1394456Y1111834D02*
G02X1397050I1297J0D01*
G02X1395995Y1110559I-1298J0D01*
G01X1395905Y1110542D01*
X1395098Y1109145D01*
X1395129Y1109059D01*
G02X1395202Y1108630I-1224J-429D01*
G02X1392606I-1298J0D01*
G02X1393662Y1109905I1298J0D01*
G01X1393752Y1109922D01*
X1394559Y1111319D01*
X1394528Y1111406D01*
G02X1394456Y1111834I1225J426D01*
G37*
G36*
G01X346164Y1115039D02*
G02X348758I1297J0D01*
G02X347703Y1113764I-1298J0D01*
G01X347613Y1113747D01*
X346805Y1112349D01*
X346836Y1112262D01*
G02X346908Y1111834I-1225J-426D01*
G02X344314I-1297J0D01*
G02X345369Y1113109I1298J0D01*
G01X345459Y1113126D01*
X346267Y1114524D01*
X346236Y1114611D01*
G02X346164Y1115039I1225J426D01*
G37*
G36*
G01X365961Y1116336D02*
G02X367000Y1115816I0J-1298D01*
G01X368622D01*
G02X369661Y1116336I1039J-778D01*
G02Y1113742I0J-1297D01*
G02X368622Y1114262I0J1298D01*
G01X367000D01*
G02X365961Y1113742I-1039J778D01*
G02Y1116336I0J1297D01*
G37*
G36*
G01X379464Y1115039D02*
G02X382060I1298J0D01*
G02X381004Y1113764I-1298J0D01*
G01X380914Y1113747D01*
X380106Y1112348D01*
X380136Y1112261D01*
G02X380208Y1111836I-1225J-426D01*
G01Y1111834D01*
G02X377614I-1297J0D01*
G02X378670Y1113109I1298J0D01*
G01X378761Y1113126D01*
X379568Y1114524D01*
X379537Y1114611D01*
G02X379464Y1115039I1225J429D01*
G37*
G36*
G01X390564D02*
G02X393160I1298J0D01*
G02X393087Y1114611I-1298J1D01*
G01X393056Y1114524D01*
X393864Y1113126D01*
X393954Y1113109D01*
G02X395008Y1111834I-244J-1275D01*
G02X392414I-1297J0D01*
G02X392487Y1112263I1297J0D01*
G01X392517Y1112350D01*
X391710Y1113747D01*
X391620Y1113764D01*
G02X390564Y1115039I242J1275D01*
G37*
G36*
G01X399262Y1116336D02*
G02X400301Y1115816I0J-1298D01*
G01X401923D01*
G02X402962Y1116336I1039J-778D01*
G02Y1113742I0J-1297D01*
G02X401923Y1114262I0J1298D01*
G01X400301D01*
G02X399262Y1113742I-1039J778D01*
G02Y1116336I0J1297D01*
G37*
G36*
G01X412764Y1115039D02*
G02X415360I1298J0D01*
G02X415287Y1114611I-1298J1D01*
G01X415256Y1114524D01*
X416064Y1113126D01*
X416154Y1113109D01*
G02X417208Y1111834I-244J-1275D01*
G02X414614I-1297J0D01*
G02X414687Y1112263I1297J0D01*
G01X414717Y1112350D01*
X413910Y1113747D01*
X413820Y1113764D01*
G02X412764Y1115039I242J1275D01*
G37*
G36*
G01X1322306D02*
G02X1324900I1297J0D01*
G02X1323845Y1113764I-1298J0D01*
G01X1323755Y1113747D01*
X1322947Y1112349D01*
X1322978Y1112262D01*
G02X1323050Y1111834I-1225J-426D01*
G02X1320456I-1297J0D01*
G02X1321511Y1113109I1298J0D01*
G01X1321601Y1113126D01*
X1322409Y1114524D01*
X1322378Y1114611D01*
G02X1322306Y1115039I1225J426D01*
G37*
G36*
G01X1342103Y1116336D02*
G02X1343142Y1115816I0J-1298D01*
G01X1344764D01*
G02X1345803Y1116336I1039J-778D01*
G02Y1113742I0J-1297D01*
G02X1344764Y1114262I0J1298D01*
G01X1343142D01*
G02X1342103Y1113742I-1039J778D01*
G02Y1116336I0J1297D01*
G37*
G36*
G01X1355606Y1115039D02*
G02X1358202I1298J0D01*
G02X1357146Y1113764I-1298J0D01*
G01X1357056Y1113747D01*
X1356248Y1112348D01*
X1356278Y1112261D01*
G02X1356350Y1111836I-1225J-426D01*
G01Y1111834D01*
G02X1353756I-1297J0D01*
G02X1354812Y1113109I1298J0D01*
G01X1354903Y1113126D01*
X1355710Y1114524D01*
X1355679Y1114611D01*
G02X1355606Y1115039I1225J429D01*
G37*
G36*
G01X1366706D02*
G02X1369302I1298J0D01*
G02X1369229Y1114611I-1298J1D01*
G01X1369198Y1114524D01*
X1370006Y1113126D01*
X1370096Y1113109D01*
G02X1371150Y1111834I-244J-1275D01*
G02X1368556I-1297J0D01*
G02X1368629Y1112263I1297J0D01*
G01X1368659Y1112350D01*
X1367852Y1113747D01*
X1367762Y1113764D01*
G02X1366706Y1115039I242J1275D01*
G37*
G36*
G01X1375404Y1116336D02*
G02X1376443Y1115816I0J-1298D01*
G01X1378065D01*
G02X1379104Y1116336I1039J-778D01*
G02Y1113742I0J-1297D01*
G02X1378065Y1114262I0J1298D01*
G01X1376443D01*
G02X1375404Y1113742I-1039J778D01*
G02Y1116336I0J1297D01*
G37*
G36*
G01X1388906Y1115039D02*
G02X1391502I1298J0D01*
G02X1391429Y1114611I-1298J1D01*
G01X1391398Y1114524D01*
X1392206Y1113126D01*
X1392296Y1113109D01*
G02X1393350Y1111834I-244J-1275D01*
G02X1390756I-1297J0D01*
G02X1390829Y1112263I1297J0D01*
G01X1390859Y1112350D01*
X1390052Y1113747D01*
X1389962Y1113764D01*
G02X1388906Y1115039I242J1275D01*
G37*
G36*
G01X342464Y1121447D02*
G02X345058I1297J0D01*
G02X344003Y1120172I-1298J0D01*
G01X343913Y1120155D01*
X343106Y1118758D01*
X343137Y1118671D01*
G02X343210Y1118243I-1225J-429D01*
G02X340614I-1298J0D01*
G02X341670Y1119518I1298J0D01*
G01X341760Y1119535D01*
X342567Y1120932D01*
X342536Y1121019D01*
G02X342464Y1121447I1225J426D01*
G37*
G36*
G01X1318606D02*
G02X1321200I1297J0D01*
G02X1320145Y1120172I-1298J0D01*
G01X1320055Y1120155D01*
X1319248Y1118758D01*
X1319279Y1118671D01*
G02X1319352Y1118243I-1225J-429D01*
G02X1316756I-1298J0D01*
G02X1317812Y1119518I1298J0D01*
G01X1317902Y1119535D01*
X1318709Y1120932D01*
X1318678Y1121019D01*
G02X1318606Y1121447I1225J426D01*
G37*
G36*
G01X355414Y1124651D02*
G02X358010I1298J0D01*
G02X357937Y1124223I-1298J1D01*
G01X357906Y1124136D01*
X358713Y1122739D01*
X358803Y1122722D01*
G02X359858Y1121447I-243J-1275D01*
G02X357264I-1297J0D01*
G02X357336Y1121876I1297J3D01*
G01X357367Y1121962D01*
X356560Y1123359D01*
X356470Y1123376D01*
G02X355414Y1124651I242J1275D01*
G37*
G36*
G01X362814D02*
G02X365408I1297J0D01*
G02X365336Y1124223I-1297J-2D01*
G01X365305Y1124136D01*
X366112Y1122739D01*
X366202Y1122722D01*
G02X367260Y1121447I-239J-1275D01*
G02X364664I-1298J0D01*
G02X364737Y1121874I1298J-2D01*
G01X364767Y1121960D01*
X363959Y1123359D01*
X363869Y1123376D01*
G02X362814Y1124651I243J1275D01*
G37*
G36*
G01X370214D02*
G02X372808I1297J0D01*
G02X372736Y1124223I-1297J-2D01*
G01X372705Y1124136D01*
X373512Y1122739D01*
X373602Y1122722D01*
G02X374660Y1121447I-239J-1275D01*
G02X372064I-1298J0D01*
G02X372137Y1121874I1298J-2D01*
G01X372167Y1121960D01*
X371359Y1123359D01*
X371269Y1123376D01*
G02X370214Y1124651I243J1275D01*
G37*
G36*
G01X377614D02*
G02X380208I1297J0D01*
G02X380136Y1124223I-1297J-2D01*
G01X380105Y1124136D01*
X380912Y1122739D01*
X381002Y1122722D01*
G02X382060Y1121447I-239J-1275D01*
G02X379464I-1298J0D01*
G02X379537Y1121874I1298J-2D01*
G01X379567Y1121960D01*
X378759Y1123359D01*
X378669Y1123376D01*
G02X377614Y1124651I243J1275D01*
G37*
G36*
G01X385014D02*
G02X387608I1297J0D01*
G02X387536Y1124223I-1297J-2D01*
G01X387505Y1124136D01*
X388312Y1122739D01*
X388402Y1122722D01*
G02X389460Y1121447I-239J-1275D01*
G02X386864I-1298J0D01*
G02X386937Y1121874I1298J-2D01*
G01X386967Y1121960D01*
X386159Y1123359D01*
X386069Y1123376D01*
G02X385014Y1124651I243J1275D01*
G37*
G36*
G01X392414D02*
G02X395008I1297J0D01*
G02X394936Y1124223I-1297J-2D01*
G01X394905Y1124136D01*
X395712Y1122739D01*
X395802Y1122722D01*
G02X396860Y1121447I-239J-1275D01*
G02X394264I-1298J0D01*
G02X394337Y1121874I1298J-2D01*
G01X394367Y1121960D01*
X393559Y1123359D01*
X393469Y1123376D01*
G02X392414Y1124651I243J1275D01*
G37*
G36*
G01X399814D02*
G02X402408I1297J0D01*
G02X402336Y1124223I-1297J-2D01*
G01X402305Y1124136D01*
X403112Y1122739D01*
X403202Y1122722D01*
G02X404260Y1121447I-239J-1275D01*
G02X401664I-1298J0D01*
G02X401737Y1121874I1298J-2D01*
G01X401767Y1121960D01*
X400959Y1123359D01*
X400869Y1123376D01*
G02X399814Y1124651I243J1275D01*
G37*
G36*
G01X407214D02*
G02X409808I1297J0D01*
G02X409736Y1124223I-1297J-2D01*
G01X409705Y1124136D01*
X410512Y1122739D01*
X410602Y1122722D01*
G02X411660Y1121447I-239J-1275D01*
G02X409064I-1298J0D01*
G02X409137Y1121874I1298J-2D01*
G01X409167Y1121960D01*
X408359Y1123359D01*
X408269Y1123376D01*
G02X407214Y1124651I243J1275D01*
G37*
G36*
G01X470114D02*
G02X472708I1297J0D01*
G02X471653Y1123376I-1298J0D01*
G01X471563Y1123359D01*
X470756Y1121962D01*
X470787Y1121875D01*
G02X470860Y1121447I-1225J-429D01*
G02X468264I-1298J0D01*
G02X469320Y1122722I1298J0D01*
G01X469410Y1122739D01*
X470217Y1124136D01*
X470186Y1124223D01*
G02X470114Y1124651I1225J426D01*
G37*
G36*
G01X477514D02*
G02X480108I1297J0D01*
G02X479053Y1123376I-1298J0D01*
G01X478963Y1123359D01*
X478156Y1121962D01*
X478187Y1121875D01*
G02X478260Y1121447I-1225J-429D01*
G02X475664I-1298J0D01*
G02X476720Y1122722I1298J0D01*
G01X476810Y1122739D01*
X477617Y1124136D01*
X477586Y1124223D01*
G02X477514Y1124651I1225J426D01*
G37*
G36*
G01X484914D02*
G02X487508I1297J0D01*
G02X486453Y1123376I-1298J0D01*
G01X486363Y1123359D01*
X485556Y1121962D01*
X485587Y1121875D01*
G02X485660Y1121447I-1225J-429D01*
G02X483064I-1298J0D01*
G02X484120Y1122722I1298J0D01*
G01X484210Y1122739D01*
X485017Y1124136D01*
X484986Y1124223D01*
G02X484914Y1124651I1225J426D01*
G37*
G36*
G01X492314D02*
G02X494908I1297J0D01*
G02X493853Y1123376I-1298J0D01*
G01X493763Y1123359D01*
X492956Y1121962D01*
X492987Y1121875D01*
G02X493060Y1121447I-1225J-429D01*
G02X490464I-1298J0D01*
G02X491520Y1122722I1298J0D01*
G01X491610Y1122739D01*
X492417Y1124136D01*
X492386Y1124223D01*
G02X492314Y1124651I1225J426D01*
G37*
G36*
G01X499714D02*
G02X502308I1297J0D01*
G02X501253Y1123376I-1298J0D01*
G01X501163Y1123359D01*
X500356Y1121962D01*
X500387Y1121875D01*
G02X500460Y1121447I-1225J-429D01*
G02X497864I-1298J0D01*
G02X498920Y1122722I1298J0D01*
G01X499010Y1122739D01*
X499817Y1124136D01*
X499786Y1124223D01*
G02X499714Y1124651I1225J426D01*
G37*
G36*
G01X507114D02*
G02X509708I1297J0D01*
G02X508653Y1123376I-1298J0D01*
G01X508563Y1123359D01*
X507756Y1121962D01*
X507787Y1121875D01*
G02X507860Y1121447I-1225J-429D01*
G02X505264I-1298J0D01*
G02X506320Y1122722I1298J0D01*
G01X506410Y1122739D01*
X507217Y1124136D01*
X507186Y1124223D01*
G02X507114Y1124651I1225J426D01*
G37*
G36*
G01X514514D02*
G02X517108I1297J0D01*
G02X516053Y1123376I-1298J0D01*
G01X515963Y1123359D01*
X515156Y1121962D01*
X515187Y1121875D01*
G02X515260Y1121447I-1225J-429D01*
G02X512664I-1298J0D01*
G02X513720Y1122722I1298J0D01*
G01X513810Y1122739D01*
X514617Y1124136D01*
X514586Y1124223D01*
G02X514514Y1124651I1225J426D01*
G37*
G36*
G01X521914D02*
G02X524508I1297J0D01*
G02X523453Y1123376I-1298J0D01*
G01X523363Y1123359D01*
X522556Y1121962D01*
X522587Y1121875D01*
G02X522660Y1121447I-1225J-429D01*
G02X520064I-1298J0D01*
G02X521120Y1122722I1298J0D01*
G01X521210Y1122739D01*
X522017Y1124136D01*
X521986Y1124223D01*
G02X521914Y1124651I1225J426D01*
G37*
G36*
G01X1331556D02*
G02X1334152I1298J0D01*
G02X1334079Y1124223I-1298J1D01*
G01X1334048Y1124136D01*
X1334855Y1122739D01*
X1334945Y1122722D01*
G02X1336000Y1121447I-243J-1275D01*
G02X1333406I-1297J0D01*
G02X1333478Y1121876I1297J3D01*
G01X1333509Y1121962D01*
X1332702Y1123359D01*
X1332612Y1123376D01*
G02X1331556Y1124651I242J1275D01*
G37*
G36*
G01X1338956D02*
G02X1341550I1297J0D01*
G02X1341478Y1124223I-1297J-2D01*
G01X1341447Y1124136D01*
X1342254Y1122739D01*
X1342344Y1122722D01*
G02X1343402Y1121447I-239J-1275D01*
G02X1340806I-1298J0D01*
G02X1340879Y1121874I1298J-2D01*
G01X1340909Y1121960D01*
X1340101Y1123359D01*
X1340011Y1123376D01*
G02X1338956Y1124651I243J1275D01*
G37*
G36*
G01X1346356D02*
G02X1348950I1297J0D01*
G02X1348878Y1124223I-1297J-2D01*
G01X1348847Y1124136D01*
X1349654Y1122739D01*
X1349744Y1122722D01*
G02X1350802Y1121447I-239J-1275D01*
G02X1348206I-1298J0D01*
G02X1348279Y1121874I1298J-2D01*
G01X1348309Y1121960D01*
X1347501Y1123359D01*
X1347411Y1123376D01*
G02X1346356Y1124651I243J1275D01*
G37*
G36*
G01X1353756D02*
G02X1356350I1297J0D01*
G02X1356278Y1124223I-1297J-2D01*
G01X1356247Y1124136D01*
X1357054Y1122739D01*
X1357144Y1122722D01*
G02X1358202Y1121447I-239J-1275D01*
G02X1355606I-1298J0D01*
G02X1355679Y1121874I1298J-2D01*
G01X1355709Y1121960D01*
X1354901Y1123359D01*
X1354811Y1123376D01*
G02X1353756Y1124651I243J1275D01*
G37*
G36*
G01X1361156D02*
G02X1363750I1297J0D01*
G02X1363678Y1124223I-1297J-2D01*
G01X1363647Y1124136D01*
X1364454Y1122739D01*
X1364544Y1122722D01*
G02X1365602Y1121447I-239J-1275D01*
G02X1363006I-1298J0D01*
G02X1363079Y1121874I1298J-2D01*
G01X1363109Y1121960D01*
X1362301Y1123359D01*
X1362211Y1123376D01*
G02X1361156Y1124651I243J1275D01*
G37*
G36*
G01X1368556D02*
G02X1371150I1297J0D01*
G02X1371078Y1124223I-1297J-2D01*
G01X1371047Y1124136D01*
X1371854Y1122739D01*
X1371944Y1122722D01*
G02X1373002Y1121447I-239J-1275D01*
G02X1370406I-1298J0D01*
G02X1370479Y1121874I1298J-2D01*
G01X1370509Y1121960D01*
X1369701Y1123359D01*
X1369611Y1123376D01*
G02X1368556Y1124651I243J1275D01*
G37*
G36*
G01X1375956D02*
G02X1378550I1297J0D01*
G02X1378478Y1124223I-1297J-2D01*
G01X1378447Y1124136D01*
X1379254Y1122739D01*
X1379344Y1122722D01*
G02X1380402Y1121447I-239J-1275D01*
G02X1377806I-1298J0D01*
G02X1377879Y1121874I1298J-2D01*
G01X1377909Y1121960D01*
X1377101Y1123359D01*
X1377011Y1123376D01*
G02X1375956Y1124651I243J1275D01*
G37*
G36*
G01X1383356D02*
G02X1385950I1297J0D01*
G02X1385878Y1124223I-1297J-2D01*
G01X1385847Y1124136D01*
X1386654Y1122739D01*
X1386744Y1122722D01*
G02X1387802Y1121447I-239J-1275D01*
G02X1385206I-1298J0D01*
G02X1385279Y1121874I1298J-2D01*
G01X1385309Y1121960D01*
X1384501Y1123359D01*
X1384411Y1123376D01*
G02X1383356Y1124651I243J1275D01*
G37*
G36*
G01X1446256D02*
G02X1448850I1297J0D01*
G02X1447795Y1123376I-1298J0D01*
G01X1447705Y1123359D01*
X1446898Y1121962D01*
X1446929Y1121875D01*
G02X1447002Y1121447I-1225J-429D01*
G02X1444406I-1298J0D01*
G02X1445462Y1122722I1298J0D01*
G01X1445552Y1122739D01*
X1446359Y1124136D01*
X1446328Y1124223D01*
G02X1446256Y1124651I1225J426D01*
G37*
G36*
G01X1453656D02*
G02X1456250I1297J0D01*
G02X1455195Y1123376I-1298J0D01*
G01X1455105Y1123359D01*
X1454298Y1121962D01*
X1454329Y1121875D01*
G02X1454402Y1121447I-1225J-429D01*
G02X1451806I-1298J0D01*
G02X1452862Y1122722I1298J0D01*
G01X1452952Y1122739D01*
X1453759Y1124136D01*
X1453728Y1124223D01*
G02X1453656Y1124651I1225J426D01*
G37*
G36*
G01X1461056D02*
G02X1463650I1297J0D01*
G02X1462595Y1123376I-1298J0D01*
G01X1462505Y1123359D01*
X1461698Y1121962D01*
X1461729Y1121875D01*
G02X1461802Y1121447I-1225J-429D01*
G02X1459206I-1298J0D01*
G02X1460262Y1122722I1298J0D01*
G01X1460352Y1122739D01*
X1461159Y1124136D01*
X1461128Y1124223D01*
G02X1461056Y1124651I1225J426D01*
G37*
G36*
G01X1468456D02*
G02X1471050I1297J0D01*
G02X1469995Y1123376I-1298J0D01*
G01X1469905Y1123359D01*
X1469098Y1121962D01*
X1469129Y1121875D01*
G02X1469202Y1121447I-1225J-429D01*
G02X1466606I-1298J0D01*
G02X1467662Y1122722I1298J0D01*
G01X1467752Y1122739D01*
X1468559Y1124136D01*
X1468528Y1124223D01*
G02X1468456Y1124651I1225J426D01*
G37*
G36*
G01X1475856D02*
G02X1478450I1297J0D01*
G02X1477395Y1123376I-1298J0D01*
G01X1477305Y1123359D01*
X1476498Y1121962D01*
X1476529Y1121875D01*
G02X1476602Y1121447I-1225J-429D01*
G02X1474006I-1298J0D01*
G02X1475062Y1122722I1298J0D01*
G01X1475152Y1122739D01*
X1475959Y1124136D01*
X1475928Y1124223D01*
G02X1475856Y1124651I1225J426D01*
G37*
G36*
G01X1483256D02*
G02X1485850I1297J0D01*
G02X1484795Y1123376I-1298J0D01*
G01X1484705Y1123359D01*
X1483898Y1121962D01*
X1483929Y1121875D01*
G02X1484002Y1121447I-1225J-429D01*
G02X1481406I-1298J0D01*
G02X1482462Y1122722I1298J0D01*
G01X1482552Y1122739D01*
X1483359Y1124136D01*
X1483328Y1124223D01*
G02X1483256Y1124651I1225J426D01*
G37*
G36*
G01X1490656D02*
G02X1493250I1297J0D01*
G02X1492195Y1123376I-1298J0D01*
G01X1492105Y1123359D01*
X1491298Y1121962D01*
X1491329Y1121875D01*
G02X1491402Y1121447I-1225J-429D01*
G02X1488806I-1298J0D01*
G02X1489862Y1122722I1298J0D01*
G01X1489952Y1122739D01*
X1490759Y1124136D01*
X1490728Y1124223D01*
G02X1490656Y1124651I1225J426D01*
G37*
G36*
G01X1498056D02*
G02X1500650I1297J0D01*
G02X1499595Y1123376I-1298J0D01*
G01X1499505Y1123359D01*
X1498698Y1121962D01*
X1498729Y1121875D01*
G02X1498802Y1121447I-1225J-429D01*
G02X1496206I-1298J0D01*
G02X1497262Y1122722I1298J0D01*
G01X1497352Y1122739D01*
X1498159Y1124136D01*
X1498128Y1124223D01*
G02X1498056Y1124651I1225J426D01*
G37*
G36*
G01X353564Y1127856D02*
G02X356158I1297J0D01*
G02X355103Y1126581I-1298J0D01*
G01X355013Y1126564D01*
X354205Y1125166D01*
X354236Y1125079D01*
G02X354308Y1124651I-1225J-426D01*
G02X351714I-1297J0D01*
G02X352769Y1125926I1298J0D01*
G01X352859Y1125943D01*
X353667Y1127341D01*
X353636Y1127428D01*
G02X353564Y1127856I1225J426D01*
G37*
G36*
G01X360964D02*
G02X363560I1298J0D01*
G02X362504Y1126581I-1298J0D01*
G01X362414Y1126564D01*
X361606Y1125166D01*
X361637Y1125079D01*
G02X361710Y1124651I-1225J-429D01*
G02X359114I-1298J0D01*
G02X360170Y1125926I1298J0D01*
G01X360260Y1125943D01*
X361068Y1127341D01*
X361037Y1127428D01*
G02X360964Y1127856I1225J429D01*
G37*
G36*
G01X368364D02*
G02X370960I1298J0D01*
G02X369904Y1126581I-1298J0D01*
G01X369814Y1126564D01*
X369006Y1125165D01*
X369036Y1125078D01*
G02X369108Y1124653I-1225J-426D01*
G01Y1124651D01*
G02X366514I-1297J0D01*
G02X367570Y1125926I1298J0D01*
G01X367661Y1125943D01*
X368468Y1127341D01*
X368437Y1127428D01*
G02X368364Y1127856I1225J429D01*
G37*
G36*
G01X375764D02*
G02X378360I1298J0D01*
G02X377304Y1126581I-1298J0D01*
G01X377214Y1126564D01*
X376406Y1125165D01*
X376436Y1125078D01*
G02X376508Y1124653I-1225J-426D01*
G01Y1124651D01*
G02X373914I-1297J0D01*
G02X374970Y1125926I1298J0D01*
G01X375061Y1125943D01*
X375868Y1127341D01*
X375837Y1127428D01*
G02X375764Y1127856I1225J429D01*
G37*
G36*
G01X383164D02*
G02X385760I1298J0D01*
G02X384704Y1126581I-1298J0D01*
G01X384614Y1126564D01*
X383806Y1125165D01*
X383836Y1125078D01*
G02X383908Y1124653I-1225J-426D01*
G01Y1124651D01*
G02X381314I-1297J0D01*
G02X382370Y1125926I1298J0D01*
G01X382461Y1125943D01*
X383268Y1127341D01*
X383237Y1127428D01*
G02X383164Y1127856I1225J429D01*
G37*
G36*
G01X390564D02*
G02X393160I1298J0D01*
G02X392104Y1126581I-1298J0D01*
G01X392014Y1126564D01*
X391206Y1125165D01*
X391236Y1125078D01*
G02X391308Y1124653I-1225J-426D01*
G01Y1124651D01*
G02X388714I-1297J0D01*
G02X389770Y1125926I1298J0D01*
G01X389861Y1125943D01*
X390668Y1127341D01*
X390637Y1127428D01*
G02X390564Y1127856I1225J429D01*
G37*
G36*
G01X397964D02*
G02X400560I1298J0D01*
G02X399504Y1126581I-1298J0D01*
G01X399414Y1126564D01*
X398606Y1125165D01*
X398636Y1125078D01*
G02X398708Y1124653I-1225J-426D01*
G01Y1124651D01*
G02X396114I-1297J0D01*
G02X397170Y1125926I1298J0D01*
G01X397261Y1125943D01*
X398068Y1127341D01*
X398037Y1127428D01*
G02X397964Y1127856I1225J429D01*
G37*
G36*
G01X405364D02*
G02X407960I1298J0D01*
G02X406904Y1126581I-1298J0D01*
G01X406814Y1126564D01*
X406006Y1125165D01*
X406036Y1125078D01*
G02X406108Y1124653I-1225J-426D01*
G01Y1124651D01*
G02X403514I-1297J0D01*
G02X404570Y1125926I1298J0D01*
G01X404661Y1125943D01*
X405468Y1127341D01*
X405437Y1127428D01*
G02X405364Y1127856I1225J429D01*
G37*
G36*
G01X471964D02*
G02X474560I1298J0D01*
G02X474487Y1127427I-1297J0D01*
G01X474456Y1127341D01*
X475263Y1125943D01*
X475353Y1125926D01*
G02X476408Y1124651I-243J-1275D01*
G02X473814I-1297J0D01*
G02X473886Y1125080I1297J3D01*
G01X473917Y1125166D01*
X473110Y1126564D01*
X473020Y1126581D01*
G02X471964Y1127856I242J1275D01*
G37*
G36*
G01X479364D02*
G02X481960I1298J0D01*
G02X481887Y1127427I-1297J0D01*
G01X481856Y1127341D01*
X482663Y1125943D01*
X482753Y1125926D01*
G02X483808Y1124651I-243J-1275D01*
G02X481214I-1297J0D01*
G02X481286Y1125080I1297J3D01*
G01X481317Y1125166D01*
X480510Y1126564D01*
X480420Y1126581D01*
G02X479364Y1127856I242J1275D01*
G37*
G36*
G01X486764D02*
G02X489360I1298J0D01*
G02X489287Y1127427I-1297J0D01*
G01X489256Y1127341D01*
X490063Y1125943D01*
X490153Y1125926D01*
G02X491208Y1124651I-243J-1275D01*
G02X488614I-1297J0D01*
G02X488686Y1125080I1297J3D01*
G01X488717Y1125166D01*
X487910Y1126564D01*
X487820Y1126581D01*
G02X486764Y1127856I242J1275D01*
G37*
G36*
G01X494164D02*
G02X496760I1298J0D01*
G02X496687Y1127427I-1297J0D01*
G01X496656Y1127341D01*
X497463Y1125943D01*
X497553Y1125926D01*
G02X498608Y1124651I-243J-1275D01*
G02X496014I-1297J0D01*
G02X496086Y1125080I1297J3D01*
G01X496117Y1125166D01*
X495310Y1126564D01*
X495220Y1126581D01*
G02X494164Y1127856I242J1275D01*
G37*
G36*
G01X501564D02*
G02X504160I1298J0D01*
G02X504087Y1127427I-1297J0D01*
G01X504056Y1127341D01*
X504863Y1125943D01*
X504953Y1125926D01*
G02X506008Y1124651I-243J-1275D01*
G02X503414I-1297J0D01*
G02X503486Y1125080I1297J3D01*
G01X503517Y1125166D01*
X502710Y1126564D01*
X502620Y1126581D01*
G02X501564Y1127856I242J1275D01*
G37*
G36*
G01X508964D02*
G02X511560I1298J0D01*
G02X511487Y1127427I-1297J0D01*
G01X511456Y1127341D01*
X512263Y1125943D01*
X512353Y1125926D01*
G02X513408Y1124651I-243J-1275D01*
G02X510814I-1297J0D01*
G02X510886Y1125080I1297J3D01*
G01X510917Y1125166D01*
X510110Y1126564D01*
X510020Y1126581D01*
G02X508964Y1127856I242J1275D01*
G37*
G36*
G01X516364D02*
G02X518960I1298J0D01*
G02X518887Y1127427I-1297J0D01*
G01X518856Y1127341D01*
X519663Y1125943D01*
X519753Y1125926D01*
G02X520808Y1124651I-243J-1275D01*
G02X518214I-1297J0D01*
G02X518286Y1125080I1297J3D01*
G01X518317Y1125166D01*
X517510Y1126564D01*
X517420Y1126581D01*
G02X516364Y1127856I242J1275D01*
G37*
G36*
G01X523764D02*
G02X526360I1298J0D01*
G02X526287Y1127427I-1297J0D01*
G01X526256Y1127341D01*
X527063Y1125943D01*
X527153Y1125926D01*
G02X528208Y1124651I-243J-1275D01*
G02X525614I-1297J0D01*
G02X525686Y1125080I1297J3D01*
G01X525717Y1125166D01*
X524910Y1126564D01*
X524820Y1126581D01*
G02X523764Y1127856I242J1275D01*
G37*
G36*
G01X1329706D02*
G02X1332300I1297J0D01*
G02X1331245Y1126581I-1298J0D01*
G01X1331155Y1126564D01*
X1330347Y1125166D01*
X1330378Y1125079D01*
G02X1330450Y1124651I-1225J-426D01*
G02X1327856I-1297J0D01*
G02X1328911Y1125926I1298J0D01*
G01X1329001Y1125943D01*
X1329809Y1127341D01*
X1329778Y1127428D01*
G02X1329706Y1127856I1225J426D01*
G37*
G36*
G01X1337106D02*
G02X1339702I1298J0D01*
G02X1338646Y1126581I-1298J0D01*
G01X1338556Y1126564D01*
X1337748Y1125166D01*
X1337779Y1125079D01*
G02X1337852Y1124651I-1225J-429D01*
G02X1335256I-1298J0D01*
G02X1336312Y1125926I1298J0D01*
G01X1336402Y1125943D01*
X1337210Y1127341D01*
X1337179Y1127428D01*
G02X1337106Y1127856I1225J429D01*
G37*
G36*
G01X1344506D02*
G02X1347102I1298J0D01*
G02X1346046Y1126581I-1298J0D01*
G01X1345956Y1126564D01*
X1345148Y1125165D01*
X1345178Y1125078D01*
G02X1345250Y1124653I-1225J-426D01*
G01Y1124651D01*
G02X1342656I-1297J0D01*
G02X1343712Y1125926I1298J0D01*
G01X1343803Y1125943D01*
X1344610Y1127341D01*
X1344579Y1127428D01*
G02X1344506Y1127856I1225J429D01*
G37*
G36*
G01X1351906D02*
G02X1354502I1298J0D01*
G02X1353446Y1126581I-1298J0D01*
G01X1353356Y1126564D01*
X1352548Y1125165D01*
X1352578Y1125078D01*
G02X1352650Y1124653I-1225J-426D01*
G01Y1124651D01*
G02X1350056I-1297J0D01*
G02X1351112Y1125926I1298J0D01*
G01X1351203Y1125943D01*
X1352010Y1127341D01*
X1351979Y1127428D01*
G02X1351906Y1127856I1225J429D01*
G37*
G36*
G01X1359306D02*
G02X1361902I1298J0D01*
G02X1360846Y1126581I-1298J0D01*
G01X1360756Y1126564D01*
X1359948Y1125165D01*
X1359978Y1125078D01*
G02X1360050Y1124653I-1225J-426D01*
G01Y1124651D01*
G02X1357456I-1297J0D01*
G02X1358512Y1125926I1298J0D01*
G01X1358603Y1125943D01*
X1359410Y1127341D01*
X1359379Y1127428D01*
G02X1359306Y1127856I1225J429D01*
G37*
G36*
G01X1366706D02*
G02X1369302I1298J0D01*
G02X1368246Y1126581I-1298J0D01*
G01X1368156Y1126564D01*
X1367348Y1125165D01*
X1367378Y1125078D01*
G02X1367450Y1124653I-1225J-426D01*
G01Y1124651D01*
G02X1364856I-1297J0D01*
G02X1365912Y1125926I1298J0D01*
G01X1366003Y1125943D01*
X1366810Y1127341D01*
X1366779Y1127428D01*
G02X1366706Y1127856I1225J429D01*
G37*
G36*
G01X1374106D02*
G02X1376702I1298J0D01*
G02X1375646Y1126581I-1298J0D01*
G01X1375556Y1126564D01*
X1374748Y1125165D01*
X1374778Y1125078D01*
G02X1374850Y1124653I-1225J-426D01*
G01Y1124651D01*
G02X1372256I-1297J0D01*
G02X1373312Y1125926I1298J0D01*
G01X1373403Y1125943D01*
X1374210Y1127341D01*
X1374179Y1127428D01*
G02X1374106Y1127856I1225J429D01*
G37*
G36*
G01X1381506D02*
G02X1384102I1298J0D01*
G02X1383046Y1126581I-1298J0D01*
G01X1382956Y1126564D01*
X1382148Y1125165D01*
X1382178Y1125078D01*
G02X1382250Y1124653I-1225J-426D01*
G01Y1124651D01*
G02X1379656I-1297J0D01*
G02X1380712Y1125926I1298J0D01*
G01X1380803Y1125943D01*
X1381610Y1127341D01*
X1381579Y1127428D01*
G02X1381506Y1127856I1225J429D01*
G37*
G36*
G01X1448106D02*
G02X1450702I1298J0D01*
G02X1450629Y1127427I-1297J0D01*
G01X1450598Y1127341D01*
X1451405Y1125943D01*
X1451495Y1125926D01*
G02X1452550Y1124651I-243J-1275D01*
G02X1449956I-1297J0D01*
G02X1450028Y1125080I1297J3D01*
G01X1450059Y1125166D01*
X1449252Y1126564D01*
X1449162Y1126581D01*
G02X1448106Y1127856I242J1275D01*
G37*
G36*
G01X1455506D02*
G02X1458102I1298J0D01*
G02X1458029Y1127427I-1297J0D01*
G01X1457998Y1127341D01*
X1458805Y1125943D01*
X1458895Y1125926D01*
G02X1459950Y1124651I-243J-1275D01*
G02X1457356I-1297J0D01*
G02X1457428Y1125080I1297J3D01*
G01X1457459Y1125166D01*
X1456652Y1126564D01*
X1456562Y1126581D01*
G02X1455506Y1127856I242J1275D01*
G37*
G36*
G01X1462906D02*
G02X1465502I1298J0D01*
G02X1465429Y1127427I-1297J0D01*
G01X1465398Y1127341D01*
X1466205Y1125943D01*
X1466295Y1125926D01*
G02X1467350Y1124651I-243J-1275D01*
G02X1464756I-1297J0D01*
G02X1464828Y1125080I1297J3D01*
G01X1464859Y1125166D01*
X1464052Y1126564D01*
X1463962Y1126581D01*
G02X1462906Y1127856I242J1275D01*
G37*
G36*
G01X1470306D02*
G02X1472902I1298J0D01*
G02X1472829Y1127427I-1297J0D01*
G01X1472798Y1127341D01*
X1473605Y1125943D01*
X1473695Y1125926D01*
G02X1474750Y1124651I-243J-1275D01*
G02X1472156I-1297J0D01*
G02X1472228Y1125080I1297J3D01*
G01X1472259Y1125166D01*
X1471452Y1126564D01*
X1471362Y1126581D01*
G02X1470306Y1127856I242J1275D01*
G37*
G36*
G01X1477706D02*
G02X1480302I1298J0D01*
G02X1480229Y1127427I-1297J0D01*
G01X1480198Y1127341D01*
X1481005Y1125943D01*
X1481095Y1125926D01*
G02X1482150Y1124651I-243J-1275D01*
G02X1479556I-1297J0D01*
G02X1479628Y1125080I1297J3D01*
G01X1479659Y1125166D01*
X1478852Y1126564D01*
X1478762Y1126581D01*
G02X1477706Y1127856I242J1275D01*
G37*
G36*
G01X1485106D02*
G02X1487702I1298J0D01*
G02X1487629Y1127427I-1297J0D01*
G01X1487598Y1127341D01*
X1488405Y1125943D01*
X1488495Y1125926D01*
G02X1489550Y1124651I-243J-1275D01*
G02X1486956I-1297J0D01*
G02X1487028Y1125080I1297J3D01*
G01X1487059Y1125166D01*
X1486252Y1126564D01*
X1486162Y1126581D01*
G02X1485106Y1127856I242J1275D01*
G37*
G36*
G01X1492506D02*
G02X1495102I1298J0D01*
G02X1495029Y1127427I-1297J0D01*
G01X1494998Y1127341D01*
X1495805Y1125943D01*
X1495895Y1125926D01*
G02X1496950Y1124651I-243J-1275D01*
G02X1494356I-1297J0D01*
G02X1494428Y1125080I1297J3D01*
G01X1494459Y1125166D01*
X1493652Y1126564D01*
X1493562Y1126581D01*
G02X1492506Y1127856I242J1275D01*
G37*
G36*
G01X1499906D02*
G02X1502502I1298J0D01*
G02X1502429Y1127427I-1297J0D01*
G01X1502398Y1127341D01*
X1503205Y1125943D01*
X1503295Y1125926D01*
G02X1504350Y1124651I-243J-1275D01*
G02X1501756I-1297J0D01*
G02X1501828Y1125080I1297J3D01*
G01X1501859Y1125166D01*
X1501052Y1126564D01*
X1500962Y1126581D01*
G02X1499906Y1127856I242J1275D01*
G37*
G36*
G01X340614Y1131060D02*
G02X343208I1297J0D01*
G02X342153Y1129785I-1298J0D01*
G01X342063Y1129768D01*
X341256Y1128370D01*
X341286Y1128284D01*
G02X341358Y1127856I-1225J-426D01*
G02X338764I-1297J0D01*
G02X339819Y1129131I1298J0D01*
G01X339909Y1129148D01*
X340716Y1130546D01*
X340686Y1130632D01*
G02X340614Y1131060I1225J426D01*
G37*
G36*
G01X1316756D02*
G02X1319350I1297J0D01*
G02X1318295Y1129785I-1298J0D01*
G01X1318205Y1129768D01*
X1317398Y1128370D01*
X1317428Y1128284D01*
G02X1317500Y1127856I-1225J-426D01*
G02X1314906I-1297J0D01*
G02X1315961Y1129131I1298J0D01*
G01X1316051Y1129148D01*
X1316858Y1130546D01*
X1316828Y1130632D01*
G02X1316756Y1131060I1225J426D01*
G37*
G36*
G01X348014Y1137469D02*
G02X350610I1298J0D01*
G02X350537Y1137040I-1297J0D01*
G01X350506Y1136954D01*
X351313Y1135556D01*
X351403Y1135539D01*
G02X352458Y1134264I-243J-1275D01*
G02X349864I-1297J0D01*
G02X349936Y1134693I1297J3D01*
G01X349967Y1134779D01*
X349160Y1136177D01*
X349070Y1136194D01*
G02X348014Y1137469I242J1275D01*
G37*
G36*
G01X355414D02*
G02X358010I1298J0D01*
G02X357937Y1137040I-1297J0D01*
G01X357906Y1136954D01*
X358713Y1135556D01*
X358803Y1135539D01*
G02X359858Y1134264I-243J-1275D01*
G02X357264I-1297J0D01*
G02X357336Y1134693I1297J3D01*
G01X357367Y1134779D01*
X356560Y1136177D01*
X356470Y1136194D01*
G02X355414Y1137469I242J1275D01*
G37*
G36*
G01X362814D02*
G02X365410I1298J0D01*
G02X365337Y1137041I-1298J1D01*
G01X365306Y1136954D01*
X366114Y1135556D01*
X366204Y1135539D01*
G02X367260Y1134264I-242J-1275D01*
G02X364664I-1298J0D01*
G02X364737Y1134692I1298J-1D01*
G01X364768Y1134779D01*
X363960Y1136177D01*
X363870Y1136194D01*
G02X362814Y1137469I242J1275D01*
G37*
G36*
G01X370214D02*
G02X372810I1298J0D01*
G02X372737Y1137041I-1298J1D01*
G01X372706Y1136954D01*
X373514Y1135556D01*
X373604Y1135539D01*
G02X374660Y1134264I-242J-1275D01*
G02X372064I-1298J0D01*
G02X372137Y1134692I1298J-1D01*
G01X372168Y1134779D01*
X371360Y1136177D01*
X371270Y1136194D01*
G02X370214Y1137469I242J1275D01*
G37*
G36*
G01X377614D02*
G02X380210I1298J0D01*
G02X380137Y1137041I-1298J1D01*
G01X380106Y1136954D01*
X380914Y1135556D01*
X381004Y1135539D01*
G02X382060Y1134264I-242J-1275D01*
G02X379464I-1298J0D01*
G02X379537Y1134692I1298J-1D01*
G01X379568Y1134779D01*
X378760Y1136177D01*
X378670Y1136194D01*
G02X377614Y1137469I242J1275D01*
G37*
G36*
G01X385014D02*
G02X387610I1298J0D01*
G02X387537Y1137041I-1298J1D01*
G01X387506Y1136954D01*
X388314Y1135556D01*
X388404Y1135539D01*
G02X389460Y1134264I-242J-1275D01*
G02X386864I-1298J0D01*
G02X386937Y1134692I1298J-1D01*
G01X386968Y1134779D01*
X386160Y1136177D01*
X386070Y1136194D01*
G02X385014Y1137469I242J1275D01*
G37*
G36*
G01X392414D02*
G02X395010I1298J0D01*
G02X394937Y1137041I-1298J1D01*
G01X394906Y1136954D01*
X395714Y1135556D01*
X395804Y1135539D01*
G02X396860Y1134264I-242J-1275D01*
G02X394264I-1298J0D01*
G02X394337Y1134692I1298J-1D01*
G01X394368Y1134779D01*
X393560Y1136177D01*
X393470Y1136194D01*
G02X392414Y1137469I242J1275D01*
G37*
G36*
G01X399814D02*
G02X402410I1298J0D01*
G02X402337Y1137041I-1298J1D01*
G01X402306Y1136954D01*
X403114Y1135556D01*
X403204Y1135539D01*
G02X404260Y1134264I-242J-1275D01*
G02X401664I-1298J0D01*
G02X401737Y1134692I1298J-1D01*
G01X401768Y1134779D01*
X400960Y1136177D01*
X400870Y1136194D01*
G02X399814Y1137469I242J1275D01*
G37*
G36*
G01X407214D02*
G02X409810I1298J0D01*
G02X409737Y1137041I-1298J1D01*
G01X409706Y1136954D01*
X410514Y1135556D01*
X410604Y1135539D01*
G02X411660Y1134264I-242J-1275D01*
G02X409064I-1298J0D01*
G02X409137Y1134692I1298J-1D01*
G01X409168Y1134779D01*
X408360Y1136177D01*
X408270Y1136194D01*
G02X407214Y1137469I242J1275D01*
G37*
G36*
G01X477514D02*
G02X480110I1298J0D01*
G02X479054Y1136194I-1298J0D01*
G01X478964Y1136177D01*
X478156Y1134779D01*
X478187Y1134692D01*
G02X478260Y1134264I-1225J-429D01*
G02X475664I-1298J0D01*
G02X476720Y1135539I1298J0D01*
G01X476810Y1135556D01*
X477618Y1136954D01*
X477587Y1137041D01*
G02X477514Y1137469I1225J429D01*
G37*
G36*
G01X484914D02*
G02X487510I1298J0D01*
G02X486454Y1136194I-1298J0D01*
G01X486364Y1136177D01*
X485557Y1134779D01*
X485587Y1134692D01*
G02X485660Y1134264I-1225J-429D01*
G02X483064I-1298J0D01*
G02X484121Y1135539I1297J0D01*
G01X484211Y1135556D01*
X485018Y1136954D01*
X484987Y1137041D01*
G02X484914Y1137469I1225J429D01*
G37*
G36*
G01X492314D02*
G02X494910I1298J0D01*
G02X493854Y1136194I-1298J0D01*
G01X493764Y1136177D01*
X492957Y1134779D01*
X492987Y1134692D01*
G02X493060Y1134264I-1225J-429D01*
G02X490464I-1298J0D01*
G02X491521Y1135539I1297J0D01*
G01X491611Y1135556D01*
X492418Y1136954D01*
X492387Y1137041D01*
G02X492314Y1137469I1225J429D01*
G37*
G36*
G01X499714D02*
G02X502310I1298J0D01*
G02X501254Y1136194I-1298J0D01*
G01X501164Y1136177D01*
X500357Y1134779D01*
X500387Y1134692D01*
G02X500460Y1134264I-1225J-429D01*
G02X497864I-1298J0D01*
G02X498921Y1135539I1297J0D01*
G01X499011Y1135556D01*
X499818Y1136954D01*
X499787Y1137041D01*
G02X499714Y1137469I1225J429D01*
G37*
G36*
G01X507114D02*
G02X509710I1298J0D01*
G02X508654Y1136194I-1298J0D01*
G01X508564Y1136177D01*
X507757Y1134779D01*
X507787Y1134692D01*
G02X507860Y1134264I-1225J-429D01*
G02X505264I-1298J0D01*
G02X506321Y1135539I1297J0D01*
G01X506411Y1135556D01*
X507218Y1136954D01*
X507187Y1137041D01*
G02X507114Y1137469I1225J429D01*
G37*
G36*
G01X514514D02*
G02X517110I1298J0D01*
G02X516054Y1136194I-1298J0D01*
G01X515964Y1136177D01*
X515157Y1134779D01*
X515187Y1134692D01*
G02X515260Y1134264I-1225J-429D01*
G02X512664I-1298J0D01*
G02X513721Y1135539I1297J0D01*
G01X513811Y1135556D01*
X514618Y1136954D01*
X514587Y1137041D01*
G02X514514Y1137469I1225J429D01*
G37*
G36*
G01X521914D02*
G02X524510I1298J0D01*
G02X523454Y1136194I-1298J0D01*
G01X523364Y1136177D01*
X522557Y1134779D01*
X522587Y1134692D01*
G02X522660Y1134264I-1225J-429D01*
G02X520064I-1298J0D01*
G02X521121Y1135539I1297J0D01*
G01X521211Y1135556D01*
X522018Y1136954D01*
X521987Y1137041D01*
G02X521914Y1137469I1225J429D01*
G37*
G36*
G01X533014D02*
G02X535610I1298J0D01*
G02X534554Y1136194I-1298J0D01*
G01X534464Y1136177D01*
X533656Y1134779D01*
X533687Y1134692D01*
G02X533760Y1134264I-1225J-429D01*
G02X531164I-1298J0D01*
G02X532220Y1135539I1298J0D01*
G01X532310Y1135556D01*
X533118Y1136954D01*
X533087Y1137041D01*
G02X533014Y1137469I1225J429D01*
G37*
G36*
G01X1324156D02*
G02X1326752I1298J0D01*
G02X1326679Y1137040I-1297J0D01*
G01X1326648Y1136954D01*
X1327455Y1135556D01*
X1327545Y1135539D01*
G02X1328600Y1134264I-243J-1275D01*
G02X1326006I-1297J0D01*
G02X1326078Y1134693I1297J3D01*
G01X1326109Y1134779D01*
X1325302Y1136177D01*
X1325212Y1136194D01*
G02X1324156Y1137469I242J1275D01*
G37*
G36*
G01X1331556D02*
G02X1334152I1298J0D01*
G02X1334079Y1137040I-1297J0D01*
G01X1334048Y1136954D01*
X1334855Y1135556D01*
X1334945Y1135539D01*
G02X1336000Y1134264I-243J-1275D01*
G02X1333406I-1297J0D01*
G02X1333478Y1134693I1297J3D01*
G01X1333509Y1134779D01*
X1332702Y1136177D01*
X1332612Y1136194D01*
G02X1331556Y1137469I242J1275D01*
G37*
G36*
G01X1338956D02*
G02X1341552I1298J0D01*
G02X1341479Y1137041I-1298J1D01*
G01X1341448Y1136954D01*
X1342256Y1135556D01*
X1342346Y1135539D01*
G02X1343402Y1134264I-242J-1275D01*
G02X1340806I-1298J0D01*
G02X1340879Y1134692I1298J-1D01*
G01X1340910Y1134779D01*
X1340102Y1136177D01*
X1340012Y1136194D01*
G02X1338956Y1137469I242J1275D01*
G37*
G36*
G01X1346356D02*
G02X1348952I1298J0D01*
G02X1348879Y1137041I-1298J1D01*
G01X1348848Y1136954D01*
X1349656Y1135556D01*
X1349746Y1135539D01*
G02X1350802Y1134264I-242J-1275D01*
G02X1348206I-1298J0D01*
G02X1348279Y1134692I1298J-1D01*
G01X1348310Y1134779D01*
X1347502Y1136177D01*
X1347412Y1136194D01*
G02X1346356Y1137469I242J1275D01*
G37*
G36*
G01X1353756D02*
G02X1356352I1298J0D01*
G02X1356279Y1137041I-1298J1D01*
G01X1356248Y1136954D01*
X1357056Y1135556D01*
X1357146Y1135539D01*
G02X1358202Y1134264I-242J-1275D01*
G02X1355606I-1298J0D01*
G02X1355679Y1134692I1298J-1D01*
G01X1355710Y1134779D01*
X1354902Y1136177D01*
X1354812Y1136194D01*
G02X1353756Y1137469I242J1275D01*
G37*
G36*
G01X1361156D02*
G02X1363752I1298J0D01*
G02X1363679Y1137041I-1298J1D01*
G01X1363648Y1136954D01*
X1364456Y1135556D01*
X1364546Y1135539D01*
G02X1365602Y1134264I-242J-1275D01*
G02X1363006I-1298J0D01*
G02X1363079Y1134692I1298J-1D01*
G01X1363110Y1134779D01*
X1362302Y1136177D01*
X1362212Y1136194D01*
G02X1361156Y1137469I242J1275D01*
G37*
G36*
G01X1368556D02*
G02X1371152I1298J0D01*
G02X1371079Y1137041I-1298J1D01*
G01X1371048Y1136954D01*
X1371856Y1135556D01*
X1371946Y1135539D01*
G02X1373002Y1134264I-242J-1275D01*
G02X1370406I-1298J0D01*
G02X1370479Y1134692I1298J-1D01*
G01X1370510Y1134779D01*
X1369702Y1136177D01*
X1369612Y1136194D01*
G02X1368556Y1137469I242J1275D01*
G37*
G36*
G01X1375956D02*
G02X1378552I1298J0D01*
G02X1378479Y1137041I-1298J1D01*
G01X1378448Y1136954D01*
X1379256Y1135556D01*
X1379346Y1135539D01*
G02X1380402Y1134264I-242J-1275D01*
G02X1377806I-1298J0D01*
G02X1377879Y1134692I1298J-1D01*
G01X1377910Y1134779D01*
X1377102Y1136177D01*
X1377012Y1136194D01*
G02X1375956Y1137469I242J1275D01*
G37*
G36*
G01X1383356D02*
G02X1385952I1298J0D01*
G02X1385879Y1137041I-1298J1D01*
G01X1385848Y1136954D01*
X1386656Y1135556D01*
X1386746Y1135539D01*
G02X1387802Y1134264I-242J-1275D01*
G02X1385206I-1298J0D01*
G02X1385279Y1134692I1298J-1D01*
G01X1385310Y1134779D01*
X1384502Y1136177D01*
X1384412Y1136194D01*
G02X1383356Y1137469I242J1275D01*
G37*
G36*
G01X1453656D02*
G02X1456252I1298J0D01*
G02X1455196Y1136194I-1298J0D01*
G01X1455106Y1136177D01*
X1454298Y1134779D01*
X1454329Y1134692D01*
G02X1454402Y1134264I-1225J-429D01*
G02X1451806I-1298J0D01*
G02X1452862Y1135539I1298J0D01*
G01X1452952Y1135556D01*
X1453760Y1136954D01*
X1453729Y1137041D01*
G02X1453656Y1137469I1225J429D01*
G37*
G36*
G01X1461056D02*
G02X1463652I1298J0D01*
G02X1462596Y1136194I-1298J0D01*
G01X1462506Y1136177D01*
X1461699Y1134779D01*
X1461729Y1134692D01*
G02X1461802Y1134264I-1225J-429D01*
G02X1459206I-1298J0D01*
G02X1460263Y1135539I1297J0D01*
G01X1460353Y1135556D01*
X1461160Y1136954D01*
X1461129Y1137041D01*
G02X1461056Y1137469I1225J429D01*
G37*
G36*
G01X1468456D02*
G02X1471052I1298J0D01*
G02X1469996Y1136194I-1298J0D01*
G01X1469906Y1136177D01*
X1469099Y1134779D01*
X1469129Y1134692D01*
G02X1469202Y1134264I-1225J-429D01*
G02X1466606I-1298J0D01*
G02X1467663Y1135539I1297J0D01*
G01X1467753Y1135556D01*
X1468560Y1136954D01*
X1468529Y1137041D01*
G02X1468456Y1137469I1225J429D01*
G37*
G36*
G01X1475856D02*
G02X1478452I1298J0D01*
G02X1477396Y1136194I-1298J0D01*
G01X1477306Y1136177D01*
X1476499Y1134779D01*
X1476529Y1134692D01*
G02X1476602Y1134264I-1225J-429D01*
G02X1474006I-1298J0D01*
G02X1475063Y1135539I1297J0D01*
G01X1475153Y1135556D01*
X1475960Y1136954D01*
X1475929Y1137041D01*
G02X1475856Y1137469I1225J429D01*
G37*
G36*
G01X1483256D02*
G02X1485852I1298J0D01*
G02X1484796Y1136194I-1298J0D01*
G01X1484706Y1136177D01*
X1483899Y1134779D01*
X1483929Y1134692D01*
G02X1484002Y1134264I-1225J-429D01*
G02X1481406I-1298J0D01*
G02X1482463Y1135539I1297J0D01*
G01X1482553Y1135556D01*
X1483360Y1136954D01*
X1483329Y1137041D01*
G02X1483256Y1137469I1225J429D01*
G37*
G36*
G01X1490656D02*
G02X1493252I1298J0D01*
G02X1492196Y1136194I-1298J0D01*
G01X1492106Y1136177D01*
X1491299Y1134779D01*
X1491329Y1134692D01*
G02X1491402Y1134264I-1225J-429D01*
G02X1488806I-1298J0D01*
G02X1489863Y1135539I1297J0D01*
G01X1489953Y1135556D01*
X1490760Y1136954D01*
X1490729Y1137041D01*
G02X1490656Y1137469I1225J429D01*
G37*
G36*
G01X1498056D02*
G02X1500652I1298J0D01*
G02X1499596Y1136194I-1298J0D01*
G01X1499506Y1136177D01*
X1498699Y1134779D01*
X1498729Y1134692D01*
G02X1498802Y1134264I-1225J-429D01*
G02X1496206I-1298J0D01*
G02X1497263Y1135539I1297J0D01*
G01X1497353Y1135556D01*
X1498160Y1136954D01*
X1498129Y1137041D01*
G02X1498056Y1137469I1225J429D01*
G37*
G36*
G01X1509156D02*
G02X1511752I1298J0D01*
G02X1510696Y1136194I-1298J0D01*
G01X1510606Y1136177D01*
X1509798Y1134779D01*
X1509829Y1134692D01*
G02X1509902Y1134264I-1225J-429D01*
G02X1507306I-1298J0D01*
G02X1508362Y1135539I1298J0D01*
G01X1508452Y1135556D01*
X1509260Y1136954D01*
X1509229Y1137041D01*
G02X1509156Y1137469I1225J429D01*
G37*
G36*
G01X360964Y1140973D02*
G02X363558I1297J0D01*
G02X362496Y1139697I-1298J0D01*
G01X362401Y1139679D01*
X361559Y1138084D01*
X361598Y1137995D01*
G02X361710Y1137469I-1186J-527D01*
G02X359114I-1298J0D01*
G02X360177Y1138745I1297J0D01*
G01X360272Y1138763D01*
X361114Y1140358D01*
X361075Y1140447D01*
G02X360964Y1140971I1186J525D01*
G01Y1140973D01*
G37*
G36*
G01X368364D02*
G02X370958I1297J0D01*
G02X369896Y1139697I-1298J0D01*
G01X369801Y1139679D01*
X368959Y1138084D01*
X368998Y1137995D01*
G02X369110Y1137469I-1186J-527D01*
G02X366514I-1298J0D01*
G02X367577Y1138745I1297J0D01*
G01X367672Y1138763D01*
X368514Y1140358D01*
X368475Y1140447D01*
G02X368364Y1140971I1186J525D01*
G01Y1140973D01*
G37*
G36*
G01X375764D02*
G02X378358I1297J0D01*
G02X377296Y1139697I-1298J0D01*
G01X377201Y1139679D01*
X376359Y1138084D01*
X376398Y1137995D01*
G02X376510Y1137469I-1186J-527D01*
G02X373914I-1298J0D01*
G02X374977Y1138745I1297J0D01*
G01X375072Y1138763D01*
X375914Y1140358D01*
X375875Y1140447D01*
G02X375764Y1140971I1186J525D01*
G01Y1140973D01*
G37*
G36*
G01X383164D02*
G02X385758I1297J0D01*
G02X384696Y1139697I-1298J0D01*
G01X384601Y1139679D01*
X383759Y1138084D01*
X383798Y1137995D01*
G02X383910Y1137469I-1186J-527D01*
G02X381314I-1298J0D01*
G02X382377Y1138745I1297J0D01*
G01X382472Y1138763D01*
X383314Y1140358D01*
X383275Y1140447D01*
G02X383164Y1140971I1186J525D01*
G01Y1140973D01*
G37*
G36*
G01X390564D02*
G02X393158I1297J0D01*
G02X392096Y1139697I-1298J0D01*
G01X392001Y1139679D01*
X391159Y1138084D01*
X391198Y1137995D01*
G02X391310Y1137469I-1186J-527D01*
G02X388714I-1298J0D01*
G02X389777Y1138745I1297J0D01*
G01X389872Y1138763D01*
X390714Y1140358D01*
X390675Y1140447D01*
G02X390564Y1140971I1186J525D01*
G01Y1140973D01*
G37*
G36*
G01X397964D02*
G02X400558I1297J0D01*
G02X399496Y1139697I-1298J0D01*
G01X399401Y1139679D01*
X398559Y1138084D01*
X398598Y1137995D01*
G02X398710Y1137469I-1186J-527D01*
G02X396114I-1298J0D01*
G02X397177Y1138745I1297J0D01*
G01X397272Y1138763D01*
X398114Y1140358D01*
X398075Y1140447D01*
G02X397964Y1140971I1186J525D01*
G01Y1140973D01*
G37*
G36*
G01X405364D02*
G02X407958I1297J0D01*
G02X406896Y1139697I-1298J0D01*
G01X406801Y1139679D01*
X405959Y1138084D01*
X405998Y1137995D01*
G02X406110Y1137469I-1186J-527D01*
G02X403514I-1298J0D01*
G02X404577Y1138745I1297J0D01*
G01X404672Y1138763D01*
X405514Y1140358D01*
X405475Y1140447D01*
G02X405364Y1140971I1186J525D01*
G01Y1140973D01*
G37*
G36*
G01X471964D02*
G02X474558I1297J0D01*
G02X474447Y1140448I-1297J0D01*
G01X474408Y1140359D01*
X475252Y1138763D01*
X475347Y1138745D01*
G02X476410Y1137469I-234J-1276D01*
G02X473814I-1298J0D01*
G02X473926Y1137994I1297J-2D01*
G01X473965Y1138083D01*
X473121Y1139679D01*
X473026Y1139697D01*
G02X471964Y1140973I236J1276D01*
G37*
G36*
G01X479364D02*
G02X481958I1297J0D01*
G02X481847Y1140448I-1297J0D01*
G01X481808Y1140359D01*
X482652Y1138763D01*
X482747Y1138745D01*
G02X483810Y1137469I-234J-1276D01*
G02X481214I-1298J0D01*
G02X481326Y1137994I1297J-2D01*
G01X481365Y1138083D01*
X480521Y1139679D01*
X480426Y1139697D01*
G02X479364Y1140973I236J1276D01*
G37*
G36*
G01X486764D02*
G02X489358I1297J0D01*
G02X489247Y1140448I-1297J0D01*
G01X489208Y1140359D01*
X490052Y1138763D01*
X490147Y1138745D01*
G02X491210Y1137469I-234J-1276D01*
G02X488614I-1298J0D01*
G02X488726Y1137994I1297J-2D01*
G01X488765Y1138083D01*
X487921Y1139679D01*
X487826Y1139697D01*
G02X486764Y1140973I236J1276D01*
G37*
G36*
G01X494164D02*
G02X496758I1297J0D01*
G02X496647Y1140448I-1297J0D01*
G01X496608Y1140359D01*
X497452Y1138763D01*
X497547Y1138745D01*
G02X498610Y1137469I-234J-1276D01*
G02X496014I-1298J0D01*
G02X496126Y1137994I1297J-2D01*
G01X496165Y1138083D01*
X495321Y1139679D01*
X495226Y1139697D01*
G02X494164Y1140973I236J1276D01*
G37*
G36*
G01X501564D02*
G02X504158I1297J0D01*
G02X504047Y1140448I-1297J0D01*
G01X504008Y1140359D01*
X504852Y1138763D01*
X504947Y1138745D01*
G02X506010Y1137469I-234J-1276D01*
G02X503414I-1298J0D01*
G02X503526Y1137994I1297J-2D01*
G01X503565Y1138083D01*
X502721Y1139679D01*
X502626Y1139697D01*
G02X501564Y1140973I236J1276D01*
G37*
G36*
G01X508964D02*
G02X511558I1297J0D01*
G02X511447Y1140448I-1297J0D01*
G01X511408Y1140359D01*
X512252Y1138763D01*
X512347Y1138745D01*
G02X513410Y1137469I-234J-1276D01*
G02X510814I-1298J0D01*
G02X510926Y1137994I1297J-2D01*
G01X510965Y1138083D01*
X510121Y1139679D01*
X510026Y1139697D01*
G02X508964Y1140973I236J1276D01*
G37*
G36*
G01X516364D02*
G02X518958I1297J0D01*
G02X518847Y1140448I-1297J0D01*
G01X518808Y1140359D01*
X519652Y1138763D01*
X519747Y1138745D01*
G02X520810Y1137469I-234J-1276D01*
G02X518214I-1298J0D01*
G02X518326Y1137994I1297J-2D01*
G01X518365Y1138083D01*
X517521Y1139679D01*
X517426Y1139697D01*
G02X516364Y1140973I236J1276D01*
G37*
G36*
G01X523764D02*
G02X526358I1297J0D01*
G02X526247Y1140448I-1297J0D01*
G01X526208Y1140359D01*
X527052Y1138763D01*
X527147Y1138745D01*
G02X528210Y1137469I-234J-1276D01*
G02X525614I-1298J0D01*
G02X525726Y1137994I1297J-2D01*
G01X525765Y1138083D01*
X524921Y1139679D01*
X524826Y1139697D01*
G02X523764Y1140973I236J1276D01*
G37*
G36*
G01X1337106D02*
G02X1339700I1297J0D01*
G02X1338638Y1139697I-1298J0D01*
G01X1338543Y1139679D01*
X1337701Y1138084D01*
X1337740Y1137995D01*
G02X1337852Y1137469I-1186J-527D01*
G02X1335256I-1298J0D01*
G02X1336319Y1138745I1297J0D01*
G01X1336414Y1138763D01*
X1337256Y1140358D01*
X1337217Y1140447D01*
G02X1337106Y1140971I1186J525D01*
G01Y1140973D01*
G37*
G36*
G01X1344506D02*
G02X1347100I1297J0D01*
G02X1346038Y1139697I-1298J0D01*
G01X1345943Y1139679D01*
X1345101Y1138084D01*
X1345140Y1137995D01*
G02X1345252Y1137469I-1186J-527D01*
G02X1342656I-1298J0D01*
G02X1343719Y1138745I1297J0D01*
G01X1343814Y1138763D01*
X1344656Y1140358D01*
X1344617Y1140447D01*
G02X1344506Y1140971I1186J525D01*
G01Y1140973D01*
G37*
G36*
G01X1351906D02*
G02X1354500I1297J0D01*
G02X1353438Y1139697I-1298J0D01*
G01X1353343Y1139679D01*
X1352501Y1138084D01*
X1352540Y1137995D01*
G02X1352652Y1137469I-1186J-527D01*
G02X1350056I-1298J0D01*
G02X1351119Y1138745I1297J0D01*
G01X1351214Y1138763D01*
X1352056Y1140358D01*
X1352017Y1140447D01*
G02X1351906Y1140971I1186J525D01*
G01Y1140973D01*
G37*
G36*
G01X1359306D02*
G02X1361900I1297J0D01*
G02X1360838Y1139697I-1298J0D01*
G01X1360743Y1139679D01*
X1359901Y1138084D01*
X1359940Y1137995D01*
G02X1360052Y1137469I-1186J-527D01*
G02X1357456I-1298J0D01*
G02X1358519Y1138745I1297J0D01*
G01X1358614Y1138763D01*
X1359456Y1140358D01*
X1359417Y1140447D01*
G02X1359306Y1140971I1186J525D01*
G01Y1140973D01*
G37*
G36*
G01X1366706D02*
G02X1369300I1297J0D01*
G02X1368238Y1139697I-1298J0D01*
G01X1368143Y1139679D01*
X1367301Y1138084D01*
X1367340Y1137995D01*
G02X1367452Y1137469I-1186J-527D01*
G02X1364856I-1298J0D01*
G02X1365919Y1138745I1297J0D01*
G01X1366014Y1138763D01*
X1366856Y1140358D01*
X1366817Y1140447D01*
G02X1366706Y1140971I1186J525D01*
G01Y1140973D01*
G37*
G36*
G01X1374106D02*
G02X1376700I1297J0D01*
G02X1375638Y1139697I-1298J0D01*
G01X1375543Y1139679D01*
X1374701Y1138084D01*
X1374740Y1137995D01*
G02X1374852Y1137469I-1186J-527D01*
G02X1372256I-1298J0D01*
G02X1373319Y1138745I1297J0D01*
G01X1373414Y1138763D01*
X1374256Y1140358D01*
X1374217Y1140447D01*
G02X1374106Y1140971I1186J525D01*
G01Y1140973D01*
G37*
G36*
G01X1381506D02*
G02X1384100I1297J0D01*
G02X1383038Y1139697I-1298J0D01*
G01X1382943Y1139679D01*
X1382101Y1138084D01*
X1382140Y1137995D01*
G02X1382252Y1137469I-1186J-527D01*
G02X1379656I-1298J0D01*
G02X1380719Y1138745I1297J0D01*
G01X1380814Y1138763D01*
X1381656Y1140358D01*
X1381617Y1140447D01*
G02X1381506Y1140971I1186J525D01*
G01Y1140973D01*
G37*
G36*
G01X1448106D02*
G02X1450700I1297J0D01*
G02X1450589Y1140448I-1297J0D01*
G01X1450550Y1140359D01*
X1451394Y1138763D01*
X1451489Y1138745D01*
G02X1452552Y1137469I-234J-1276D01*
G02X1449956I-1298J0D01*
G02X1450068Y1137994I1297J-2D01*
G01X1450107Y1138083D01*
X1449263Y1139679D01*
X1449168Y1139697D01*
G02X1448106Y1140973I236J1276D01*
G37*
G36*
G01X1455506D02*
G02X1458100I1297J0D01*
G02X1457989Y1140448I-1297J0D01*
G01X1457950Y1140359D01*
X1458794Y1138763D01*
X1458889Y1138745D01*
G02X1459952Y1137469I-234J-1276D01*
G02X1457356I-1298J0D01*
G02X1457468Y1137994I1297J-2D01*
G01X1457507Y1138083D01*
X1456663Y1139679D01*
X1456568Y1139697D01*
G02X1455506Y1140973I236J1276D01*
G37*
G36*
G01X1462906D02*
G02X1465500I1297J0D01*
G02X1465389Y1140448I-1297J0D01*
G01X1465350Y1140359D01*
X1466194Y1138763D01*
X1466289Y1138745D01*
G02X1467352Y1137469I-234J-1276D01*
G02X1464756I-1298J0D01*
G02X1464868Y1137994I1297J-2D01*
G01X1464907Y1138083D01*
X1464063Y1139679D01*
X1463968Y1139697D01*
G02X1462906Y1140973I236J1276D01*
G37*
G36*
G01X1470306D02*
G02X1472900I1297J0D01*
G02X1472789Y1140448I-1297J0D01*
G01X1472750Y1140359D01*
X1473594Y1138763D01*
X1473689Y1138745D01*
G02X1474752Y1137469I-234J-1276D01*
G02X1472156I-1298J0D01*
G02X1472268Y1137994I1297J-2D01*
G01X1472307Y1138083D01*
X1471463Y1139679D01*
X1471368Y1139697D01*
G02X1470306Y1140973I236J1276D01*
G37*
G36*
G01X1477706D02*
G02X1480300I1297J0D01*
G02X1480189Y1140448I-1297J0D01*
G01X1480150Y1140359D01*
X1480994Y1138763D01*
X1481089Y1138745D01*
G02X1482152Y1137469I-234J-1276D01*
G02X1479556I-1298J0D01*
G02X1479668Y1137994I1297J-2D01*
G01X1479707Y1138083D01*
X1478863Y1139679D01*
X1478768Y1139697D01*
G02X1477706Y1140973I236J1276D01*
G37*
G36*
G01X1485106D02*
G02X1487700I1297J0D01*
G02X1487589Y1140448I-1297J0D01*
G01X1487550Y1140359D01*
X1488394Y1138763D01*
X1488489Y1138745D01*
G02X1489552Y1137469I-234J-1276D01*
G02X1486956I-1298J0D01*
G02X1487068Y1137994I1297J-2D01*
G01X1487107Y1138083D01*
X1486263Y1139679D01*
X1486168Y1139697D01*
G02X1485106Y1140973I236J1276D01*
G37*
G36*
G01X1492506D02*
G02X1495100I1297J0D01*
G02X1494989Y1140448I-1297J0D01*
G01X1494950Y1140359D01*
X1495794Y1138763D01*
X1495889Y1138745D01*
G02X1496952Y1137469I-234J-1276D01*
G02X1494356I-1298J0D01*
G02X1494468Y1137994I1297J-2D01*
G01X1494507Y1138083D01*
X1493663Y1139679D01*
X1493568Y1139697D01*
G02X1492506Y1140973I236J1276D01*
G37*
G36*
G01X1499906D02*
G02X1502500I1297J0D01*
G02X1502389Y1140448I-1297J0D01*
G01X1502350Y1140359D01*
X1503194Y1138763D01*
X1503289Y1138745D01*
G02X1504352Y1137469I-234J-1276D01*
G02X1501756I-1298J0D01*
G02X1501868Y1137994I1297J-2D01*
G01X1501907Y1138083D01*
X1501063Y1139679D01*
X1500968Y1139697D01*
G02X1499906Y1140973I236J1276D01*
G37*
G36*
G01X1143020Y1540382D02*
G03X1143411Y1540758I-8J400D01*
G02X1145410Y1542642I1999J-119D01*
G02X1147412Y1540640I0J-2002D01*
G02X1145450Y1538638I-2002J0D01*
G03X1145059Y1538262I8J-400D01*
G02X1143060Y1536378I-1999J119D01*
G02X1141058Y1538380I0J2002D01*
G02X1143020Y1540382I2002J0D01*
G37*
G36*
G01X1162980Y1551449D02*
G03X1163635I328J229D01*
G02X1166917I1641J-1147D01*
G03X1167572I327J229D01*
G02X1169213Y1552304I1641J-1147D01*
G02Y1548298I0J-2003D01*
G02X1167572Y1549153I0J2002D01*
G03X1166917I-328J-229D01*
G02X1163635I-1641J1147D01*
G03X1162980I-327J-229D01*
G02X1159698I-1641J1147D01*
G03X1159043I-328J-229D01*
G02X1155761I-1641J1147D01*
G03X1155106I-328J-229D01*
G02X1151824I-1641J1147D01*
G03X1151169I-328J-229D01*
G02X1149528Y1548298I-1641J1147D01*
G02Y1552304I0J2003D01*
G02X1151169Y1551449I0J-2002D01*
G03X1151824I327J229D01*
G02X1155106I1641J-1147D01*
G03X1155761I328J229D01*
G02X1159043I1641J-1147D01*
G03X1159698I327J229D01*
G02X1162980I1641J-1147D01*
G37*
G36*
G01X1139652Y1550301D02*
Y1550302D01*
G02X1140157Y1551631I2002J0D01*
G02X1139688Y1552918I1533J1288D01*
G01Y1552920D01*
G02X1143692I2002J0D01*
G01Y1552919D01*
G02X1143187Y1551590I-2002J0D01*
G02X1143656Y1550303I-1533J-1288D01*
G01Y1550301D01*
G02X1139652I-2002J0D01*
G37*
G36*
G01X1101405Y1550386D02*
G03X1101083Y1550900I-382J119D01*
G02X1098098Y1554364I517J3464D01*
G02X1105102I3502J0D01*
G02X1104945Y1553324I-3502J-3D01*
G03X1105267Y1552810I382J-119D01*
G02X1108252Y1549346I-517J-3464D01*
G02X1101248I-3502J0D01*
G02X1101405Y1550386I3502J3D01*
G37*
G36*
G01X1143823Y1573272D02*
G03X1143551I-136J-147D01*
G02X1142188Y1572736I-1363J1466D01*
G01X1142187D01*
G02Y1576740I0J2002D01*
G01X1142188D01*
G02X1143551Y1576204I0J-2002D01*
G03X1143823I136J147D01*
G02X1145186Y1576740I1363J-1466D01*
G01X1145187D01*
G02Y1572736I0J-2002D01*
G01X1145186D01*
G02X1143823Y1573272I0J2002D01*
G37*
G36*
G01X1153823D02*
G03X1153551I-136J-147D01*
G02X1152188Y1572736I-1363J1466D01*
G01X1152187D01*
G02Y1576740I0J2002D01*
G01X1152188D01*
G02X1153551Y1576204I0J-2002D01*
G03X1153823I136J147D01*
G02X1155186Y1576740I1363J-1466D01*
G01X1155187D01*
G02Y1572736I0J-2002D01*
G01X1155186D01*
G02X1153823Y1573272I0J2002D01*
G37*
G36*
G01X1163231D02*
G03X1162959I-136J-147D01*
G02X1161596Y1572736I-1363J1466D01*
G01X1161595D01*
G02Y1576740I0J2002D01*
G01X1161596D01*
G02X1162959Y1576204I0J-2002D01*
G03X1163231I136J147D01*
G02X1164594Y1576740I1363J-1466D01*
G01X1164595D01*
G02Y1572736I0J-2002D01*
G01X1164594D01*
G02X1163231Y1573272I0J2002D01*
G37*
G36*
G01X1173231D02*
G03X1172959I-136J-147D01*
G02X1171596Y1572736I-1363J1466D01*
G01X1171595D01*
G02Y1576740I0J2002D01*
G01X1171596D01*
G02X1172959Y1576204I0J-2002D01*
G03X1173231I136J147D01*
G02X1174594Y1576740I1363J-1466D01*
G01X1174595D01*
G02Y1572736I0J-2002D01*
G01X1174594D01*
G02X1173231Y1573272I0J2002D01*
G37*
G36*
G01X1133823Y1581272D02*
G03X1133551I-136J-147D01*
G02X1132188Y1580736I-1363J1466D01*
G01X1132187D01*
G02Y1584740I0J2002D01*
G01X1132188D01*
G02X1133551Y1584204I0J-2002D01*
G03X1133823I136J147D01*
G02X1135186Y1584740I1363J-1466D01*
G01X1135187D01*
G02Y1580736I0J-2002D01*
G01X1135186D01*
G02X1133823Y1581272I0J2002D01*
G37*
G36*
G01X1143823D02*
G03X1143551I-136J-147D01*
G02X1142188Y1580736I-1363J1466D01*
G01X1142187D01*
G02Y1584740I0J2002D01*
G01X1142188D01*
G02X1143551Y1584204I0J-2002D01*
G03X1143823I136J147D01*
G02X1145186Y1584740I1363J-1466D01*
G01X1145187D01*
G02Y1580736I0J-2002D01*
G01X1145186D01*
G02X1143823Y1581272I0J2002D01*
G37*
G36*
G01X1153823D02*
G03X1153551I-136J-147D01*
G02X1152188Y1580736I-1363J1466D01*
G01X1152187D01*
G02Y1584740I0J2002D01*
G01X1152188D01*
G02X1153551Y1584204I0J-2002D01*
G03X1153823I136J147D01*
G02X1155186Y1584740I1363J-1466D01*
G01X1155187D01*
G02Y1580736I0J-2002D01*
G01X1155186D01*
G02X1153823Y1581272I0J2002D01*
G37*
G36*
G01X1163231D02*
G03X1162959I-136J-147D01*
G02X1161596Y1580736I-1363J1466D01*
G01X1161595D01*
G02Y1584740I0J2002D01*
G01X1161596D01*
G02X1162959Y1584204I0J-2002D01*
G03X1163231I136J147D01*
G02X1164594Y1584740I1363J-1466D01*
G01X1164595D01*
G02Y1580736I0J-2002D01*
G01X1164594D01*
G02X1163231Y1581272I0J2002D01*
G37*
G36*
G01X1173231D02*
G03X1172959I-136J-147D01*
G02X1171596Y1580736I-1363J1466D01*
G01X1171595D01*
G02Y1584740I0J2002D01*
G01X1171596D01*
G02X1172959Y1584204I0J-2002D01*
G03X1173231I136J147D01*
G02X1174594Y1584740I1363J-1466D01*
G01X1174595D01*
G02Y1580736I0J-2002D01*
G01X1174594D01*
G02X1173231Y1581272I0J2002D01*
G37*
G36*
G01X1133823Y1589272D02*
G03X1133551I-136J-147D01*
G02X1132188Y1588736I-1363J1466D01*
G01X1132187D01*
G02Y1592740I0J2002D01*
G01X1132188D01*
G02X1133551Y1592204I0J-2002D01*
G03X1133823I136J147D01*
G02X1135186Y1592740I1363J-1466D01*
G01X1135187D01*
G02Y1588736I0J-2002D01*
G01X1135186D01*
G02X1133823Y1589272I0J2002D01*
G37*
G36*
G01X1143823D02*
G03X1143551I-136J-147D01*
G02X1142188Y1588736I-1363J1466D01*
G01X1142187D01*
G02Y1592740I0J2002D01*
G01X1142188D01*
G02X1143551Y1592204I0J-2002D01*
G03X1143823I136J147D01*
G02X1145186Y1592740I1363J-1466D01*
G01X1145187D01*
G02Y1588736I0J-2002D01*
G01X1145186D01*
G02X1143823Y1589272I0J2002D01*
G37*
G36*
G01X1153823D02*
G03X1153551I-136J-147D01*
G02X1152188Y1588736I-1363J1466D01*
G01X1152187D01*
G02Y1592740I0J2002D01*
G01X1152188D01*
G02X1153551Y1592204I0J-2002D01*
G03X1153823I136J147D01*
G02X1155186Y1592740I1363J-1466D01*
G01X1155187D01*
G02Y1588736I0J-2002D01*
G01X1155186D01*
G02X1153823Y1589272I0J2002D01*
G37*
G36*
G01X1163231D02*
G03X1162959I-136J-147D01*
G02X1161596Y1588736I-1363J1466D01*
G01X1161595D01*
G02Y1592740I0J2002D01*
G01X1161596D01*
G02X1162959Y1592204I0J-2002D01*
G03X1163231I136J147D01*
G02X1164594Y1592740I1363J-1466D01*
G01X1164595D01*
G02Y1588736I0J-2002D01*
G01X1164594D01*
G02X1163231Y1589272I0J2002D01*
G37*
G36*
G01X1173231D02*
G03X1172959I-136J-147D01*
G02X1171596Y1588736I-1363J1466D01*
G01X1171595D01*
G02Y1592740I0J2002D01*
G01X1171596D01*
G02X1172959Y1592204I0J-2002D01*
G03X1173231I136J147D01*
G02X1174594Y1592740I1363J-1466D01*
G01X1174595D01*
G02Y1588736I0J-2002D01*
G01X1174594D01*
G02X1173231Y1589272I0J2002D01*
G37*
G36*
G01X1411037Y1711457D02*
G03X1411142Y1712134I-151J370D01*
G02X1421732I5295J6330D01*
G03X1421837Y1711457I256J-307D01*
G02X1430690Y1698267I-5399J-13190D01*
G02X1402184I-14253J0D01*
G02X1411037Y1711457I14252J0D01*
G37*
G36*
G01X435643Y1711458D02*
G03X435748Y1712135I-151J370D01*
G02X446338I5295J6330D01*
G03X446443Y1711458I256J-307D01*
G02X455296Y1698268I-5399J-13190D01*
G02X426790I-14253J0D01*
G02X435643Y1711458I14252J0D01*
G37*
G54D105*
X1137717Y1558020D03*
G54D102*
X1290005Y293768D03*
G54D98*
X1455787Y1421784D03*
X1710550Y691327D03*
X479646Y1421784D03*
X93547Y692260D03*
G54D103*
X1175215Y1532913D03*
X1131715D03*
G54D83*
X1307572Y-26511D03*
X1040152Y-16511D03*
X1015152D03*
X1307572Y13489D03*
X1282572Y23489D03*
X1307572D03*
X1282572Y13489D03*
X1040152Y23489D03*
Y13489D03*
X973180Y-6500D03*
X998180D03*
X1015152Y13489D03*
X1282572Y-16511D03*
X973180Y-26500D03*
X998180D03*
Y-16500D03*
X1015152Y23489D03*
X1307572Y-16511D03*
X973180Y-16500D03*
X1474931Y23489D03*
X1499931D03*
X705760Y-26500D03*
X730760D03*
X705760Y-6500D03*
Y-16500D03*
X730760D03*
Y-6500D03*
X1474931Y13489D03*
X998180Y3500D03*
X973180D03*
X1499931Y13489D03*
X998180Y13500D03*
Y23500D03*
X973180D03*
Y13500D03*
X1499931Y-16511D03*
X1474931D03*
X1324471Y23489D03*
X1349471D03*
X822720Y3500D03*
X847720D03*
X822720Y23500D03*
Y13500D03*
X847720D03*
Y23500D03*
X1324471Y-16511D03*
X1349471D03*
X1324471Y13489D03*
X1349471D03*
X1307572Y-36511D03*
X1282572D03*
Y-26511D03*
X1307572Y-6511D03*
Y3489D03*
X1282572D03*
Y-6511D03*
X1015152Y-36511D03*
Y-26511D03*
X1040152D03*
Y-36511D03*
X1015152Y3489D03*
Y-6511D03*
X1040152D03*
Y3489D03*
X1499931Y-26511D03*
Y-36511D03*
X1474931D03*
Y-26511D03*
X1499931Y-6511D03*
Y3489D03*
X1474931D03*
Y-6511D03*
X1324471Y-36511D03*
Y-26511D03*
X1349471D03*
Y-36511D03*
X1324471Y3489D03*
Y-6511D03*
X1349471D03*
Y3489D03*
G54D90*
X70472Y173228D03*
Y236220D03*
G54D94*
X1565236Y184783D03*
Y264035D03*
G54D95*
X929331Y160413D03*
X922441Y237697D03*
X1534712Y20354D03*
X1787330Y24291D03*
X505185Y41142D03*
X757803Y45079D03*
X312921Y24291D03*
G54D93*
X676508Y224606D03*
G54D92*
Y145866D03*
G54D89*
X1829725Y130315D03*
G54D85*
X791280Y1704890D03*
X1066280D03*
G54D100*
X1405118Y112008D03*
G54D82*
X1341752Y-31511D03*
Y-21511D03*
Y-11511D03*
Y-1511D03*
X1482650Y-31511D03*
Y-21511D03*
Y-11511D03*
Y-1511D03*
X90998Y1517237D03*
X78120Y1517136D03*
X99750Y1563678D03*
X75922Y1560674D03*
X404030Y1593690D03*
X957156Y228863D03*
X899830Y973184D03*
X1380522Y261936D03*
X1388754Y255503D03*
X1380638Y247394D03*
X1386630Y240351D03*
X397406Y1634842D03*
X1031950Y385471D03*
X736710Y605542D03*
X527310Y96447D03*
X414406Y1626692D03*
X460910Y1627472D03*
X64410Y1600802D03*
X1340420Y540122D03*
X704770Y204921D03*
X896060Y482922D03*
X716698Y210721D03*
X704770Y216732D03*
X895340Y499582D03*
X907470Y213680D03*
X902350Y220768D03*
X953970Y206575D03*
X716698Y198887D03*
X704770Y193110D03*
Y181299D03*
X947496Y227835D03*
X705800Y169488D03*
X947496Y213697D03*
X907470Y227854D03*
X941050Y530552D03*
X968286Y482241D03*
X716698Y175387D03*
X902350Y206594D03*
X944032Y435931D03*
X716698Y187387D03*
X944250Y196189D03*
X954420Y512952D03*
Y498852D03*
G54D101*
X1247638Y269488D03*
G54D97*
X1550708Y991220D03*
X525275Y1171319D03*
X1332204D03*
X1326240Y811122D03*
X1501417Y1171319D03*
X1507381Y811122D03*
X1282913Y991220D03*
X306771D03*
X574566D03*
X350098Y811122D03*
X531240D03*
X356062Y1171319D03*
G54D81*
X723041Y-11500D03*
Y-21500D03*
X840001Y8500D03*
Y18500D03*
X980899Y-21500D03*
Y-11500D03*
Y8500D03*
Y18500D03*
X1032433Y-31511D03*
Y-21511D03*
Y-11511D03*
Y-1511D03*
X1290291Y-31511D03*
Y-21511D03*
Y-11511D03*
Y-1511D03*
X62813Y414300D03*
X47619Y417205D03*
X1386273Y270370D03*
X615573Y178034D03*
X628195Y174214D03*
X1282645Y253971D03*
X941059Y426211D03*
X901829Y514430D03*
X889439Y491299D03*
X1407029Y154432D03*
X922879Y530276D03*
X946727Y506252D03*
G54D96*
X1819208Y1420330D03*
X38346D03*
G54D84*
X19685Y-29134D03*
X1837795D03*
X1808192Y1569255D03*
X41870Y1511291D03*
X1812980Y502472D03*
X49280Y337402D03*
X441043Y1672205D03*
X1416437Y1672204D03*
X2081889Y1803261D03*
Y-29134D03*
G54D91*
X1057658Y204724D03*
X805690D03*
G54D99*
X763602Y605413D03*
X1739744D03*
X1094075Y605378D03*
X117933D03*
G54D104*
X841240Y1420330D03*
X1016240D03*
G54D88*
X1680327Y277236D03*
X1153555Y277208D03*
X704185Y277236D03*
X177413Y277208D03*
G54D86*
X177311Y1657953D03*
G54D87*
X1680232D03*
%LPC*%
G75*
G36*
G01X917256Y1656376D02*
G03X918140Y1656010I884J885D01*
G01X1064430D01*
X1084474Y1635966D01*
G03X1085358Y1635600I884J885D01*
G01X1101560D01*
X1103140Y1634020D01*
Y1607480D01*
X1102240Y1606580D01*
X944270D01*
X917966Y1632884D01*
G03X917082Y1633250I-884J-885D01*
G01X816320D01*
X812960Y1636610D01*
Y1714140D01*
X817460Y1718640D01*
X900700D01*
X907010Y1712330D01*
Y1667140D01*
G03X907376Y1666256I1251J0D01*
G01X917256Y1656376D01*
G37*
%LPD*%
G75*
G54D15*
X16925Y203366D03*
X17061Y196368D03*
X24720Y216362D03*
Y232362D03*
Y224362D03*
Y240362D03*
X16420Y420662D03*
X26500Y672862D03*
Y675862D03*
X27300Y764200D03*
X27520Y1245162D03*
X33500Y200862D03*
X33670Y192862D03*
Y208362D03*
X30795Y213358D03*
X33670Y232362D03*
X42500Y224409D03*
X30795Y227366D03*
X33670Y240362D03*
X40000Y298707D03*
X36000Y295952D03*
X40000Y293392D03*
X33105Y304972D03*
X35740Y363337D03*
X39320Y392269D03*
X40940Y387302D03*
X43020Y382942D03*
X41933Y395652D03*
X45960Y428806D03*
X38220Y589862D03*
Y592862D03*
X33020Y595232D03*
X32720Y598402D03*
X34790Y666595D03*
X31390D03*
X38470Y688122D03*
Y683122D03*
Y680622D03*
Y685622D03*
Y693122D03*
Y690622D03*
Y695622D03*
X34899Y711400D03*
X45700Y724100D03*
X45800Y726874D03*
X43841Y1248688D03*
X44833Y1656759D03*
X48269Y1672771D03*
X62020Y295952D03*
X62731Y305426D03*
X59322Y360702D03*
X51114Y360862D03*
X53406Y402862D03*
X49360Y428806D03*
X61171D03*
X47619Y418655D03*
X47618Y415613D03*
X48400Y586000D03*
X57595Y603476D03*
X59500Y738700D03*
X56777Y1314165D03*
X56799Y1520094D03*
Y1536094D03*
Y1540094D03*
Y1560094D03*
X59833Y1604359D03*
X54333Y1613359D03*
X50333D03*
X54478Y1663669D03*
X54535Y1658447D03*
X57833Y1671809D03*
X53333Y1671862D03*
X65000Y1681900D03*
X58325Y1679275D03*
X65937Y28403D03*
Y48720D03*
X77165Y278798D03*
Y295798D03*
Y286262D03*
Y303262D03*
X63429Y360702D03*
X67681D03*
X77220Y379022D03*
Y381522D03*
X68020Y395222D03*
X75516Y420319D03*
Y424319D03*
X64571Y428806D03*
X63540Y438802D03*
X72610Y441262D03*
Y444762D03*
X72981Y466385D03*
X77000Y485362D03*
X74550Y487812D03*
X80300Y641862D03*
X80241Y659011D03*
X80123Y664031D03*
X80135Y667933D03*
X74559Y667814D03*
X78080Y701832D03*
X63930Y739300D03*
X73759Y754726D03*
X68315Y765664D03*
X73759Y759246D03*
X72485Y1304152D03*
X75485D03*
X78485D03*
X72485Y1307152D03*
X75485D03*
X69485Y1304152D03*
Y1307152D03*
X65600Y1318588D03*
X65240Y1326068D03*
X75485Y1316152D03*
X72485Y1313152D03*
Y1310152D03*
X75485Y1313152D03*
Y1310152D03*
X69485D03*
X69809Y1333918D03*
Y1331418D03*
Y1336418D03*
X72809Y1333918D03*
Y1331418D03*
Y1336418D03*
X75809Y1333918D03*
Y1331418D03*
Y1336418D03*
X72909Y1339938D03*
X79009Y1340238D03*
X75909Y1339938D03*
X73027Y1347925D03*
X73059Y1345138D03*
X72987Y1342535D03*
X75909Y1342438D03*
X79009Y1342738D03*
Y1345238D03*
X78977Y1348025D03*
X75859Y1348138D03*
Y1345138D03*
X76369Y1507456D03*
X76680Y1530482D03*
X72774Y1546519D03*
X75922Y1558974D03*
Y1562374D03*
X77040Y1601102D03*
X65120Y1609909D03*
X65520Y1615972D03*
X74100Y1613300D03*
X77833Y1678902D03*
X73833Y1674252D03*
X69833Y1678582D03*
X87620Y285321D03*
X87845Y278798D03*
Y295798D03*
X87820Y302821D03*
X87520Y395865D03*
Y391391D03*
Y382219D03*
X85826Y428319D03*
X84410Y438519D03*
X83320Y445212D03*
X94439Y450081D03*
X81505Y447377D03*
X79400Y482862D03*
X91027Y643276D03*
X89859Y628246D03*
X86459D03*
X82961Y657111D03*
X95725Y654540D03*
X95860Y659622D03*
X83165Y652564D03*
X91078Y649584D03*
X83208Y646436D03*
X83250Y665428D03*
X84470Y668702D03*
X86433Y688160D03*
X81285Y689804D03*
X84035Y697604D03*
X93547Y692260D03*
X83004Y705141D03*
X97295Y699786D03*
X85095Y722164D03*
X95849Y716358D03*
X91610Y721414D03*
X82357Y737803D03*
X84623Y741249D03*
X81966Y759246D03*
X85877Y759275D03*
X93485Y1304152D03*
X87485D03*
X90485D03*
X93485Y1307152D03*
X84485Y1304152D03*
X81485D03*
X93485Y1318152D03*
Y1315652D03*
Y1310152D03*
Y1313152D03*
X94209Y1337738D03*
X81809Y1340238D03*
X84809D03*
X87809D03*
X90809D03*
X94209D03*
X84809Y1345238D03*
X81809Y1342738D03*
X84809D03*
X81809Y1348238D03*
Y1345238D03*
X84809Y1348238D03*
X87809D03*
Y1345238D03*
Y1342738D03*
X94209D03*
Y1348238D03*
Y1345238D03*
X90809Y1348238D03*
Y1345238D03*
Y1342738D03*
X88520Y1484482D03*
Y1491482D03*
Y1487982D03*
Y1494982D03*
X89264Y1507611D03*
X92664D03*
X79769Y1507456D03*
X87500Y1567069D03*
X91500D03*
X90713Y1581852D03*
Y1597867D03*
X81008Y1589872D03*
X90788Y1615821D03*
Y1601867D03*
X81900Y1613300D03*
X85800D03*
X90698Y1630362D03*
X90788Y1619821D03*
X90698Y1642362D03*
X90407Y1656672D03*
X88333Y1661334D03*
X81833Y1674526D03*
X86245Y1694362D03*
X96420Y1693803D03*
X86030Y1683092D03*
X113490Y216596D03*
X113400Y232128D03*
X110937Y285495D03*
Y302854D03*
X107200Y393562D03*
X107301Y388071D03*
X107419Y487807D03*
X104875Y490980D03*
X102384Y505374D03*
X112480Y507792D03*
X110689Y498271D03*
X110464Y505374D03*
X101983Y518100D03*
X99880Y526300D03*
X110060Y515279D03*
X99773Y515606D03*
X105587Y520727D03*
X106110Y633732D03*
X107489Y630917D03*
X110374Y630879D03*
X102269Y634466D03*
X107045Y661917D03*
X99021Y663732D03*
X103397Y667272D03*
X102120Y688650D03*
X102060Y692100D03*
X102420Y697262D03*
X96626Y736187D03*
X110527Y758869D03*
X108465Y1304292D03*
Y1307292D03*
X105475Y1304222D03*
Y1307222D03*
X102485Y1304152D03*
X99485D03*
X96485D03*
X102485Y1307152D03*
X99485D03*
X96485D03*
X108465Y1318292D03*
Y1310292D03*
Y1313292D03*
Y1315792D03*
X105475Y1318222D03*
Y1310222D03*
Y1313222D03*
Y1315722D03*
X99485Y1318152D03*
X96485D03*
Y1315652D03*
Y1310152D03*
Y1313152D03*
X99485Y1310152D03*
Y1313152D03*
Y1315652D03*
X102485Y1318152D03*
Y1310152D03*
Y1313152D03*
Y1315652D03*
X96809Y1340238D03*
Y1345238D03*
Y1348238D03*
Y1342738D03*
X112270Y1518907D03*
X99274Y1529169D03*
X96570Y1546187D03*
X99750Y1565378D03*
Y1561978D03*
X103902Y1584337D03*
X102251Y1576504D03*
X105651D03*
X104318Y1589352D03*
X100620Y1596367D03*
X101500Y1604400D03*
X100020Y1615821D03*
X98738Y1605867D03*
X104400Y1632385D03*
X104430Y1628012D03*
X104318Y1637862D03*
X99600Y1668332D03*
X99645Y1663217D03*
X99980Y1687921D03*
Y1698921D03*
X115850Y186362D03*
X122000Y207362D03*
X116920Y207462D03*
X118920Y278875D03*
X119220Y306236D03*
X119920Y379362D03*
X119457Y392071D03*
Y388071D03*
X125070Y486736D03*
X125013Y491829D03*
X124124Y495883D03*
X116171Y485041D03*
X112483Y510637D03*
X116411Y497707D03*
X118652Y528860D03*
X129762Y531942D03*
X115793Y528188D03*
X112393D03*
X111920Y632922D03*
X114540Y633032D03*
X117750Y633232D03*
X120440Y633347D03*
X121400Y638062D03*
X125890Y644163D03*
X122329Y654660D03*
X122280Y651934D03*
X124431Y649570D03*
X122575Y671930D03*
X118019Y661371D03*
X124737Y735726D03*
X118737D03*
X121737D03*
Y738726D03*
X118737D03*
X124737D03*
X123220Y1324662D03*
X120220D03*
X112749Y1532594D03*
Y1528594D03*
Y1552594D03*
Y1556594D03*
X117707Y1553759D03*
X125033Y1589352D03*
X116798D03*
X123230Y1597350D03*
X119500Y1622380D03*
X124795Y1681846D03*
X128195Y1674362D03*
X114645Y1698862D03*
X117220Y1683437D03*
X127195Y1696362D03*
Y1700362D03*
Y1704362D03*
X125082Y1727092D03*
X123394Y1723472D03*
X117426Y1726622D03*
X125720Y1719262D03*
X141520Y181462D03*
X139720Y179162D03*
X143470Y184012D03*
X133590Y212382D03*
X129394Y278875D03*
X129375Y274800D03*
X129394Y306236D03*
X135220Y397071D03*
X132490Y420062D03*
X138042Y480238D03*
X132833D03*
X136982Y497090D03*
X131737Y496295D03*
X135006Y487753D03*
X131295Y487822D03*
X141325Y503806D03*
X141462Y507600D03*
X141329Y510487D03*
X141220Y498810D03*
X138878Y512550D03*
X138408Y507366D03*
X139153Y516453D03*
X133160Y532002D03*
X132600Y537072D03*
Y540472D03*
X133467Y634531D03*
X131740Y640103D03*
X131600Y646861D03*
X131330Y665740D03*
X142960Y690807D03*
X140460D03*
X142754Y698811D03*
X140254D03*
X142778Y706835D03*
X140278D03*
X140326Y721660D03*
X142826D03*
X140142Y1392545D03*
Y1396275D03*
X129627Y1556360D03*
X129586Y1553759D03*
X129813Y1604367D03*
X130533Y1622321D03*
X129533Y1637862D03*
X137420Y1708362D03*
X144520Y1717562D03*
X141642Y1717592D03*
X134557Y1722778D03*
X137852Y1726572D03*
X147924Y28258D03*
X148784Y48720D03*
X145720Y186462D03*
Y202862D03*
Y206362D03*
X156670Y344542D03*
X159170D03*
X154220Y375682D03*
X158110Y376172D03*
X160090Y391170D03*
Y397470D03*
X152826Y439397D03*
Y434362D03*
X156306Y449045D03*
X153360Y449112D03*
X149557Y494353D03*
X150113Y488487D03*
X161267Y503143D03*
X149472Y506810D03*
X160000Y510052D03*
X152470Y495383D03*
X151378Y526924D03*
X149512Y514810D03*
X150800Y512021D03*
X153737Y514893D03*
X149504Y519881D03*
X154647Y521783D03*
X150877Y757969D03*
X151277Y1339183D03*
X153877D03*
X156477D03*
X156417Y1336343D03*
X151217Y1336393D03*
X153817D03*
X156417Y1333843D03*
X151217Y1333893D03*
X153817D03*
X151277Y1346883D03*
X153877D03*
X151277Y1349383D03*
X153877D03*
X156477Y1346883D03*
Y1349383D03*
Y1344383D03*
X151277D03*
X153877D03*
X156477Y1341883D03*
X151277D03*
X153877D03*
X147307Y1404745D03*
X149568Y1395145D03*
Y1397695D03*
X152684Y1403451D03*
X157490Y1421454D03*
X154990D03*
X159858Y1409361D03*
X155858Y1406669D03*
Y1409390D03*
X157530Y1432124D03*
X155030D03*
X157530Y1424124D03*
X155030D03*
X157530Y1429124D03*
X155030Y1426624D03*
Y1429124D03*
X157530Y1426624D03*
Y1435124D03*
X155030D03*
X157530Y1437754D03*
X155030D03*
X146390Y1504240D03*
X145538Y1517374D03*
X148938D03*
X153600Y1505600D03*
X147067Y1545985D03*
X157441Y1581932D03*
X146312Y1569525D03*
X149712D03*
X152026Y1614138D03*
X158335Y1614452D03*
X155180Y1619872D03*
X156070Y1695702D03*
X145745Y1712362D03*
X161310Y1708022D03*
X148145Y1701862D03*
X155145Y1713517D03*
X164830Y344542D03*
X161670D03*
X173275Y393497D03*
X164000Y415362D03*
X163926Y425383D03*
X164000Y420362D03*
X172507Y417205D03*
X163926Y430883D03*
Y443319D03*
Y439397D03*
Y435383D03*
X178546Y453806D03*
X172632Y454095D03*
X165176Y500782D03*
X176393Y575189D03*
X173793D03*
X176393Y572689D03*
X173793D03*
X171293D03*
Y575189D03*
X173793Y577790D03*
X171293D03*
X176393D03*
X176651Y596883D03*
Y594163D03*
X173878Y597027D03*
Y594307D03*
X176651Y599603D03*
X173878Y599747D03*
X161126Y721660D03*
X161078Y706835D03*
X163626Y721660D03*
X163578Y706835D03*
X170877Y1333783D03*
Y1336383D03*
X176077Y1333783D03*
X173477D03*
X176077Y1336383D03*
X173477D03*
X170907Y1339233D03*
X176107D03*
X173507D03*
X170877Y1341883D03*
X176077D03*
X173477D03*
Y1349383D03*
Y1346883D03*
Y1344383D03*
X176077D03*
Y1346883D03*
Y1349383D03*
X170877D03*
Y1346883D03*
Y1344383D03*
X176358Y1403669D03*
X176258Y1400669D03*
X173892Y1402749D03*
Y1405649D03*
X170922Y1399255D03*
X166262D03*
X173252Y1400005D03*
X168592D03*
X160490Y1421454D03*
X164000Y1408862D03*
X162257Y1406594D03*
X160530Y1432124D03*
Y1424124D03*
Y1429124D03*
Y1426624D03*
Y1435124D03*
Y1437754D03*
X165500Y1440362D03*
X173727Y1452134D03*
Y1448734D03*
X170570Y1509250D03*
X164710Y1518014D03*
X168110D03*
X173331Y1579399D03*
X172099Y1588141D03*
X164920Y1712017D03*
X163060Y1717017D03*
X178226Y1726517D03*
X172962Y1721234D03*
X169777Y1726517D03*
X178142Y1720652D03*
X186120Y24162D03*
X188620D03*
X190880Y383012D03*
Y387162D03*
Y391082D03*
X178375Y396571D03*
X181845Y401071D03*
X187371Y425383D03*
X187532Y421387D03*
X187371Y430883D03*
Y443383D03*
X180740Y437562D03*
X184550Y435712D03*
X187371Y440742D03*
X194440Y433895D03*
Y439565D03*
X187371Y447172D03*
X177871D03*
X181994Y453932D03*
X180640Y447172D03*
X185211Y453942D03*
X185191Y502439D03*
X186793Y575189D03*
X184193D03*
X186793Y572689D03*
X184193D03*
X181593Y575189D03*
X178993D03*
X181593Y572689D03*
X178993D03*
X189293Y575189D03*
X186793Y577790D03*
X184193D03*
X189293D03*
X181593D03*
X178993D03*
X181651Y596883D03*
X179151D03*
X186796Y594195D03*
Y596915D03*
X184151Y596883D03*
X179151Y594163D03*
X181651D03*
X184151D03*
X181651Y599603D03*
X179151D03*
X186796Y599635D03*
X184151Y599603D03*
X186720Y737862D03*
X180720D03*
X183720D03*
Y734862D03*
X180720D03*
X186720D03*
X185835Y757057D03*
X188978Y756855D03*
X191602Y756839D03*
X189377Y1333783D03*
X191977D03*
X189377Y1336383D03*
X191977D03*
X191947Y1339263D03*
X189347D03*
X189377Y1349383D03*
X191977D03*
X189377Y1346883D03*
X191977D03*
Y1344383D03*
X189377D03*
X191977Y1341883D03*
X189377D03*
X187711Y1395170D03*
Y1397670D03*
X190827Y1403451D03*
X180977Y1396173D03*
X178458Y1399269D03*
Y1402169D03*
Y1405069D03*
X188211Y1406691D03*
X186165Y1422589D03*
X183135Y1419784D03*
X180510Y1420258D03*
X177510D03*
X186135Y1419784D03*
X183165Y1422589D03*
X177510Y1423278D03*
X180510D03*
X183075Y1430424D03*
Y1425424D03*
Y1427924D03*
X186075Y1430424D03*
Y1425424D03*
Y1427924D03*
X183075Y1432924D03*
X186075D03*
X192600Y1557360D03*
X185895Y1557875D03*
X189600Y1566300D03*
X187400Y1568132D03*
X187542Y1729092D03*
X193293Y1722197D03*
X188794Y1725092D03*
X195050Y412055D03*
X199149Y425755D03*
Y420255D03*
Y414755D03*
X204699Y423242D03*
Y428742D03*
X195050Y417465D03*
X199149Y436755D03*
Y442255D03*
Y431255D03*
Y453255D03*
Y447755D03*
X197650Y455712D03*
X199149Y468255D03*
X208200Y493510D03*
X202338Y568746D03*
X201392Y574271D03*
X198336D03*
X204610Y571097D03*
X199164Y582481D03*
X200654Y578271D03*
X201622Y581009D03*
X208056Y591665D03*
X208806Y589335D03*
X208056Y587005D03*
X208806Y584675D03*
X202262Y592305D03*
X205162D03*
X202338Y602746D03*
X201392Y608271D03*
X198336D03*
X203892Y594471D03*
X202492Y596571D03*
X208292D03*
X206892Y594371D03*
X205392Y596571D03*
X204610Y605097D03*
X199164Y616481D03*
X200654Y612271D03*
X201622Y615009D03*
X208806Y618675D03*
X208056Y621005D03*
X208806Y623335D03*
X202338Y636746D03*
X208056Y625665D03*
X203892Y628471D03*
X202492Y630571D03*
X202262Y626305D03*
X208292Y630571D03*
X206892Y628371D03*
X205162Y626305D03*
X205392Y630571D03*
X204610Y639097D03*
X201392Y642271D03*
X199164Y650481D03*
X200654Y646271D03*
X201622Y649009D03*
X198336Y642271D03*
X208056Y655005D03*
X208806Y657335D03*
Y652675D03*
X207620Y671262D03*
X198420Y672662D03*
X198495Y669487D03*
X208056Y659665D03*
X205392Y664571D03*
X205162Y660305D03*
X206892Y662371D03*
X202262Y660305D03*
X202492Y664571D03*
X203892Y662471D03*
X208292Y664571D03*
X196049Y678195D03*
X194196Y687061D03*
X200018Y677492D03*
X193332Y678195D03*
X207129Y690027D03*
X203199Y690006D03*
X197086Y686326D03*
X203179Y693626D03*
X207140Y693636D03*
X195735Y696469D03*
X198235Y698969D03*
Y696469D03*
X200735Y698969D03*
Y696469D03*
X207140Y738462D03*
X205220Y736562D03*
X201220Y736662D03*
X203660Y731802D03*
X195602Y756839D03*
X203602Y756855D03*
X208977Y1336383D03*
Y1333783D03*
X194577D03*
Y1336383D03*
X209007Y1339263D03*
X194547D03*
X208977Y1341883D03*
X194577Y1349383D03*
Y1346883D03*
Y1344383D03*
X208977D03*
Y1346883D03*
Y1349383D03*
X194577Y1341883D03*
X206735Y1400005D03*
X209065Y1399255D03*
X204405D03*
X198001Y1409361D03*
X193941Y1407029D03*
X200797Y1409605D03*
X200492Y1406686D03*
X193941Y1409750D03*
X195966Y1542863D03*
X203120Y1624782D03*
X208115Y1624217D03*
X195590Y1714517D03*
X196010Y1709017D03*
X208295Y1703362D03*
X199050Y1726431D03*
X204600Y1733022D03*
X225407Y321831D03*
X209530Y426192D03*
X217770Y428262D03*
X224210Y431501D03*
X224305Y422977D03*
X219995Y426267D03*
X224210Y436619D03*
X218140Y440735D03*
X218010Y432735D03*
X223664Y443125D03*
X220000Y448735D03*
X212891Y566632D03*
X210391Y567981D03*
X212891Y601981D03*
X210391D03*
Y635981D03*
X212891D03*
X210320Y671262D03*
X224900Y713293D03*
X209720Y731862D03*
X220033Y756844D03*
X211602Y756855D03*
X216842Y756865D03*
X214177Y1336383D03*
X211577D03*
X214177Y1333783D03*
X211577D03*
X214207Y1339263D03*
X211607D03*
X214177Y1341883D03*
X211577D03*
X214177Y1349383D03*
Y1346883D03*
Y1344383D03*
X211577D03*
Y1346883D03*
Y1349383D03*
X211395Y1400005D03*
X214201Y1404169D03*
X212035Y1402899D03*
X214101Y1401169D03*
X216554Y1399264D03*
Y1402164D03*
Y1405064D03*
X212035Y1405799D03*
X219587Y1435402D03*
X217469Y1454725D03*
X219587Y1443402D03*
Y1439402D03*
X220869Y1454725D03*
X209820Y1631142D03*
X210593Y1714017D03*
X212120Y1703062D03*
X214120Y1713462D03*
X233339Y17662D03*
X235701Y21582D03*
X241310Y20322D03*
X229135Y26474D03*
X225735D03*
X238063Y26232D03*
X235701Y39570D03*
X229131Y50646D03*
X225731D03*
X239820Y54362D03*
X239720Y71862D03*
X239010Y78542D03*
X238297Y129703D03*
X234902Y174047D03*
X226800Y359464D03*
X230359Y461683D03*
X227430Y719772D03*
X238940Y716652D03*
X230864Y1254295D03*
X246510Y20362D03*
X242220Y39362D03*
X246220D03*
X250220D03*
X254050Y39422D03*
X246360Y26852D03*
X248820Y48962D03*
X252320D03*
X255820D03*
X257520Y51562D03*
X254020D03*
X250520D03*
X249885Y69623D03*
X245220Y67862D03*
X248097Y92143D03*
X247897Y100543D03*
X244822Y115543D03*
Y111543D03*
X253910Y115722D03*
X253878Y111771D03*
X243892Y140912D03*
X259933Y141122D03*
X257256Y156727D03*
X245490Y159702D03*
X252000Y395400D03*
X255810Y405582D03*
X252500Y415862D03*
X258066Y426735D03*
X256695Y461117D03*
X257750Y450842D03*
X254713Y518465D03*
X245700Y513262D03*
X250100Y521783D03*
X256885Y574805D03*
X254385D03*
X256855Y571995D03*
X251885Y574805D03*
X249800Y563262D03*
X254355Y589235D03*
X256855D03*
X251855D03*
X256855Y605995D03*
X251885Y608805D03*
X257643Y594220D03*
X255043D03*
Y596820D03*
X257643D03*
X256885Y608805D03*
X254385D03*
X256855Y603495D03*
X251855Y623265D03*
X254355D03*
X256855D03*
Y639995D03*
Y637495D03*
X257643Y628220D03*
X255043D03*
Y630820D03*
X257643D03*
X256885Y642805D03*
X254385D03*
X251855Y657265D03*
X251885Y642805D03*
X254355Y657265D03*
X256855D03*
X257643Y662220D03*
X255043D03*
Y664820D03*
X257643D03*
X253819Y675567D03*
X253849Y678077D03*
X256419Y675567D03*
X256449Y678077D03*
X251219Y675567D03*
X251249Y678077D03*
X248649D03*
X248989Y698827D03*
X249019Y693767D03*
X251589Y698827D03*
X251649Y696277D03*
X254189Y698827D03*
X251619Y693767D03*
X256849Y696277D03*
X256789Y698827D03*
X256819Y693767D03*
X254249Y696277D03*
X254219Y693767D03*
X248300Y703862D03*
X242460Y716652D03*
X253057Y755345D03*
X245487Y755435D03*
X259510Y757822D03*
X251187Y1255025D03*
X263240Y38122D03*
X266990Y41832D03*
X275120Y28562D03*
X275900Y48872D03*
X259320Y48962D03*
X261020Y51562D03*
X263520D03*
X261820Y48962D03*
X264740Y49182D03*
X266497Y69536D03*
Y72036D03*
X264720Y56362D03*
Y60362D03*
Y64362D03*
X266597Y77526D03*
Y80026D03*
X263320Y87662D03*
X261420Y100662D03*
X264920D03*
X268420D03*
X262920Y97962D03*
X266420D03*
X269920D03*
X273620Y96662D03*
X263550Y120922D03*
X269191Y121092D03*
X275797Y120245D03*
X265910Y125492D03*
X266975Y140107D03*
X260600Y151062D03*
X272800Y140162D03*
X264578Y151203D03*
X260100Y159562D03*
X265500Y227862D03*
X263000D03*
X260500Y227362D03*
Y224862D03*
X270240Y245332D03*
X271821Y251962D03*
X267759D03*
X259224Y419532D03*
X263430Y422235D03*
X259869Y431039D03*
X262963Y443735D03*
X272500Y447735D03*
X263040Y448752D03*
X272500Y452862D03*
X264055Y574505D03*
X264025Y571995D03*
X261555Y574505D03*
X261525Y571995D03*
X264055Y566935D03*
X263995Y569485D03*
X261495D03*
X261555Y566935D03*
X266555Y574505D03*
X266525Y571995D03*
X266495Y569485D03*
X266555Y566935D03*
X269055Y574505D03*
X269025Y571995D03*
X268995Y569485D03*
X269055Y566935D03*
X261465Y592115D03*
X261525Y589565D03*
X264025D03*
X263965Y592115D03*
X266525Y589565D03*
X266465Y592115D03*
X269025Y589565D03*
X268965Y592115D03*
X264025Y605995D03*
X261525D03*
X264055Y608505D03*
X261555D03*
X261435Y597175D03*
X261495Y594625D03*
X263995D03*
X263935Y597175D03*
X266525Y605995D03*
X266555Y608505D03*
X266435Y597175D03*
X266495Y594625D03*
X261525Y603495D03*
X264025D03*
X266525D03*
X269025Y605995D03*
X269055Y608505D03*
X268935Y597175D03*
X268995Y594625D03*
X269025Y603495D03*
X261495Y621055D03*
X263995D03*
X261525Y623565D03*
X264025D03*
X263995Y611055D03*
X261495D03*
X266495Y621055D03*
X266525Y623565D03*
X266495Y611055D03*
X268995Y621055D03*
X269025Y623565D03*
X268995Y611055D03*
X261525Y639995D03*
X264025D03*
X261525Y637495D03*
X266525Y639995D03*
X269025D03*
X264025Y637495D03*
X266525D03*
X269025D03*
X263965Y626115D03*
X261465D03*
X266465D03*
X268965D03*
X261495Y655055D03*
X263995D03*
X261525Y657565D03*
X264025D03*
X263995Y645055D03*
X264055Y642505D03*
X261495Y645055D03*
X261555Y642505D03*
X266495Y655055D03*
X266525Y657565D03*
X266495Y645055D03*
X266555Y642505D03*
X268995Y655055D03*
X269025Y657565D03*
X268995Y645055D03*
X269055Y642505D03*
X261465Y660115D03*
X263965D03*
X266465D03*
X268965D03*
X259049Y678077D03*
X259019Y675567D03*
X259419Y693767D03*
X259389Y698827D03*
X259449Y696277D03*
X269600Y715792D03*
X274247Y727165D03*
X268331Y738029D03*
X273046Y735662D03*
X270100Y727262D03*
X264000Y726262D03*
X266700Y730962D03*
X271570Y746422D03*
X265997Y747535D03*
X272208Y768516D03*
X271057Y765525D03*
Y762425D03*
X287000Y20862D03*
X284233Y26474D03*
X280833D03*
X290799Y28362D03*
X284230Y50646D03*
X280830D03*
X289400Y54222D03*
X285357Y105003D03*
X288557D03*
X280857Y107303D03*
X285857Y115603D03*
X282857D03*
X280857Y109903D03*
X275797Y129592D03*
X287000Y139862D03*
X283053Y139728D03*
X276825Y140462D03*
X290685Y165447D03*
X286481Y251962D03*
X281077D03*
X276491D03*
X289274Y290662D03*
X284515D03*
X276500Y444862D03*
X274850Y442562D03*
X279500Y455362D03*
X277578Y509039D03*
X284482Y566022D03*
X286582Y637809D03*
Y634283D03*
X284287Y716015D03*
X277046Y725709D03*
Y735442D03*
X284358Y732562D03*
X283350Y728483D03*
X289137Y735275D03*
X279507Y727025D03*
X285046Y737964D03*
X281046Y737938D03*
X275210Y738102D03*
X287607Y754962D03*
X277046Y746702D03*
X281046D03*
X285046D03*
X299500Y22862D03*
X295520Y12762D03*
X302610Y26362D03*
X292060Y24472D03*
X295520Y26362D03*
X300248Y28362D03*
X304927Y24654D03*
X304972Y28362D03*
X302720Y38182D03*
X292590Y53982D03*
X293161Y50522D03*
X306570Y50222D03*
X290720Y40017D03*
X294720D03*
X295524Y52092D03*
X301310Y52482D03*
X298550Y51602D03*
X303715Y50857D03*
X292942Y71499D03*
X305747Y64013D03*
Y61113D03*
X305247Y71567D03*
X301600Y82457D03*
X302310Y75673D03*
X295357Y88903D03*
X307820Y95724D03*
X301183Y107103D03*
Y110003D03*
Y112803D03*
X296478Y149203D03*
X296800Y139762D03*
X306000Y165662D03*
X295685Y165447D03*
X296478Y158703D03*
X306730Y173842D03*
X304651Y251962D03*
X291759D03*
X306736Y290662D03*
X302765D03*
X298184D03*
X293763D03*
X298587Y508074D03*
X300520Y552262D03*
X307987Y577658D03*
X293805Y569397D03*
Y565997D03*
X298000Y587890D03*
X308417Y585158D03*
X308447Y592255D03*
X306144Y602225D03*
X305612Y622530D03*
Y625030D03*
Y627530D03*
X296405Y630732D03*
Y634132D03*
X295962Y679374D03*
X294679Y688446D03*
Y685046D03*
X291600Y705162D03*
X298273Y715400D03*
X297087Y721249D03*
X304602Y727968D03*
X293027Y755985D03*
X303647Y1307981D03*
X303723Y1353316D03*
Y1355853D03*
X304051Y1365453D03*
X306667Y1361597D03*
X302805Y1379941D03*
Y1376541D03*
X296170Y1622852D03*
X310400Y50362D03*
X314657Y71803D03*
Y68903D03*
X323040Y73122D03*
X323117Y81168D03*
Y76938D03*
X322875Y84318D03*
X316364Y89212D03*
X310459Y75892D03*
X320430Y78002D03*
X313357Y89503D03*
X313457Y96803D03*
X311057Y107103D03*
Y110003D03*
Y112803D03*
X308175Y144202D03*
X308500Y165662D03*
X311200Y165562D03*
X309230Y173842D03*
X309756Y177449D03*
Y181449D03*
X310970Y195362D03*
X308790Y197622D03*
X320270Y200462D03*
X319370Y214492D03*
X316370D03*
X319370Y217492D03*
X316370D03*
X323314Y210645D03*
X306910Y228162D03*
X309910D03*
X306910Y225162D03*
X309910D03*
X322658Y229254D03*
X319718Y223750D03*
X317981Y237724D03*
X320940Y238372D03*
X317129Y251962D03*
X316463Y290662D03*
X316444Y559125D03*
X317860Y572322D03*
X319520Y577658D03*
X312007Y588675D03*
X319520Y582658D03*
X316127Y592785D03*
X318560Y587632D03*
X321276Y599298D03*
X317386Y623207D03*
X308605Y629525D03*
Y627025D03*
X319557Y736225D03*
X317967Y746985D03*
Y771875D03*
X320578Y1290197D03*
X323028Y1297967D03*
X320428D03*
Y1295467D03*
X323028D03*
Y1292967D03*
X320428D03*
X320245Y1357401D03*
X313841Y1365553D03*
X309841Y1364815D03*
X318051Y1367043D03*
X316579Y1364585D03*
X309841Y1367871D03*
X322575Y1358151D03*
X332500Y150738D03*
X326216Y138787D03*
X326900Y162287D03*
X323420Y207549D03*
X326168Y207580D03*
X334485Y216809D03*
X337000Y216862D03*
X335575Y214170D03*
X328588Y209677D03*
X334500Y219362D03*
X337000D03*
X328939Y229139D03*
X335385Y235309D03*
X335412Y222176D03*
X329648Y252202D03*
X341295Y290239D03*
X329002Y290662D03*
X330674Y365702D03*
X328167Y379073D03*
X336270Y402992D03*
X329050Y607402D03*
X331339Y709313D03*
X328120Y710862D03*
X335677Y715215D03*
X327107Y732665D03*
X335467Y725335D03*
X338097Y736235D03*
X335126Y728323D03*
X327096Y736005D03*
X336446Y746486D03*
X338667Y772452D03*
X341527Y778362D03*
X339148Y1269717D03*
X339088Y1272287D03*
X339028Y1274887D03*
X325688Y1290167D03*
X325718Y1287587D03*
X328078Y1288747D03*
X323178Y1290197D03*
X323208Y1287617D03*
X328168Y1280967D03*
X325748Y1284987D03*
X328108Y1286147D03*
X328138Y1283567D03*
X328018Y1291317D03*
X339035Y1280218D03*
X339040Y1277594D03*
X328065Y1299248D03*
X325538Y1297937D03*
Y1292937D03*
Y1295437D03*
X328058Y1293917D03*
X328070Y1296624D03*
X335679Y1330518D03*
X334973Y1333353D03*
X338795Y1338799D03*
X336179Y1342753D03*
X324905Y1357401D03*
X327235Y1358151D03*
X332475Y1357945D03*
X327875Y1363945D03*
Y1361045D03*
X330041Y1362315D03*
X329941Y1359315D03*
X332475Y1363345D03*
Y1360445D03*
X340440Y120552D03*
X343450Y131167D03*
X342700Y139662D03*
X355189Y144267D03*
X351100Y150412D03*
X348100Y185162D03*
X345600Y188162D03*
X356295Y219362D03*
X353145D03*
X342000Y252612D03*
X354672Y252693D03*
X354145Y290591D03*
X345411Y364702D03*
Y376923D03*
X343354Y391643D03*
X347340Y407462D03*
X348880Y703442D03*
X354100Y720743D03*
X352879Y728657D03*
X348037Y728735D03*
X348730Y735098D03*
Y731698D03*
X344264Y1272455D03*
X341754Y1272485D03*
X344252Y1269948D03*
X341742Y1269978D03*
X344258Y1267117D03*
X341748Y1267147D03*
X341754Y1274985D03*
X344264Y1274955D03*
X355036Y1272433D03*
Y1269933D03*
X355378Y1262027D03*
X355318Y1264597D03*
X355258Y1267197D03*
X355036Y1274933D03*
X341605Y1280248D03*
X344115Y1280218D03*
X344264Y1277455D03*
X341754Y1277485D03*
X355048Y1277440D03*
X355025Y1280248D03*
X352373Y1334603D03*
X354703Y1335353D03*
X345969Y1342755D03*
X341969Y1342017D03*
X350179Y1344245D03*
X348707Y1341787D03*
X341969Y1345073D03*
X354850Y1371908D03*
X351850D03*
X349260Y1373418D03*
X351850Y1375408D03*
X354850D03*
X351850Y1378408D03*
X354850D03*
X351850Y1381408D03*
X354850D03*
X349260Y1376918D03*
Y1379918D03*
X349636Y1399601D03*
X352713Y1399336D03*
X355513Y1402306D03*
X352513D03*
X349513D03*
X355325Y1405386D03*
X349463Y1405286D03*
X352463D03*
X355325Y1408386D03*
X346426Y1414401D03*
X352401Y1414432D03*
X355325Y1414386D03*
Y1417386D03*
X352401Y1411432D03*
X355325Y1411386D03*
X352401Y1408432D03*
X349123Y1411376D03*
X349323Y1408406D03*
X349073Y1414356D03*
X346256Y1417301D03*
X352231Y1417332D03*
X348903Y1417256D03*
X363625Y127662D03*
X361800Y122522D03*
X366060Y133912D03*
X363525Y158702D03*
X361190Y210762D03*
X357303Y213159D03*
X371551Y224862D03*
X367306Y252811D03*
X366498Y290264D03*
X357660Y318850D03*
X364014Y366391D03*
Y378649D03*
X364179Y392037D03*
X370200Y409582D03*
X373720Y431362D03*
X365720Y440562D03*
X365771Y449480D03*
X359669Y686744D03*
X359639Y690114D03*
X360470Y705965D03*
X363101Y697348D03*
Y693948D03*
X360990Y726862D03*
X358902Y736225D03*
X355946Y728800D03*
X359790Y729835D03*
X358902Y739755D03*
Y743035D03*
Y754945D03*
Y746405D03*
Y773352D03*
X371578Y1248967D03*
X371458Y1254137D03*
X371330Y1256687D03*
X371518Y1251537D03*
X371278Y1259257D03*
X360198Y1269777D03*
X357546Y1272403D03*
Y1269903D03*
X360138Y1272347D03*
X357828Y1264567D03*
X357888Y1261997D03*
X360378Y1264627D03*
X360438Y1262057D03*
X357768Y1267167D03*
X360318Y1267227D03*
X357546Y1274903D03*
X360128Y1274957D03*
X371218Y1261857D03*
X371225Y1267188D03*
X371230Y1264564D03*
X357558Y1277410D03*
X357535Y1280218D03*
X360120Y1277654D03*
X367694Y1317092D03*
X367807Y1319592D03*
X368391Y1328161D03*
X370923Y1325373D03*
X357033Y1334603D03*
X359363Y1335353D03*
X362147Y1336553D03*
X360003Y1338247D03*
X364269Y1338017D03*
X364073Y1334903D03*
X360003Y1341147D03*
X362147Y1339653D03*
X364347Y1340853D03*
X364647Y1371990D03*
X361647D03*
X358647D03*
X367647D03*
X370552Y1372073D03*
X364647Y1375490D03*
X361647D03*
X358647D03*
Y1378490D03*
X370552Y1375573D03*
X367647Y1375490D03*
X355713Y1399336D03*
X361703Y1399386D03*
X364703D03*
X367703D03*
X370703D03*
X358703Y1402386D03*
X361703D03*
X364703D03*
X367703D03*
X370703D03*
X358713Y1399336D03*
X358573Y1405336D03*
X361573D03*
X364573D03*
X367573D03*
X370573D03*
X358703Y1414606D03*
X361703D03*
X364703D03*
X361703Y1417386D03*
X358703D03*
X364703D03*
X367703D03*
Y1414606D03*
X358217Y1411405D03*
X370517Y1414615D03*
X370717Y1417405D03*
X357917Y1408205D03*
X367948Y1531529D03*
X371850Y1534062D03*
X368600Y1543200D03*
X367140Y1645390D03*
X366700Y1649000D03*
X370500Y1654362D03*
X370635Y1675820D03*
X369300Y1680400D03*
Y1682900D03*
X380930Y122022D03*
X383160Y124322D03*
X383060Y128491D03*
X372530Y122972D03*
X373200Y126052D03*
X379295Y131002D03*
X379860Y252162D03*
X379112Y290386D03*
X385720Y320902D03*
X376500Y366391D03*
Y378649D03*
X377136Y390307D03*
X390220Y392062D03*
X383060Y403542D03*
X379220Y436362D03*
X376220D03*
X382220D03*
X389920Y461362D03*
X379220Y470962D03*
X387500Y495362D03*
X389020Y522862D03*
X371970Y683892D03*
X381010Y734732D03*
X376638Y1248997D03*
X374088Y1248937D03*
X374028Y1251507D03*
X373823Y1256896D03*
X376333Y1256866D03*
X376518Y1254167D03*
X376578Y1251567D03*
X373968Y1254107D03*
X373835Y1259403D03*
X376345Y1259373D03*
X387478Y1248967D03*
X387358Y1254137D03*
X387117Y1256851D03*
X387418Y1251537D03*
X387117Y1259351D03*
X373835Y1261903D03*
Y1264403D03*
X376345Y1261873D03*
Y1264373D03*
X376285Y1267218D03*
X373735Y1267158D03*
X387117Y1261851D03*
X387129Y1264358D03*
X387125Y1267188D03*
X384501Y1321177D03*
X386831Y1321927D03*
X378097Y1329329D03*
X374097Y1328591D03*
X382307Y1330819D03*
X380835Y1328361D03*
X374097Y1331647D03*
X373552Y1372073D03*
X377025Y1371990D03*
X380025D03*
X373532Y1378598D03*
X373552Y1375573D03*
X380025Y1378490D03*
X377025D03*
X380025Y1375490D03*
X377025D03*
Y1381490D03*
X380025D03*
X376825Y1399386D03*
X379825D03*
X373703D03*
X379825Y1402386D03*
X376825D03*
X373703D03*
X376825Y1405386D03*
X379825D03*
X373573Y1405336D03*
X374027Y1411365D03*
X373703Y1414606D03*
X376825Y1414386D03*
X379825D03*
X376825Y1417386D03*
Y1411386D03*
X379825D03*
X373703Y1417386D03*
X376825Y1408386D03*
X379825D03*
X374307Y1408135D03*
X382489Y1428478D03*
X385667Y1433425D03*
X386827Y1429525D03*
X377830Y1534342D03*
X374900Y1534102D03*
X381120D03*
X377720Y1539862D03*
X374720D03*
X374800Y1546400D03*
X385100Y1539700D03*
X381800Y1539600D03*
X381000Y1546500D03*
X384000D03*
X378000Y1546400D03*
X387930Y1585155D03*
X384600Y1595100D03*
X382220Y1591870D03*
X374391Y1648476D03*
X385123Y1639732D03*
X378547D03*
X380170Y1660002D03*
X372640Y1662112D03*
X380077Y1654049D03*
X372009Y1682584D03*
X375430Y1676462D03*
X376610Y1688252D03*
X396380Y62742D03*
X402100Y62632D03*
X399240Y62722D03*
X404910Y62562D03*
X388735Y117322D03*
X395980Y148272D03*
X388965Y215067D03*
X388720Y218362D03*
X394720Y206362D03*
X402700Y234167D03*
X392616Y252162D03*
X396294Y281585D03*
X392083Y290954D03*
X404215Y291140D03*
X398720Y321202D03*
X398661Y323761D03*
X390876Y365640D03*
X390843Y378439D03*
X403875Y365640D03*
X404120Y378439D03*
X404291Y391433D03*
X391149Y404304D03*
X403720Y405552D03*
X388720Y430862D03*
X403220Y436362D03*
X395520Y448362D03*
X400080Y472652D03*
X402500Y495362D03*
X394500Y522862D03*
X400589Y575236D03*
X398796Y1161570D03*
Y1153070D03*
Y1170070D03*
X403738Y1249027D03*
X403618Y1254197D03*
X403498Y1256747D03*
X403678Y1251597D03*
X392538Y1248997D03*
X389928Y1251507D03*
X389988Y1248937D03*
X389868Y1254107D03*
X392298Y1256717D03*
X392418Y1254167D03*
X389627Y1256821D03*
X392478Y1251567D03*
X392238Y1259287D03*
X389627Y1259321D03*
X403438Y1259317D03*
X392220Y1264594D03*
X392228Y1261897D03*
X389627Y1261821D03*
X389639Y1264328D03*
X389635Y1267158D03*
X392185Y1267218D03*
X403385Y1267248D03*
X403378Y1261917D03*
X403390Y1264624D03*
X399935Y1317092D03*
Y1319592D03*
X389161Y1321177D03*
X391491Y1321927D03*
X392131Y1324821D03*
X396397Y1324591D03*
X394197Y1323091D03*
X396397Y1321691D03*
X400073Y1327653D03*
X403051Y1325373D03*
X394297Y1326091D03*
X392131Y1327721D03*
X396397Y1327491D03*
X400888Y1395508D03*
X392947Y1397827D03*
X390934Y1404085D03*
X401079Y1399208D03*
X400924Y1408227D03*
X400926Y1404707D03*
X392517Y1419015D03*
X400991Y1417264D03*
X390934Y1407605D03*
X390914Y1412991D03*
X403125Y1425008D03*
X390687Y1431713D03*
X390777Y1435152D03*
X394067Y1435323D03*
X401244Y1440773D03*
X396822Y1439340D03*
X396946Y1537632D03*
X396768Y1541810D03*
X404920Y1539362D03*
X396946Y1556810D03*
X391330Y1585155D03*
X404030Y1595390D03*
Y1591990D03*
X394360Y1616380D03*
X392550Y1618650D03*
X397406Y1633142D03*
X402590Y1618952D03*
X401740Y1648082D03*
X404240D03*
X404320Y1645452D03*
X401820D03*
X391563Y1640244D03*
X397406Y1636542D03*
X397400Y1641000D03*
X390180Y1668212D03*
X396824Y1673662D03*
X407970Y59612D03*
X407790Y62652D03*
X415800Y62665D03*
Y67465D03*
X419901Y117491D03*
X408284Y163662D03*
X420865Y215067D03*
X410996Y218834D03*
X420752Y239562D03*
X405139Y239908D03*
X417765Y252162D03*
X404985D03*
X417218Y291274D03*
X419920Y338162D03*
X416220Y364062D03*
X418704Y379201D03*
X416762Y367353D03*
X418540Y392163D03*
X416514Y407028D03*
X412720Y439362D03*
X417880Y461942D03*
X418520Y473562D03*
X419460Y1161570D03*
Y1153370D03*
Y1169597D03*
X406248Y1248997D03*
X408798Y1249057D03*
X408511Y1256866D03*
X406001Y1256896D03*
X406128Y1254167D03*
X408678Y1254227D03*
X406188Y1251567D03*
X419638Y1248967D03*
X419295Y1256851D03*
X419518Y1254137D03*
X419578Y1251537D03*
X419295Y1259351D03*
X408738Y1251627D03*
X408523Y1259373D03*
X406013Y1259403D03*
X419295Y1261851D03*
X419307Y1264358D03*
X419285Y1267188D03*
X408523Y1264373D03*
X406013Y1264403D03*
Y1261903D03*
X408523Y1261873D03*
X405895Y1267218D03*
X408445Y1267278D03*
X416629Y1321177D03*
X418959Y1321927D03*
X410225Y1329329D03*
X406225Y1328591D03*
X414435Y1330819D03*
X412963Y1328361D03*
X406225Y1331647D03*
X418320Y1383862D03*
X422320D03*
X414333Y1385292D03*
X410933Y1384648D03*
X414909Y1395658D03*
X408915Y1402606D03*
X411150Y1408163D03*
X410912Y1418177D03*
X408968Y1410427D03*
X411162Y1414126D03*
X416926Y1426471D03*
X412416Y1431645D03*
X419861Y1429718D03*
X419302Y1434700D03*
X422708Y1437560D03*
X410074Y1424993D03*
X416999Y1441908D03*
X413599D03*
X407625Y1552572D03*
X419820Y1555862D03*
X409140Y1566892D03*
X405000Y1566670D03*
X412600Y1601000D03*
X408600Y1607400D03*
X419780Y1602802D03*
X414406Y1624992D03*
Y1628392D03*
X405990Y1618952D03*
X416020Y1620862D03*
X412456Y1649838D03*
X417960Y1650072D03*
X410700Y1655310D03*
X409857Y1682767D03*
X421320Y1671699D03*
X410249Y1673082D03*
X427120Y59862D03*
X428500Y65016D03*
Y70016D03*
X435340Y122196D03*
X428889Y121515D03*
X428883Y131015D03*
X429780Y149373D03*
Y153477D03*
Y157466D03*
Y161466D03*
X433695Y209862D03*
X421200Y232562D03*
X423145Y227862D03*
X426490Y244262D03*
X429702Y290763D03*
X425720Y319492D03*
X432380Y346522D03*
X422420Y338162D03*
X431781Y379201D03*
X434006Y365203D03*
X433596Y391163D03*
X431920Y405288D03*
X428720Y439362D03*
X437720Y435362D03*
X431570Y435512D03*
X437520Y476337D03*
X431220Y496362D03*
X434343Y504233D03*
Y509733D03*
Y498733D03*
X431220Y507143D03*
Y512623D03*
Y501643D03*
X434343Y515233D03*
Y526233D03*
Y520733D03*
X431220Y518133D03*
Y523362D03*
X434620Y535762D03*
X434343Y542733D03*
X434320Y540153D03*
X434343Y547769D03*
Y552769D03*
X421960Y1161570D03*
Y1153370D03*
Y1169597D03*
X422148Y1248937D03*
X424698Y1248997D03*
X422088Y1251507D03*
X421805Y1256821D03*
X422028Y1254107D03*
X424458Y1256717D03*
X424578Y1254167D03*
X424638Y1251567D03*
X421805Y1259321D03*
X424398Y1259287D03*
X436068Y1248967D03*
X435828Y1256687D03*
X435948Y1254137D03*
X436008Y1251537D03*
X435768Y1259257D03*
X421805Y1261821D03*
X421817Y1264328D03*
X421795Y1267158D03*
X424345Y1267218D03*
X424380Y1264594D03*
X424388Y1261897D03*
X435715Y1267188D03*
X435720Y1264564D03*
X435708Y1261857D03*
X432063Y1317092D03*
Y1319592D03*
X421289Y1321177D03*
X423619Y1321927D03*
X428525Y1321691D03*
X426325Y1323091D03*
X424259Y1324821D03*
X428525Y1324591D03*
X432628Y1327845D03*
X435179Y1325373D03*
X424259Y1327721D03*
X426425Y1326091D03*
X428525Y1327491D03*
X426320Y1383862D03*
X430320D03*
X439030Y1383692D03*
X436780Y1387387D03*
X436467Y1391687D03*
X438458Y1402169D03*
X438645Y1426890D03*
X437299Y1436774D03*
X433539Y1430613D03*
X425030Y1434292D03*
X433897Y1434670D03*
X427546Y1443411D03*
X433954Y1439029D03*
X424146Y1443411D03*
X435396Y1551810D03*
X424820Y1552605D03*
X431620Y1541362D03*
X434430Y1567562D03*
X424570Y1579466D03*
X433350Y1579509D03*
X424800Y1616600D03*
X432200Y1607060D03*
X423180Y1602802D03*
X432500Y1613822D03*
X430015Y1626608D03*
X433670Y1639562D03*
X426728Y1636495D03*
X451418Y78782D03*
X446640Y104552D03*
X446746Y152662D03*
X453028Y154864D03*
X452500Y213362D03*
Y222362D03*
X452071Y254862D03*
X442265Y290939D03*
X439120Y314562D03*
X442220Y323362D03*
X448220Y323582D03*
Y319862D03*
X446000Y339362D03*
X455000Y340362D03*
X450500Y358862D03*
X443770Y371042D03*
X451062Y397262D03*
X447490Y409052D03*
X443300Y410962D03*
X447750Y414112D03*
X453020Y414262D03*
X449420Y424162D03*
X451520Y475837D03*
X442520Y476337D03*
X453680Y515072D03*
X451320Y533562D03*
X448276Y1161570D03*
X445776D03*
X443276D03*
X445776Y1153370D03*
X448276D03*
X443276D03*
X448276Y1170069D03*
X445776D03*
X443276D03*
X441128Y1248997D03*
X438578Y1248937D03*
X438518Y1251507D03*
X440858Y1256866D03*
X438348Y1256896D03*
X441008Y1254167D03*
X438458Y1254107D03*
X441068Y1251567D03*
X440870Y1259373D03*
X438360Y1259403D03*
X451642Y1256851D03*
X451878Y1254107D03*
X451642Y1259351D03*
X451938Y1251507D03*
X451998Y1248937D03*
X438360Y1261903D03*
X440870Y1261873D03*
Y1264373D03*
X438360Y1264403D03*
X438225Y1267158D03*
X440775Y1267218D03*
X451642Y1261851D03*
X451654Y1264358D03*
X451645Y1267158D03*
X448757Y1321177D03*
X451087Y1321927D03*
X442353Y1329329D03*
X438353Y1328591D03*
X446563Y1330819D03*
X445091Y1328361D03*
X438353Y1331647D03*
X443842Y1389106D03*
X448020Y1391862D03*
X443424Y1397869D03*
X439391Y1398266D03*
X441369Y1394260D03*
X451048Y1404914D03*
X447110Y1403812D03*
X448114Y1396812D03*
X445339Y1415731D03*
X446230Y1407722D03*
X445230Y1411719D03*
X445723Y1419730D03*
X443850Y1423404D03*
X451080Y1433740D03*
X440164Y1433982D03*
X445294Y1430415D03*
X443715Y1436052D03*
X452520Y1564862D03*
X448328Y1582476D03*
X446020Y1570412D03*
X452020Y1580412D03*
X448740Y1574862D03*
X444458Y1602654D03*
X437383Y1602629D03*
X454661Y1609235D03*
X442974Y1615615D03*
X448181Y1614401D03*
X443800Y1610712D03*
X449940Y1647412D03*
X447090Y1647472D03*
X444940Y1641842D03*
X438340Y1652266D03*
X441740D03*
X462620Y120948D03*
X462320Y115948D03*
X453346Y149864D03*
X461900Y215244D03*
X466300Y217803D03*
X461900Y222921D03*
X466300Y225480D03*
X468323Y254562D03*
X465236Y296973D03*
X461736Y301098D03*
Y306098D03*
X463198Y311587D03*
X465000Y340362D03*
X456660Y359172D03*
X460800Y358962D03*
X467211Y371902D03*
X459220Y393762D03*
X463500Y383562D03*
X455720Y404762D03*
X458600Y414262D03*
X465421Y428078D03*
X456520Y476337D03*
X461520D03*
X453727Y518036D03*
X457456Y522516D03*
X470880Y572692D03*
X467130Y600122D03*
X456818Y1256687D03*
X454388Y1254077D03*
X454152Y1256821D03*
X456998Y1251537D03*
X456758Y1259257D03*
X454152Y1259321D03*
X468258Y1249107D03*
X468018Y1256827D03*
X468138Y1254277D03*
X468198Y1251677D03*
X467958Y1259397D03*
X457058Y1248967D03*
X454508Y1248907D03*
X454448Y1251477D03*
X456938Y1254137D03*
X456705Y1267188D03*
X454155Y1267128D03*
X456748Y1261867D03*
X456740Y1264564D03*
X454152Y1261821D03*
X454164Y1264328D03*
X467905Y1267328D03*
X467910Y1264704D03*
X467898Y1261997D03*
X464191Y1317092D03*
Y1319592D03*
X453417Y1321177D03*
X455747Y1321927D03*
X458453Y1323091D03*
X460653Y1321691D03*
Y1324591D03*
X456387Y1324821D03*
X464191Y1327793D03*
X467307Y1325373D03*
X458553Y1326091D03*
X460653Y1327491D03*
X456387Y1327721D03*
X459550Y1401348D03*
X465947Y1398355D03*
X459321Y1393009D03*
Y1396409D03*
X458441Y1414893D03*
X468880Y1418400D03*
X456619Y1431189D03*
X463140Y1451562D03*
X463207Y1547543D03*
X453595Y1551470D03*
X459520Y1546962D03*
X466905Y1567847D03*
X467400Y1556700D03*
X460020Y1580412D03*
X457220Y1584020D03*
X466520Y1574862D03*
X457220Y1603562D03*
X460200Y1589900D03*
X456510Y1614472D03*
X469488Y1607362D03*
X460910Y1629172D03*
Y1625772D03*
X455681Y1622492D03*
X458978Y1634481D03*
X463344Y1637622D03*
X469580Y1640272D03*
X468040Y1651657D03*
X466460Y1672332D03*
X466180Y1678392D03*
X481880Y147069D03*
X481246Y161364D03*
X476220Y158772D03*
X470900Y234787D03*
X486800Y259162D03*
X478500Y258862D03*
X474736Y302098D03*
X478995Y293787D03*
X479736Y303598D03*
Y308598D03*
X486720Y360862D03*
X482720D03*
X475508Y359266D03*
X476585Y370727D03*
X472720Y391362D03*
X485020Y414162D03*
X471920Y416687D03*
X474169Y476196D03*
X479169D03*
X474044Y503725D03*
X478510Y602942D03*
X472960Y602152D03*
X482780Y607012D03*
X473698Y1161570D03*
X471198D03*
X473698Y1153370D03*
X471198D03*
X473698Y1170070D03*
X471198D03*
X473318Y1249137D03*
X470768Y1249077D03*
X473035Y1256866D03*
X470525Y1256896D03*
X473198Y1254307D03*
X470648Y1254247D03*
X473258Y1251707D03*
X470708Y1251647D03*
X473047Y1259373D03*
X470537Y1259403D03*
X484098Y1248997D03*
X483819Y1256851D03*
X483978Y1254167D03*
X484038Y1251567D03*
X483819Y1259351D03*
X472965Y1267358D03*
X470415Y1267298D03*
X470537Y1261903D03*
X473047Y1261873D03*
Y1264373D03*
X470537Y1264403D03*
X483819Y1261851D03*
X483831Y1264358D03*
X483745Y1267218D03*
X480885Y1321177D03*
X485545D03*
X483215Y1321927D03*
X474481Y1329329D03*
X470481Y1328591D03*
X478691Y1330819D03*
X477219Y1328361D03*
X470481Y1331647D03*
X483560Y1401712D03*
X474983Y1400385D03*
X485141Y1405430D03*
X481997Y1409955D03*
X470987Y1409965D03*
X484921Y1413246D03*
X470890Y1435838D03*
X478449Y1448158D03*
X482633Y1449091D03*
Y1446091D03*
X470111Y1548269D03*
X483348Y1548062D03*
X475110Y1548112D03*
X477968Y1548122D03*
X480848Y1548120D03*
X486210Y1547960D03*
X482400Y1558320D03*
X472220Y1626732D03*
X472210Y1622735D03*
X477905Y1663242D03*
Y1659242D03*
X475150Y1654302D03*
X477835Y1677462D03*
X488748Y72264D03*
X499580Y78442D03*
X489730Y76132D03*
X498330Y96112D03*
X498730Y128592D03*
X498700Y212685D03*
Y220362D03*
X503100Y215244D03*
X500925Y231262D03*
X503100Y222921D03*
X496028Y258590D03*
X499096Y252462D03*
X489091Y293787D03*
X498636Y296273D03*
X495136Y300398D03*
Y305398D03*
X486861D03*
X495036Y310398D03*
X486710Y313582D03*
X492150Y336810D03*
X498720Y360862D03*
X490720D03*
Y368862D03*
X489520Y411862D03*
X494020Y414262D03*
X492970Y409252D03*
X502070Y427937D03*
X488169Y475696D03*
X493169Y476196D03*
X498169D03*
X486500Y556212D03*
X491043Y550447D03*
X486608Y1248967D03*
X489158Y1249027D03*
X486329Y1256821D03*
X486488Y1254137D03*
X488918Y1256747D03*
X489038Y1254197D03*
X486548Y1251537D03*
X489098Y1251597D03*
X486329Y1259321D03*
X488858Y1259317D03*
X500228Y1259237D03*
X486329Y1261821D03*
X486341Y1264328D03*
X488840Y1264624D03*
X488848Y1261927D03*
X488805Y1267248D03*
X486255Y1267188D03*
X500138Y1269637D03*
X500150Y1272344D03*
X500198Y1267037D03*
Y1264467D03*
X500168Y1261807D03*
X500150Y1275224D03*
Y1278104D03*
X487875Y1321927D03*
X492878Y1322618D03*
X490678Y1324018D03*
X496319Y1330493D03*
Y1333043D03*
X499435Y1338799D03*
X488539Y1325772D03*
X492878Y1325518D03*
X488539Y1328672D03*
X490778Y1327018D03*
X492878Y1328418D03*
X496319Y1341264D03*
X491089Y1446091D03*
Y1449091D03*
X499489D03*
Y1446091D03*
X489230Y1643592D03*
X516236Y92948D03*
X513586Y92799D03*
X510600Y92782D03*
X517290Y104252D03*
X513700Y117862D03*
X510900Y111962D03*
X503270Y128592D03*
X507320D03*
X515690Y147852D03*
X519010Y147912D03*
X518186Y139821D03*
X519236Y202404D03*
X518670Y219192D03*
X512500Y209862D03*
Y223362D03*
X508500Y232862D03*
X508000Y241862D03*
X508502Y298813D03*
X503040Y287928D03*
X508500Y303362D03*
X508136Y309398D03*
X502239Y315404D03*
X507160Y332452D03*
X510720Y360862D03*
X514720D03*
X502720D03*
X506720Y368862D03*
X509720Y390362D03*
X513720D03*
X505720Y398362D03*
X502260Y397742D03*
X511320Y437962D03*
X513444Y457522D03*
X516970Y592942D03*
X504135Y615612D03*
X505398Y1259377D03*
X502858Y1259257D03*
X502718Y1271417D03*
X505218Y1271447D03*
X505290Y1267254D03*
X505338Y1261947D03*
X505278Y1264547D03*
X502750Y1267134D03*
X502798Y1261827D03*
X502738Y1264427D03*
X502718Y1274114D03*
X505218Y1274144D03*
X515898Y1271447D03*
X515950Y1274144D03*
X505220Y1280054D03*
X502718Y1276994D03*
X505218Y1277024D03*
X502680Y1280054D03*
X515960D03*
X515950Y1277024D03*
X513013Y1334603D03*
X517673D03*
X515343Y1335353D03*
X506609Y1342755D03*
X502609Y1342017D03*
X510819Y1344245D03*
X509347Y1341787D03*
X502609Y1345073D03*
X509246Y1420002D03*
X505777Y1425579D03*
X507964Y1448979D03*
Y1445979D03*
X529720Y30792D03*
Y43054D03*
X534720Y42922D03*
X533915Y59822D03*
X523978Y59074D03*
X529078Y59282D03*
X527520Y69633D03*
X528590Y72922D03*
X518450Y101602D03*
X527310Y98147D03*
Y94747D03*
X527160Y129243D03*
X523220Y170362D03*
X534765Y161067D03*
X526920Y161362D03*
X529507Y202448D03*
X522337Y202404D03*
X531298Y284280D03*
X536420Y309422D03*
X523682Y307541D03*
Y304541D03*
X526980Y322582D03*
X521820Y336762D03*
X531720Y360862D03*
X527720D03*
X523670Y368892D03*
X525720Y390362D03*
X529720D03*
X521720Y398362D03*
X532650Y446396D03*
Y442376D03*
X521885Y452442D03*
X532650Y450330D03*
Y454270D03*
X533410Y475932D03*
X525820Y473662D03*
X524425Y489112D03*
Y495112D03*
X519520Y484027D03*
X522805Y482155D03*
X531258Y505473D03*
X521561Y505969D03*
Y500469D03*
Y511469D03*
X524220Y505862D03*
Y500362D03*
Y511362D03*
X521561Y516969D03*
Y522469D03*
X536000Y520362D03*
X524220Y516862D03*
X524720Y525293D03*
Y519743D03*
X521561Y527969D03*
Y539819D03*
X524920D03*
X524820Y545319D03*
X523699Y571545D03*
X528500Y566722D03*
X523890Y592387D03*
X531472Y579750D03*
X521118Y1273097D03*
X518488Y1271477D03*
X521058Y1275667D03*
X518490Y1274144D03*
X521058Y1278277D03*
X521020Y1280974D03*
X518500Y1280054D03*
X518490Y1277024D03*
X530398Y1288557D03*
X530548Y1283377D03*
X530428Y1285947D03*
X530410Y1291254D03*
X532558Y1289967D03*
X532618Y1287367D03*
X532678Y1284797D03*
X530450Y1297014D03*
Y1294134D03*
X532570Y1295554D03*
Y1298434D03*
Y1292674D03*
X525008Y1336287D03*
X520643Y1338247D03*
X522809Y1339517D03*
X522783Y1334882D03*
X520643Y1341147D03*
X520003Y1335353D03*
X528447Y1353316D03*
Y1355816D03*
X524892Y1341462D03*
X522818Y1342930D03*
X528929Y1364212D03*
X531563Y1361597D03*
X539720Y30792D03*
X534720D03*
X542050Y47452D03*
X539720Y42862D03*
X550971Y42902D03*
X544720Y42892D03*
X548609Y48082D03*
X537315Y59822D03*
X541002Y71436D03*
X544402D03*
X548070Y79372D03*
X542460Y99172D03*
X539475Y118772D03*
X547395Y147302D03*
X543083Y146338D03*
X540460Y200392D03*
X544390Y236512D03*
X550390Y231742D03*
X548390Y236512D03*
X546390Y231742D03*
X542050Y231722D03*
X539639Y271972D03*
X539830Y274912D03*
X537720Y278212D03*
X547420Y306862D03*
X544920D03*
X549220Y339687D03*
X535720Y360862D03*
X546758Y360502D03*
X547810Y414472D03*
X549670Y419892D03*
X542870Y438320D03*
X548464Y456534D03*
X548780Y475932D03*
X548550Y480382D03*
X546210Y519642D03*
X541820Y575130D03*
X541722Y568054D03*
X537730Y577440D03*
X547020Y590332D03*
X550320Y583362D03*
X536626Y590500D03*
X537560Y598102D03*
X537648Y1290037D03*
X535058Y1290007D03*
X535148Y1287397D03*
X543660Y1302934D03*
X541100D03*
X538560D03*
X535110Y1292704D03*
Y1295584D03*
Y1298464D03*
X537650Y1292704D03*
X540210D03*
X537650Y1298464D03*
Y1295584D03*
X540210Y1298464D03*
Y1295584D03*
X536020Y1302904D03*
X545141Y1357401D03*
X549801D03*
X538737Y1365553D03*
X534737Y1364815D03*
X542947Y1367043D03*
X541475Y1364585D03*
X534737Y1367871D03*
X547471Y1358151D03*
X563482Y40826D03*
X554720Y32862D03*
X565184Y47982D03*
X558058Y46352D03*
X554983Y45312D03*
X553650Y48842D03*
X551470Y79372D03*
X567865Y92656D03*
X559000Y102862D03*
X561000Y98862D03*
X552395Y134340D03*
X566500Y125097D03*
X551231Y122671D03*
X564890Y142173D03*
X555220Y164787D03*
X555545Y156462D03*
X555195Y184862D03*
Y171862D03*
X554872Y196635D03*
X559400Y201162D03*
X557248Y198909D03*
X564600Y202662D03*
X552489Y212022D03*
X553402Y231292D03*
X552089Y253202D03*
Y257202D03*
X562461Y272161D03*
X561324Y301149D03*
X566730Y300992D03*
X555520Y309827D03*
X563790Y331846D03*
X561290D03*
X558790D03*
X562200Y419412D03*
X559300Y414112D03*
X559730Y434772D03*
X557829Y454479D03*
X558220Y459362D03*
X563281Y543113D03*
X563700Y538477D03*
X560640Y540613D03*
X566140Y554972D03*
Y551472D03*
X559927Y548457D03*
X556820Y570462D03*
X557430Y583572D03*
X566510Y1352217D03*
X554837Y1359315D03*
X557037Y1363715D03*
Y1357915D03*
Y1360815D03*
X554937Y1362315D03*
X552771Y1361045D03*
Y1363945D03*
X552131Y1358151D03*
X555057Y1449395D03*
X572500Y32862D03*
X568500D03*
X581500Y41862D03*
X573190Y42912D03*
X567507Y45869D03*
X575330Y47672D03*
X570208Y47982D03*
X579930Y72052D03*
X577300Y66682D03*
X577880Y75442D03*
X570150Y102862D03*
X579080Y119402D03*
X573360Y140532D03*
X573115Y161232D03*
X569470Y171702D03*
X581120Y155062D03*
X568245Y167112D03*
X579481Y198378D03*
X579170Y190092D03*
X579481Y194378D03*
Y206378D03*
X578450Y218562D03*
X579245Y221362D03*
X567730Y225362D03*
X578390D03*
X567730Y221362D03*
X581755Y236978D03*
X575359Y265132D03*
X582510Y296657D03*
X577676Y300268D03*
X577480Y303822D03*
X582510Y304052D03*
Y311571D03*
X570440Y331930D03*
X567630Y331958D03*
X574800Y322462D03*
X571830Y348772D03*
X572360Y351962D03*
X571720Y381862D03*
X575050Y383602D03*
X577720Y381862D03*
X574491Y376549D03*
X580370Y383670D03*
X581090Y426970D03*
X571930Y421232D03*
X571110Y442656D03*
X569490Y437600D03*
X571110Y446706D03*
X567320Y454962D03*
Y459962D03*
Y457462D03*
X577220Y449462D03*
X578920Y466462D03*
X583045Y488212D03*
X583220Y493212D03*
X568840Y501046D03*
X584173Y498422D03*
X568520Y504162D03*
Y506662D03*
X577470Y505592D03*
X578925Y516846D03*
X571627Y548124D03*
X569050Y578292D03*
X572057Y577242D03*
X571555Y1352487D03*
X570645Y1361358D03*
X576220Y1423862D03*
X571620Y1424492D03*
X584950Y54842D03*
X586260Y52222D03*
X599800Y43152D03*
X597955Y48047D03*
X593369Y45682D03*
X586600Y60602D03*
X590680Y83591D03*
X592307Y94262D03*
X597287D03*
X594720Y97220D03*
X588245Y132142D03*
X598410Y124102D03*
X598390Y126802D03*
X589690Y161732D03*
X592220Y173862D03*
X596795Y179287D03*
X590281Y180698D03*
X599720Y184887D03*
X593220D03*
X584795Y233362D03*
X591310Y219582D03*
X592220Y249362D03*
X595415Y246515D03*
X591727Y285862D03*
X593763Y293999D03*
X588850Y291622D03*
X599620Y314762D03*
X595520Y314862D03*
X583820Y314662D03*
X590820Y330962D03*
X590720Y327862D03*
Y324582D03*
X590470Y319192D03*
X593120Y342782D03*
X583685Y363271D03*
X586185D03*
X586070Y352302D03*
X591839Y426112D03*
X595380Y416660D03*
X591720Y433937D03*
X595520Y439762D03*
X597220Y458688D03*
X599080Y448062D03*
X584100Y477952D03*
X592520Y467662D03*
X590210Y484132D03*
X599645Y479862D03*
X598661Y486922D03*
X587100Y493842D03*
X592400Y479162D03*
X591070Y504900D03*
X594090Y501957D03*
X587100Y496342D03*
X591425Y522337D03*
X591500Y516862D03*
X596880Y534812D03*
X592340Y744624D03*
X598693Y742072D03*
X611810Y34400D03*
X612822Y43232D03*
X606880Y44682D03*
X614400Y46012D03*
X603063Y48023D03*
X606020Y84562D03*
X615220Y76862D03*
X615170Y73812D03*
X601220Y73862D03*
Y76862D03*
X603720Y98362D03*
X608620Y94162D03*
X617585Y97257D03*
X613020Y94162D03*
X617409D03*
X603880Y93902D03*
X600220Y96862D03*
X614384Y119342D03*
X606040Y153432D03*
X606190Y144002D03*
X602580Y151052D03*
X603019Y146399D03*
X615573Y179484D03*
X615572Y176442D03*
X611381Y200378D03*
Y209878D03*
X614200Y265792D03*
X605350Y293092D03*
X605870Y298172D03*
X605560Y303372D03*
X607590Y314732D03*
X609040Y317282D03*
X615635Y317637D03*
X614130Y328762D03*
X605305Y331162D03*
X615180Y336812D03*
X605898Y372984D03*
X609690Y402812D03*
X605220Y416362D03*
X610720Y436362D03*
X600800Y430900D03*
X614220Y436362D03*
X610720Y442862D03*
X614220D03*
Y447862D03*
X602910Y461862D03*
X610720Y457862D03*
X614220D03*
X610720Y452862D03*
X604360Y452120D03*
X614220Y467862D03*
Y472862D03*
Y477862D03*
X605469Y467562D03*
X610720Y462862D03*
X614220D03*
X601220Y486922D03*
X600645Y504362D03*
X606200Y510862D03*
X611870Y512560D03*
X606220Y517762D03*
X607328Y537481D03*
X610797Y537528D03*
X607720Y550862D03*
X610720D03*
X613220Y654662D03*
X603276Y741375D03*
X600460Y744912D03*
X613047Y741492D03*
X602768Y758385D03*
X616675Y31777D03*
X624633Y49193D03*
X629820Y42562D03*
Y45062D03*
X619562Y49193D03*
X624140Y46672D03*
X622271Y44782D03*
X629000Y67362D03*
X628590Y58622D03*
X622271Y57952D03*
X623300Y95762D03*
X620540Y100112D03*
X632300Y104472D03*
X626699Y119182D03*
X630951D03*
X631290Y153702D03*
X615970Y161522D03*
X628195Y175914D03*
X628194Y172872D03*
X628730Y216472D03*
X631730D03*
X628730Y220472D03*
Y224472D03*
X631730Y220472D03*
Y224472D03*
X622730Y230362D03*
X630795Y236862D03*
X618470Y265732D03*
X629564Y253127D03*
X621060Y271066D03*
X633150Y301457D03*
X627950Y298897D03*
X627600Y309134D03*
X632143Y306575D03*
X630220Y314362D03*
X623365Y316742D03*
X631146Y317768D03*
X619474Y331162D03*
X619100Y374638D03*
X621720Y373362D03*
X622490Y402162D03*
X628500Y402362D03*
X624220Y411362D03*
X629220D03*
X623220Y426362D03*
X625500Y421362D03*
X629220D03*
Y426362D03*
X628900Y431050D03*
X625620Y447862D03*
X625900Y431050D03*
X625620Y442862D03*
X629220D03*
X622220D03*
X617220Y436362D03*
X622220Y452862D03*
Y447862D03*
X629220Y457862D03*
X626400Y462812D03*
X625620Y457862D03*
X622220D03*
X629220Y452862D03*
X625620D03*
X629220Y447862D03*
X626390Y467882D03*
X626210Y478002D03*
X626310Y472902D03*
X629220Y462862D03*
X622220D03*
X622520Y467862D03*
X629220Y487310D03*
X622860D03*
X626720Y482880D03*
X623670Y507862D03*
X629480Y508862D03*
X633000Y508700D03*
X629920Y516652D03*
X623000Y546900D03*
X629220Y643462D03*
X626720D03*
X617252Y739354D03*
X623497Y748235D03*
X626017Y745083D03*
X620870Y762072D03*
X617940Y763552D03*
X630417Y757135D03*
X628970Y1670880D03*
X637220Y31462D03*
X643880Y42142D03*
X647447Y46322D03*
X641200Y46762D03*
X638500Y57362D03*
X635000D03*
X637000Y68142D03*
X634500Y73422D03*
X645330Y77132D03*
Y72972D03*
X640220Y85542D03*
X634690D03*
X647220Y96929D03*
X639901Y103462D03*
X640000Y108542D03*
X639970Y113892D03*
X640130Y166362D03*
X643170Y171362D03*
X649870Y181942D03*
X645263Y235689D03*
X640295Y234237D03*
X645109Y249202D03*
Y260202D03*
X643800Y294327D03*
Y298297D03*
Y306547D03*
Y302247D03*
X645990Y314482D03*
X643800Y310962D03*
X633350Y314362D03*
X647100Y357372D03*
X636075Y389862D03*
X649075Y389937D03*
X632620Y389862D03*
X645925Y389937D03*
X638700Y400962D03*
X647700Y399162D03*
X643500Y400962D03*
X643940Y411482D03*
X637220Y411362D03*
X644220Y426362D03*
X640720Y418862D03*
X644220Y421362D03*
X637220Y416362D03*
Y426362D03*
X637195Y421362D03*
X647420Y434162D03*
X640720Y431362D03*
X644000Y438862D03*
X644220Y431362D03*
X638250Y439250D03*
X637220Y431362D03*
X644220Y452862D03*
X640820Y457902D03*
X637220Y452862D03*
X640720D03*
X640920Y447862D03*
X644220D03*
X637195Y457862D03*
X637220Y467862D03*
Y472862D03*
Y477862D03*
X644220D03*
Y462862D03*
X641235Y477377D03*
X640798Y472934D03*
X637220Y462862D03*
X640820Y467862D03*
X640620Y483422D03*
X642580Y508172D03*
X645220Y504362D03*
X646815Y517974D03*
X648296Y528255D03*
X637020Y522362D03*
X642630Y517870D03*
X640130D03*
X633147Y758595D03*
X647725Y1643719D03*
X643725Y1643467D03*
X648225Y1658482D03*
X642725Y1658562D03*
X635410Y1664220D03*
X637540Y1669480D03*
X636702Y1677610D03*
X645725Y1691182D03*
X640725Y1691452D03*
X650725Y1690682D03*
X646225Y1708169D03*
X642225Y1708457D03*
X648220Y1716912D03*
X636160Y1710662D03*
X639745Y1722362D03*
Y1718362D03*
X648220Y1722921D03*
X651943Y33535D03*
X663543Y43328D03*
X656950Y59012D03*
X651680Y73812D03*
X656500Y69662D03*
X661587D03*
X661600Y75562D03*
X657165Y79131D03*
X656426Y75431D03*
X652320Y123362D03*
X662498Y124960D03*
X650790Y149871D03*
Y140699D03*
X662880Y149912D03*
Y146912D03*
X651730Y177212D03*
X662560Y214152D03*
X662780Y210362D03*
Y205362D03*
Y207862D03*
X659880Y210762D03*
Y205762D03*
Y208262D03*
X650705Y270947D03*
X662891Y357442D03*
X662680Y354362D03*
X651520Y378662D03*
X658720Y399862D03*
X652000Y402362D03*
X653100Y407862D03*
X655820Y452662D03*
X655800Y461432D03*
X652195Y457862D03*
X655820Y467662D03*
X663000Y489500D03*
X663014Y493860D03*
X655220Y486862D03*
X661865Y505334D03*
X663720Y523806D03*
X665990Y517131D03*
X661220Y526862D03*
X650794Y515039D03*
X652577Y1000775D03*
X653690Y1392362D03*
X653761Y1396300D03*
X663187Y1395170D03*
Y1397720D03*
X666303Y1403476D03*
X663687Y1407279D03*
X654540Y1427605D03*
Y1424205D03*
X661100Y1451012D03*
X662660Y1548120D03*
X663410Y1553982D03*
X664590Y1631620D03*
X663097Y1642667D03*
X651725Y1643397D03*
X656725Y1660769D03*
X663118Y1655557D03*
X663043Y1651557D03*
X663145Y1672862D03*
Y1668862D03*
X653420Y1698662D03*
X663645Y1722862D03*
X680200Y39062D03*
X677560Y40572D03*
X672250Y40812D03*
X666943Y43328D03*
X682290Y46822D03*
X670612Y47264D03*
X674012D03*
X674035Y74522D03*
X678050Y58157D03*
X673987Y87662D03*
X677820Y89462D03*
X680578Y75992D03*
X674540Y80652D03*
X670800Y85932D03*
X667940Y80142D03*
X671320Y91192D03*
X677790Y104880D03*
X673720Y110362D03*
X674145Y113487D03*
X677978Y119668D03*
Y115668D03*
X675560Y117120D03*
X668300Y132400D03*
X665650Y147692D03*
X673713Y237725D03*
X674731Y359924D03*
X680600Y364282D03*
X683100Y369550D03*
X673220Y388362D03*
X675295Y399862D03*
X670720D03*
X668695Y408362D03*
Y404262D03*
X665870Y433942D03*
X675220Y508862D03*
X680220Y495887D03*
X670220Y503837D03*
X680220Y508862D03*
X675220Y521862D03*
X670720D03*
Y516862D03*
X680220Y530362D03*
X673340Y530922D03*
X673617Y744735D03*
X669700Y746626D03*
X677887Y742121D03*
X669778Y759929D03*
X670037Y1336396D03*
X664987D03*
X667487D03*
X664987Y1338896D03*
X667487D03*
X670037D03*
Y1333896D03*
X664987D03*
X667487D03*
X664987Y1348896D03*
X667487D03*
X664987Y1346396D03*
X667487D03*
X664987Y1343896D03*
Y1341396D03*
X667487D03*
Y1343896D03*
X670037Y1341396D03*
Y1343896D03*
Y1346396D03*
Y1348896D03*
X679881Y1399280D03*
X673477Y1409386D03*
X669477Y1406694D03*
X677619Y1408887D03*
X675876Y1406619D03*
X669477Y1409415D03*
X674149Y1434149D03*
X671149D03*
X668649D03*
X674149Y1426149D03*
Y1431149D03*
Y1428649D03*
X671149Y1426149D03*
X668649D03*
X671149Y1431149D03*
X668649Y1428649D03*
Y1431149D03*
X671149Y1428649D03*
X677319Y1428359D03*
Y1433359D03*
Y1430859D03*
X682160Y1548040D03*
X665410Y1548180D03*
X679207Y1560482D03*
X678877Y1566798D03*
X678621Y1571072D03*
X678610Y1582154D03*
X666560Y1581000D03*
X678619Y1579070D03*
X666600Y1584900D03*
X678900Y1595400D03*
X678771Y1585945D03*
X666700Y1595500D03*
X678900Y1589800D03*
X666700Y1591900D03*
X678900Y1592600D03*
X666700Y1588500D03*
X679640Y1617520D03*
Y1614000D03*
X679270Y1604040D03*
X675710Y1620320D03*
X673420Y1650057D03*
X671290Y1646320D03*
X668695Y1662235D03*
X671610Y1673792D03*
X671620Y1668303D03*
X677940Y1670110D03*
X678490Y1695660D03*
X674195Y1712362D03*
X675120Y1716242D03*
X674195Y1728362D03*
X672270Y1721612D03*
X687120Y39632D03*
X692289Y40633D03*
X689940Y38952D03*
X696800Y42108D03*
X696838Y47940D03*
X683440Y42832D03*
X687344Y46940D03*
X692389Y46439D03*
X694751Y70212D03*
X690027Y70142D03*
X685780Y70022D03*
X699475Y69982D03*
X685968Y58157D03*
X694400D03*
X681980D03*
X690510Y59132D03*
X696700Y72462D03*
X692389Y72692D03*
X687664Y73202D03*
X696370Y78512D03*
X696727Y81552D03*
Y84052D03*
X681053Y104668D03*
X695720Y102162D03*
X694220Y104862D03*
X688019Y109845D03*
X687030Y113090D03*
X687034Y115896D03*
X697615Y123697D03*
X687238Y171071D03*
X685600Y364282D03*
X690600D03*
X695600D03*
X683500Y381200D03*
X685210Y388852D03*
X694920Y388797D03*
X687500Y399402D03*
X692330Y388751D03*
X685220Y391652D03*
X692402Y391250D03*
X695220Y399862D03*
X685270Y408362D03*
Y404262D03*
X692400Y404682D03*
X683320Y490662D03*
X685220Y495887D03*
X690580Y482992D03*
X694510Y482942D03*
X686120Y481862D03*
X695220Y495887D03*
X690220D03*
X695220Y508862D03*
X685220D03*
X690220Y506362D03*
X685220Y503837D03*
X690220Y508882D03*
X690330Y503530D03*
X695257Y503847D03*
X695220Y516852D03*
X685220D03*
X690220Y519662D03*
X695220D03*
X689720Y530862D03*
X695220Y530662D03*
X683457Y745175D03*
X696810Y1300162D03*
X692280Y1302532D03*
X684555Y1338896D03*
X689605Y1336396D03*
Y1338896D03*
X687105Y1336396D03*
X684555D03*
X687105Y1338896D03*
X689605Y1333896D03*
X687105D03*
X684555D03*
X689605Y1348896D03*
X687105D03*
X689605Y1346396D03*
X687105D03*
X684555Y1341396D03*
Y1343896D03*
Y1346396D03*
Y1348896D03*
X689605Y1341396D03*
Y1343896D03*
X687105Y1341396D03*
Y1343896D03*
X684541Y1399280D03*
X682211Y1400030D03*
X686871D03*
X691777Y1405594D03*
Y1399794D03*
X689577Y1401194D03*
X687511Y1402924D03*
X691777Y1402694D03*
X689677Y1404194D03*
X687511Y1405824D03*
X694596Y1396198D03*
X694129Y1420283D03*
X696754Y1419809D03*
X691129Y1420283D03*
X681899Y1434049D03*
Y1426049D03*
Y1431049D03*
Y1428549D03*
X694129Y1423303D03*
X691129D03*
X696694Y1427949D03*
Y1425449D03*
Y1430449D03*
X696784Y1422614D03*
X683930Y1552562D03*
Y1555062D03*
Y1557562D03*
X692100Y1567190D03*
X692026Y1580490D03*
X697197Y1640667D03*
X697122Y1636667D03*
X689200Y1648843D03*
X686220Y1640667D03*
X697595Y1666862D03*
X687045Y1673362D03*
X706370Y46782D03*
X701838Y42202D03*
Y47940D03*
X703900Y72112D03*
X701400D03*
X713000Y69662D03*
X697720Y58162D03*
X710200Y69662D03*
X706867Y58197D03*
X703100Y58157D03*
X712500Y79862D03*
X710486Y77695D03*
X700500Y74862D03*
X698710Y86035D03*
X705390Y85792D03*
X703000Y84862D03*
X706720Y100462D03*
X699220Y102162D03*
X702720D03*
X701220Y104862D03*
X697720D03*
X712733Y117488D03*
Y114588D03*
X712290Y106722D03*
X712340Y128093D03*
X700600Y125309D03*
X707008Y125804D03*
X705800Y167788D03*
Y171188D03*
X704770Y182999D03*
Y179599D03*
Y194810D03*
Y191410D03*
Y218432D03*
Y206621D03*
Y215032D03*
Y203221D03*
X700600Y364282D03*
X705600D03*
X710600D03*
X709000Y354000D03*
X715600Y363900D03*
X705700Y361400D03*
X709400Y378200D03*
X713220Y378362D03*
X711200Y396500D03*
X707220Y399362D03*
X709160Y386730D03*
X713220Y388362D03*
X707400Y396200D03*
X713220Y399862D03*
X705195Y408362D03*
Y404262D03*
X705780Y411022D03*
X712770Y406822D03*
X705720Y488862D03*
X703220Y490362D03*
X705720Y484862D03*
X711220Y503842D03*
X705220D03*
Y508862D03*
X711220Y508882D03*
X710720Y521362D03*
X705220D03*
X701757Y521324D03*
X705220Y530362D03*
X710940Y591172D03*
X698602Y580536D03*
X705240Y594020D03*
X702740D03*
X712060Y638542D03*
X708680Y638812D03*
X708310Y646032D03*
X704320Y645262D03*
X704000Y740862D03*
X700500Y745862D03*
X703545Y745907D03*
X711720Y1286162D03*
X707720Y1290162D03*
X705720Y1286662D03*
X704795Y1294559D03*
X707320Y1301162D03*
X708137Y1336396D03*
Y1338896D03*
X703087Y1336396D03*
X705587D03*
Y1338896D03*
X703087D03*
X708137Y1333896D03*
X705587D03*
X703087D03*
Y1346396D03*
X705587D03*
X703087Y1348896D03*
X705587D03*
X708137Y1341396D03*
Y1343896D03*
X705587Y1341396D03*
X703087D03*
Y1343896D03*
X705587D03*
X708137Y1348896D03*
Y1346396D03*
X701330Y1395195D03*
Y1397695D03*
X704446Y1403476D03*
X701830Y1407326D03*
X711620Y1409386D03*
X707620Y1406694D03*
Y1409660D03*
X699754Y1419809D03*
X699694Y1427949D03*
Y1425449D03*
Y1430449D03*
X699784Y1422614D03*
X712222Y1570703D03*
X702112Y1571683D03*
Y1575683D03*
Y1579683D03*
X711102Y1575683D03*
X714162Y1574333D03*
X713052Y1579683D03*
X712582Y1584843D03*
X704497Y1598927D03*
X702112Y1587683D03*
Y1591683D03*
X713102Y1601307D03*
X715775Y1599024D03*
X714380Y1589960D03*
X702112Y1595683D03*
X712512Y1596338D03*
X711350Y1590720D03*
X711780Y1614590D03*
X704370Y1604580D03*
X706103Y1617107D03*
X708857Y1613462D03*
X710570Y1629890D03*
X708830Y1623115D03*
X705516Y1620296D03*
X710540Y1636070D03*
X708999Y1646762D03*
X703719Y1646768D03*
X697595Y1662862D03*
X700460Y1660918D03*
X709678Y1658485D03*
X697730Y1677460D03*
X704759Y1677001D03*
X723041Y-19800D03*
Y-23200D03*
X724620Y40062D03*
X728720Y43562D03*
X719820Y45862D03*
X717320Y44062D03*
X729293Y58062D03*
X724644Y58362D03*
X719949Y58862D03*
X715990Y69662D03*
X725740Y69580D03*
X721990Y69762D03*
X718900Y69662D03*
X727700Y60562D03*
X728591Y71960D03*
X722415Y77862D03*
X718425Y77882D03*
X728090Y75132D03*
X719100Y85262D03*
X727518Y90984D03*
X715933Y117488D03*
Y114588D03*
X729933Y108388D03*
X728733Y132088D03*
Y129288D03*
X720433Y135088D03*
X717433D03*
X728733Y126388D03*
X719933Y124488D03*
X723133D03*
X715940Y157362D03*
X718213Y159241D03*
X720633Y160788D03*
X716698Y185687D03*
Y173687D03*
Y177087D03*
Y197187D03*
Y200587D03*
Y189087D03*
Y209021D03*
Y212421D03*
X717020Y220862D03*
X719720Y220142D03*
X722500Y365500D03*
X724897Y353887D03*
X721989Y351234D03*
X727000Y365500D03*
X731400D03*
X722500Y374100D03*
X727000D03*
X731400Y375000D03*
X718720Y381892D03*
X728220Y388362D03*
X723195Y408362D03*
Y404262D03*
X725220Y399862D03*
X723220Y508882D03*
X717220D03*
X729220D03*
Y503842D03*
X723220D03*
X717220D03*
X714000Y496132D03*
X723120Y525362D03*
X728220Y521362D03*
X717220D03*
X717296Y525407D03*
X723220Y516852D03*
X729220D03*
X717220D03*
X729212Y531700D03*
X729328Y583076D03*
X729295Y586113D03*
X725207Y579371D03*
X722707D03*
X715860Y585540D03*
X714320Y597462D03*
X723450Y597072D03*
X720240Y598292D03*
X715420Y639162D03*
X719190Y646642D03*
X717720Y643262D03*
X715220D03*
X723340Y642922D03*
X714087Y745865D03*
X720697Y765862D03*
X723460Y1245632D03*
X714720Y1286162D03*
X723054Y1333896D03*
X725604D03*
X728104D03*
X725604Y1338896D03*
X723054Y1336396D03*
X725604D03*
X728104Y1338896D03*
Y1336396D03*
X723054Y1338896D03*
X725604Y1346396D03*
X728104D03*
X725604Y1348896D03*
X728104D03*
X725604Y1343896D03*
Y1341396D03*
X728104Y1343896D03*
Y1341396D03*
X723054Y1348896D03*
Y1346396D03*
Y1343896D03*
Y1341396D03*
X725654Y1405824D03*
Y1402924D03*
X727720Y1401194D03*
X727820Y1404194D03*
X718024Y1399280D03*
X722684D03*
X720354Y1400030D03*
X725014D03*
X715762Y1408887D03*
X714019Y1406619D03*
X717300Y1547370D03*
X715792Y1567461D03*
X720370Y1566910D03*
X723520Y1561604D03*
X724712Y1566820D03*
X716612Y1584635D03*
X717152Y1570093D03*
X728977Y1574453D03*
X717402Y1574433D03*
X724465Y1580092D03*
X722465Y1582092D03*
X726465D03*
X723942Y1574123D03*
X724465Y1590950D03*
X722465Y1588950D03*
X726465D03*
X729052Y1602518D03*
X726092Y1598483D03*
X720987Y1599568D03*
X723542Y1612702D03*
X721488Y1610945D03*
X725910Y1611900D03*
X716688Y1610055D03*
X719168Y1612016D03*
X718195Y1647300D03*
X714203Y1642926D03*
X729150Y1641690D03*
X726810Y1652430D03*
X714071Y1663842D03*
X722630Y1655740D03*
X724500Y1680400D03*
X718758Y1673800D03*
X745900Y40362D03*
X733314Y40862D03*
X740100Y41162D03*
X746100Y46262D03*
X736620Y45262D03*
X745474Y57932D03*
X733642Y58062D03*
X741377Y57932D03*
X737595D03*
X732793Y71436D03*
X736193D03*
X742620Y71762D03*
X735880Y60662D03*
X740819Y82362D03*
X736720Y101662D03*
X745035Y94632D03*
X735770Y94988D03*
X739823Y91052D03*
X741308Y108742D03*
X738600Y136600D03*
X736060Y145532D03*
X740220Y145362D03*
X745725Y167537D03*
X732720Y231362D03*
X734220Y238362D03*
X744247Y312598D03*
X741800Y363200D03*
X742090Y356082D03*
X735600Y351400D03*
X735800Y365500D03*
X732700Y351500D03*
X740200Y375100D03*
X736220Y380787D03*
X742720Y380262D03*
X735800Y375000D03*
X738220Y388362D03*
X742160Y396452D03*
X738220Y383862D03*
X745720Y399862D03*
X735220Y410842D03*
X735745Y408362D03*
Y404262D03*
X733720Y399862D03*
X743980Y443482D03*
X740740Y473822D03*
X741420Y494162D03*
X747600Y506592D03*
X735220Y508862D03*
X745220Y503842D03*
X735220D03*
X735430Y516862D03*
X745220Y522362D03*
Y516852D03*
X730220Y523362D03*
X740840Y521982D03*
X735173Y521362D03*
X736480Y531722D03*
X738980D03*
X733922Y531712D03*
X733117Y580071D03*
Y582571D03*
X733134Y585672D03*
X736710Y603842D03*
Y607242D03*
X735620Y613862D03*
X730690Y655532D03*
X744538Y746524D03*
X737609Y744282D03*
X730889Y746834D03*
X740820Y741762D03*
X729920Y1405594D03*
X732226Y1396212D03*
X729920Y1399794D03*
Y1402694D03*
X733336Y1568341D03*
Y1565341D03*
Y1559341D03*
Y1562341D03*
X730336Y1559341D03*
Y1562341D03*
X745336D03*
Y1559341D03*
Y1565341D03*
Y1568341D03*
X742336Y1562341D03*
Y1559341D03*
Y1565341D03*
Y1568341D03*
X739336Y1562341D03*
Y1559341D03*
Y1565341D03*
Y1568341D03*
X736336D03*
Y1565341D03*
Y1559341D03*
Y1562341D03*
X733336Y1574341D03*
Y1571341D03*
X745336Y1574341D03*
Y1571341D03*
X742336Y1574341D03*
Y1571341D03*
X739336Y1574341D03*
Y1571341D03*
X736336D03*
Y1574341D03*
X730282Y1580391D03*
X741382Y1585251D03*
Y1580121D03*
X735882Y1580391D03*
X730282Y1590651D03*
Y1585521D03*
X735882Y1590651D03*
X741382Y1590691D03*
X732504Y1600321D03*
Y1597321D03*
X744504D03*
Y1600321D03*
X741504Y1597321D03*
Y1600321D03*
X735504Y1597321D03*
Y1600321D03*
X738504Y1597321D03*
Y1600321D03*
X744504Y1609521D03*
Y1612521D03*
X741504Y1609521D03*
X738504D03*
X735504D03*
X741504Y1612521D03*
X738504D03*
X735504D03*
X732504Y1603321D03*
Y1606321D03*
X744504Y1603321D03*
Y1606321D03*
X741504Y1603321D03*
Y1606321D03*
X738504Y1603321D03*
X735504D03*
X738504Y1606321D03*
X735504D03*
X735300Y1648760D03*
X737080Y1655820D03*
X735080Y1662980D03*
X740840Y1655590D03*
X732705Y1669450D03*
X754620Y51602D03*
X758620D03*
X749477Y57932D03*
X755700Y59942D03*
Y62442D03*
X758200Y59942D03*
Y62442D03*
X760700Y59942D03*
Y62442D03*
X747487Y71429D03*
X757693Y100653D03*
Y96423D03*
X750700Y106642D03*
X754800Y97082D03*
X750033Y92888D03*
Y89988D03*
X757340Y92562D03*
X748033Y116288D03*
X747230Y108572D03*
X760390Y111810D03*
X751220Y137864D03*
X747200Y251500D03*
X757150Y280592D03*
X758720Y283262D03*
X759920Y280562D03*
X758412Y298790D03*
X755305Y298847D03*
X748820Y284562D03*
X758390Y295450D03*
X748498Y309640D03*
X759637Y311585D03*
X757936Y303908D03*
X760670Y317432D03*
X747554Y384962D03*
X757430Y408212D03*
X760469Y442647D03*
X750290Y462162D03*
X757365Y459862D03*
X752500Y495762D03*
X757238Y483862D03*
X756642Y496522D03*
Y501744D03*
X751220Y522362D03*
Y516852D03*
X759790Y525522D03*
X755940Y516862D03*
X756650Y526072D03*
X761710Y517651D03*
X757020Y530462D03*
X759820D03*
X754220D03*
X762345Y1284542D03*
Y1287542D03*
Y1290542D03*
X762205Y1293272D03*
X757720Y1375462D03*
Y1384062D03*
X758020Y1397862D03*
X758420Y1406862D03*
X758120Y1414762D03*
X755420Y1426262D03*
Y1422862D03*
X748336Y1562341D03*
Y1559341D03*
Y1565341D03*
Y1568341D03*
X751336D03*
Y1565341D03*
Y1559341D03*
Y1562341D03*
X748336Y1574341D03*
Y1571341D03*
X760112Y1579183D03*
X749612Y1579023D03*
X749652Y1586407D03*
X760152Y1583183D03*
X749612Y1583023D03*
X760112Y1592183D03*
Y1587183D03*
X747504Y1600321D03*
X749662Y1590733D03*
X749612Y1594683D03*
X758360Y1589661D03*
X747504Y1609521D03*
Y1612521D03*
X750504D03*
Y1609521D03*
X747504Y1603321D03*
Y1606321D03*
X761716Y1661194D03*
X751620Y1674312D03*
X759859Y1686090D03*
X759359Y1729520D03*
X752875Y1726670D03*
X774059Y68912D03*
X773420Y143462D03*
X772328Y153728D03*
X771426Y158026D03*
X766320Y264892D03*
X763320D03*
X771630Y258102D03*
X762420Y280562D03*
X777420Y277962D03*
X769789Y296231D03*
X777467Y296315D03*
X769860Y302462D03*
X771377Y314139D03*
X771490Y354942D03*
X768490D03*
X777420Y354962D03*
X774490Y354942D03*
X765000Y354862D03*
X771960Y375162D03*
X767960Y369662D03*
X776000D03*
X764000D03*
X766195Y393212D03*
X773245Y398212D03*
X766195Y403212D03*
Y413212D03*
X773245Y403212D03*
Y408212D03*
X768910Y403260D03*
X771050Y416940D03*
X766195Y423212D03*
Y428212D03*
X768701Y418662D03*
X774982Y446908D03*
X772365Y454862D03*
X768720Y459862D03*
X765315Y454862D03*
Y459862D03*
X772365D03*
X765360Y475412D03*
X765335Y469552D03*
X772364Y475062D03*
X772365Y469862D03*
X765315Y479862D03*
X772365Y488862D03*
X776170Y493422D03*
X766510Y493452D03*
X765386Y483572D03*
X773530Y507062D03*
X765810Y506342D03*
X769745Y502600D03*
X775378Y502502D03*
X765521Y525364D03*
X769220Y530362D03*
X765720D03*
X777020D03*
X772020Y746562D03*
X774384Y744088D03*
X762562Y746444D03*
X769921Y742095D03*
X767421D03*
X764921D03*
X769337Y760775D03*
X762617Y758885D03*
X765345Y1284542D03*
X768335Y1284612D03*
X765345Y1287542D03*
Y1290542D03*
X768335Y1287612D03*
Y1290612D03*
X765205Y1293272D03*
X768195Y1293342D03*
X778005Y1294092D03*
X768520Y1384062D03*
Y1375462D03*
X768620Y1397262D03*
X775375Y1403561D03*
X767820Y1414762D03*
X763152Y1581893D03*
Y1577893D03*
Y1573793D03*
X773952Y1580493D03*
X768714Y1571203D03*
X769452Y1584393D03*
X770252Y1587268D03*
X763152Y1590893D03*
Y1594893D03*
X774052Y1590293D03*
X776922Y1590444D03*
X776052Y1611893D03*
X764920Y1695347D03*
X766880Y1689020D03*
X766603Y1721797D03*
X785180Y120947D03*
X792680D03*
X790180D03*
X787680D03*
X783940Y118637D03*
X786440D03*
X788940D03*
X781440D03*
X782553Y150031D03*
Y152531D03*
X779893Y147521D03*
Y150021D03*
X780820Y278262D03*
X785135Y274822D03*
X785200Y271400D03*
X794057Y301569D03*
X794220Y296062D03*
X785220Y284762D03*
X792943Y312642D03*
X784415Y313734D03*
X793896Y309026D03*
X793820Y304962D03*
X779120Y303410D03*
Y308755D03*
X785000Y355000D03*
X779920Y354962D03*
X782420D03*
X790120Y354862D03*
X792620D03*
X787600Y354900D03*
X795520Y393462D03*
X791075Y388000D03*
X781195Y393212D03*
X781320Y398212D03*
X787720Y408362D03*
X781195Y413212D03*
Y423212D03*
X785560Y417902D03*
X788120Y422942D03*
X791040Y422892D03*
X793660Y422842D03*
X785720Y427862D03*
X789230Y414942D03*
X780020Y441437D03*
Y445287D03*
X784730Y432682D03*
X787320Y444862D03*
Y439862D03*
X791582Y435352D03*
X781205Y454402D03*
X780315Y459862D03*
X787320Y454862D03*
Y449862D03*
Y459862D03*
X787360Y469862D03*
X786220Y464862D03*
X796315Y469290D03*
X780315Y464862D03*
X783340Y474802D03*
X782690Y488862D03*
X793220Y493362D03*
X781170Y493422D03*
X785800Y482762D03*
X793875Y483262D03*
X778670Y493422D03*
X783600Y502462D03*
X783450Y522462D03*
X783400Y511902D03*
X789720Y589862D03*
X785220Y581362D03*
X789720Y587362D03*
X791720Y593862D03*
X793720Y595862D03*
X791969Y618384D03*
X794720Y617862D03*
X783507Y761875D03*
X794157Y761295D03*
X782515Y766702D03*
X791140Y761693D03*
X792045Y1284542D03*
Y1290542D03*
Y1287542D03*
X791905Y1293272D03*
X791260Y1388662D03*
X790380Y1432132D03*
X784352Y1568293D03*
Y1565293D03*
Y1559293D03*
Y1562293D03*
X781352Y1568293D03*
Y1565293D03*
Y1559293D03*
Y1562293D03*
X793352D03*
Y1559293D03*
Y1565293D03*
Y1568293D03*
X790352Y1562293D03*
Y1559293D03*
Y1565293D03*
Y1568293D03*
X787352D03*
Y1565293D03*
Y1559293D03*
Y1562293D03*
X784352Y1574293D03*
Y1571293D03*
X781352Y1574293D03*
Y1571293D03*
X793352Y1574293D03*
Y1571293D03*
X790352Y1574293D03*
Y1571293D03*
X787352D03*
Y1574293D03*
X788079Y1580393D03*
X782479D03*
X793579D03*
X788079Y1590653D03*
X782479D03*
Y1585523D03*
X793579Y1590653D03*
Y1585523D03*
X785052Y1600693D03*
Y1597693D03*
X782052D03*
Y1600693D03*
X794052D03*
X788052D03*
X791052D03*
X794052Y1597693D03*
X788052D03*
X791052D03*
X785052Y1607793D03*
X782052D03*
X779052D03*
X785052Y1611893D03*
X782052D03*
X779052D03*
X794052Y1607793D03*
X791052D03*
X788052D03*
X797052Y1611893D03*
X794052D03*
X788052D03*
X791052D03*
X785052Y1603693D03*
X782052D03*
X794052D03*
X788052D03*
X791052D03*
X808800Y267900D03*
X810920Y280062D03*
X798204Y279146D03*
X797924Y298358D03*
X806450Y310362D03*
X803620Y302962D03*
X805870Y304812D03*
X799720Y300462D03*
X795920Y312662D03*
X803280Y354982D03*
X800646Y354921D03*
X795220Y354862D03*
X806000Y360600D03*
X798400D03*
X805910Y355012D03*
X797900Y354800D03*
X795520Y398212D03*
X800352Y408389D03*
X803120Y428762D03*
X797720Y428412D03*
X798370Y439932D03*
X802010Y439940D03*
X802790Y433832D03*
X795320Y439862D03*
X805720Y432902D03*
X801750Y444330D03*
X795320Y444862D03*
X810860Y454862D03*
X802810D03*
X795320D03*
Y449862D03*
X802810Y464862D03*
Y449862D03*
X810860Y459862D03*
X802810D03*
X795320D03*
X810860Y449862D03*
X798990Y474862D03*
X802865D03*
X795320Y464862D03*
X810815Y474862D03*
X810860Y464862D03*
X810815Y469862D03*
X807220Y493362D03*
X801940Y485932D03*
X804510Y486122D03*
X809510D03*
X799230Y485922D03*
X812510Y486422D03*
X802790Y495652D03*
X805470Y510522D03*
X807640Y506672D03*
X808100Y509900D03*
X797420Y512503D03*
X805445Y587582D03*
X810720Y586862D03*
X811143Y605265D03*
X807945Y594362D03*
X803220D03*
X797200Y599883D03*
X795720Y614862D03*
X796702Y761195D03*
X810850Y770272D03*
X799577Y760985D03*
X807000Y757562D03*
X798035Y1284612D03*
X795045Y1284542D03*
X798035Y1290612D03*
Y1287612D03*
X795045Y1290542D03*
Y1287542D03*
X797895Y1293342D03*
X794905Y1293272D03*
X806323Y1343076D03*
X812130Y1343022D03*
X809210Y1343062D03*
X804100Y1435010D03*
X800000Y1431100D03*
X799352Y1562293D03*
Y1559293D03*
Y1565293D03*
Y1568293D03*
X796352Y1562293D03*
Y1559293D03*
Y1565293D03*
Y1568293D03*
X799352Y1574293D03*
Y1571293D03*
X796352Y1574293D03*
Y1571293D03*
X804652Y1581793D03*
Y1573793D03*
X812652Y1577793D03*
X801652Y1584539D03*
X812698Y1587047D03*
X804652Y1597793D03*
Y1585993D03*
X799152Y1586507D03*
X804652Y1589793D03*
X797052Y1607793D03*
X804652Y1609793D03*
X827114Y115223D03*
X823114D03*
X814570Y145952D03*
X814531Y139851D03*
X820900Y147112D03*
X815060Y280072D03*
X813490Y273862D03*
X816220Y277162D03*
X813293Y287062D03*
X826300Y311962D03*
X823800D03*
X818000Y378800D03*
X813210Y374292D03*
X815710D03*
X825003Y389012D03*
Y397276D03*
X819220Y397664D03*
X824980Y413260D03*
X819220Y412264D03*
X823600Y421194D03*
X815310Y440100D03*
X816810Y464862D03*
X825100Y468900D03*
X824860Y464862D03*
X816400Y472900D03*
X820720Y493862D03*
X822415Y479600D03*
X821720Y511082D03*
X814305Y499503D03*
X819320Y502347D03*
X821720Y527082D03*
X815650Y516807D03*
X821720Y515082D03*
Y523082D03*
X820220Y586862D03*
X814220Y582530D03*
X823720Y594862D03*
X820470Y595112D03*
X815120Y593582D03*
X820613Y744641D03*
X823589Y746924D03*
X822374Y757039D03*
X814770Y763874D03*
X815789Y1008845D03*
X826090Y1334362D03*
Y1339362D03*
Y1329362D03*
Y1344362D03*
X820920Y1344342D03*
X818420D03*
X823352Y1565293D03*
Y1562293D03*
Y1559293D03*
Y1568293D03*
X826352Y1565293D03*
Y1562293D03*
Y1559293D03*
Y1568293D03*
X823352Y1571293D03*
Y1574293D03*
X826352Y1571293D03*
Y1574293D03*
X824479Y1580393D03*
X815652Y1582570D03*
Y1573793D03*
X813352Y1590893D03*
X812652Y1593793D03*
X824479Y1590653D03*
Y1585523D03*
X824052Y1597693D03*
Y1600693D03*
X827052D03*
Y1597693D03*
X815551Y1593793D03*
X818652Y1590444D03*
X812652Y1605793D03*
X824052Y1611893D03*
Y1607793D03*
Y1603693D03*
X827052Y1611893D03*
Y1607793D03*
Y1603693D03*
X821052Y1611893D03*
Y1607793D03*
X818052Y1611893D03*
X812652Y1601793D03*
X840001Y6800D03*
Y10200D03*
X836779Y68008D03*
X828600Y61752D03*
X839898Y87248D03*
X841584Y94181D03*
X837250Y93221D03*
X839360Y114862D03*
X835114Y115223D03*
X845220Y135862D03*
Y129362D03*
X829114Y147123D03*
X828145Y160362D03*
X838220Y163862D03*
X835220D03*
X837320Y175112D03*
X842720Y181360D03*
X837160Y218212D03*
Y213207D03*
X844526Y204968D03*
X838820Y206872D03*
X837500Y229642D03*
X840063Y285022D03*
X839450Y272662D03*
X835400Y268800D03*
X829620Y280345D03*
X829820Y275045D03*
X840850Y278948D03*
X829720Y292762D03*
X839860Y294702D03*
X827620Y302962D03*
X830417Y311865D03*
X836300Y418800D03*
X832400Y427100D03*
X840400Y418900D03*
X831720Y457700D03*
X839640Y449612D03*
X832700Y446800D03*
X830600Y449200D03*
X838220Y459562D03*
X841200Y456500D03*
X832720Y494862D03*
X829720D03*
X838645Y492862D03*
X830870Y480010D03*
X832590Y512888D03*
X829745Y502082D03*
X832370Y525849D03*
X843287Y527817D03*
X841461Y525849D03*
X840990Y529786D03*
X828009Y587913D03*
X831705Y593877D03*
X829230Y582772D03*
X831530Y651932D03*
X830587Y741205D03*
X833120Y743392D03*
X838587Y766825D03*
X841827Y766795D03*
X837127Y758976D03*
X829420Y758422D03*
X841997Y773085D03*
X838020Y1232432D03*
X832090Y1326862D03*
Y1331862D03*
Y1336862D03*
Y1341862D03*
X829352Y1565293D03*
Y1562293D03*
Y1559293D03*
Y1568293D03*
X832352D03*
Y1565293D03*
Y1559293D03*
Y1562293D03*
X835352Y1568293D03*
Y1565293D03*
Y1559293D03*
Y1562293D03*
X838352Y1568293D03*
Y1565293D03*
Y1559293D03*
Y1562293D03*
X841352Y1568293D03*
Y1565293D03*
Y1559293D03*
Y1562293D03*
X829352Y1574293D03*
Y1571293D03*
X832352D03*
Y1574293D03*
X835352Y1571293D03*
Y1574293D03*
X838352Y1571293D03*
Y1574293D03*
X841352Y1571293D03*
Y1574293D03*
X830079Y1580393D03*
X835579D03*
X843652Y1584539D03*
X833052Y1597693D03*
X836052D03*
X830079Y1590653D03*
X835579D03*
X833052Y1600693D03*
X836052D03*
X835579Y1585523D03*
X830052Y1600693D03*
Y1597693D03*
X841152Y1586507D03*
X833052Y1603693D03*
X836052D03*
X839052Y1611893D03*
X833052Y1607793D03*
Y1611893D03*
X836052Y1607793D03*
Y1611893D03*
X830052D03*
Y1607793D03*
Y1603693D03*
X839052Y1607793D03*
X858629Y60293D03*
X850015Y87341D03*
X843855Y87711D03*
X847472Y94754D03*
X847660Y113962D03*
X853100Y113762D03*
X854100Y132972D03*
X854220Y135862D03*
Y129362D03*
X854200Y138562D03*
X848745Y160187D03*
X848709Y156752D03*
X848360Y182872D03*
X845720Y181362D03*
X855858Y212425D03*
X855933Y215375D03*
X860050Y215310D03*
X847580Y232222D03*
X853828Y269043D03*
X850133Y271049D03*
X861865Y273730D03*
X850093Y286625D03*
X855480Y299692D03*
X856243Y286447D03*
X859920Y308852D03*
X859740Y399081D03*
X846040Y399210D03*
X846490Y422131D03*
X850610Y444352D03*
X851606Y447927D03*
X844210Y455902D03*
X846700Y476900D03*
X855200D03*
X857620Y492862D03*
X858600Y511130D03*
X848620Y509752D03*
X853070Y515447D03*
X857195Y522162D03*
X859888Y593970D03*
X859054Y583752D03*
X845523Y582126D03*
X856520Y751262D03*
X859450Y750462D03*
X844957Y763065D03*
X854620Y1242125D03*
X854237Y1250358D03*
X846652Y1581793D03*
Y1573793D03*
X854652Y1577793D03*
X857652Y1582570D03*
Y1573793D03*
X854777Y1586968D03*
X846652Y1597793D03*
X855352Y1590893D03*
X854652Y1593793D03*
X846652Y1585993D03*
X857551Y1593793D03*
X846652Y1589793D03*
X854652Y1605793D03*
Y1601793D03*
X846652Y1609793D03*
X862930Y70072D03*
X866330D03*
X862452Y151590D03*
X867620Y154362D03*
X871145Y163862D03*
X871580Y183370D03*
X875169Y185113D03*
X864859Y187110D03*
X873200Y194262D03*
X871890Y196740D03*
X877971Y196652D03*
X867528Y231788D03*
X875543Y266447D03*
X867700Y268262D03*
X875543Y269347D03*
X863747Y280870D03*
X867237Y273325D03*
X868552Y285537D03*
X874243Y287047D03*
X877322Y296051D03*
X872320Y304936D03*
X869820D03*
X867320D03*
X864820D03*
X860531Y375826D03*
X870700Y386476D03*
Y398620D03*
Y402581D03*
X868113Y409372D03*
X870513Y414276D03*
X862320Y431462D03*
X863415Y445829D03*
X860574Y445404D03*
X861080Y459742D03*
X870360Y493042D03*
X862620Y507162D03*
X868110Y499142D03*
X865290Y499032D03*
X865810Y521862D03*
X866820Y736562D03*
X863925Y737697D03*
X864680Y751582D03*
X874155Y756993D03*
X864700Y778300D03*
X868352Y1568293D03*
Y1565293D03*
Y1559293D03*
Y1562293D03*
X865352Y1568293D03*
Y1565293D03*
Y1559293D03*
Y1562293D03*
X874352D03*
Y1559293D03*
Y1565293D03*
Y1568293D03*
X871352D03*
Y1565293D03*
Y1559293D03*
Y1562293D03*
X868352Y1574293D03*
Y1571293D03*
X865352Y1574293D03*
Y1571293D03*
X874352Y1574293D03*
Y1571293D03*
X871352D03*
Y1574293D03*
X866479Y1580393D03*
X872079D03*
X866052Y1597693D03*
X869052D03*
X866479Y1590653D03*
X869052Y1600693D03*
X866052D03*
X872052Y1597693D03*
X872079Y1590653D03*
X872052Y1600693D03*
X866479Y1585523D03*
X875052Y1597693D03*
Y1600693D03*
X860652Y1590444D03*
X869052Y1603693D03*
X866052D03*
X872052D03*
X869052Y1607793D03*
Y1611893D03*
X866052Y1607793D03*
X863052Y1611893D03*
X866052D03*
X872052Y1607793D03*
Y1611893D03*
X875052Y1603693D03*
Y1607793D03*
Y1611893D03*
X863052Y1607793D03*
X860052Y1611893D03*
X878327Y183169D03*
X876695Y171362D03*
Y176862D03*
X887520Y171362D03*
Y176862D03*
X877724Y200837D03*
X878220Y187449D03*
X888929Y209223D03*
X891620Y209662D03*
X888929Y206723D03*
X891620Y207162D03*
X884003Y278712D03*
X883870Y275802D03*
X883909Y281862D03*
X879587Y270004D03*
X883870Y272652D03*
X887338Y296760D03*
X882520Y327562D03*
X885020D03*
X887520D03*
X890422Y333879D03*
X893440Y336232D03*
X890820Y389362D03*
X890920Y386352D03*
X889453Y458926D03*
X887590Y471552D03*
X889439Y489599D03*
Y492999D03*
X881680Y504742D03*
Y508142D03*
X884512Y523800D03*
X882410Y526132D03*
X888130Y532612D03*
X891530D03*
X887810Y582442D03*
X889000Y737562D03*
X885310Y736442D03*
X886720Y741902D03*
X878192Y879910D03*
X884747Y871745D03*
X879100Y912608D03*
X884619Y916477D03*
X892317Y915872D03*
X880102Y923235D03*
X891560Y1435510D03*
X883352Y1562293D03*
Y1559293D03*
Y1565293D03*
Y1568293D03*
X880352Y1562293D03*
Y1559293D03*
Y1565293D03*
Y1568293D03*
X877352Y1562293D03*
Y1559293D03*
Y1565293D03*
Y1568293D03*
X883352Y1574293D03*
Y1571293D03*
X880352Y1574293D03*
Y1571293D03*
X877352Y1574293D03*
Y1571293D03*
X888652Y1581793D03*
Y1573793D03*
X877579Y1580393D03*
X885652Y1584539D03*
X888652Y1597793D03*
Y1585993D03*
X877579Y1585523D03*
X878052Y1597693D03*
Y1600693D03*
X877579Y1590653D03*
X883152Y1586507D03*
X888652Y1589793D03*
X878052Y1603693D03*
Y1607793D03*
X881052Y1611893D03*
X878052D03*
X881052Y1607793D03*
X888652Y1609793D03*
X908620Y188899D03*
X896620Y209662D03*
X894120D03*
Y207162D03*
X896620D03*
X906120Y261252D03*
X894770Y283062D03*
X896540Y341132D03*
X902260Y473153D03*
Y475653D03*
X903124Y470797D03*
X900020Y470672D03*
X896060Y481222D03*
Y484622D03*
X907678Y488177D03*
X895340Y497882D03*
Y501282D03*
X901829Y512730D03*
Y516130D03*
X893450Y516862D03*
X901230Y531612D03*
X904630D03*
X894897Y871745D03*
X894965Y917422D03*
X899830Y971484D03*
Y974884D03*
X907770Y1045242D03*
X894830Y1435970D03*
X907352Y1568293D03*
Y1565293D03*
Y1559293D03*
Y1562293D03*
Y1574293D03*
Y1571293D03*
X908479Y1580393D03*
X896652Y1577793D03*
X899652Y1582570D03*
Y1573793D03*
X896672Y1587073D03*
X897352Y1590893D03*
X896652Y1593793D03*
X908479Y1590653D03*
Y1585523D03*
X908052Y1600693D03*
Y1597693D03*
X899551Y1593793D03*
X902652Y1590444D03*
X896652Y1605793D03*
X908052Y1611893D03*
X905052D03*
X902052D03*
X908052Y1607793D03*
X905052D03*
X908052Y1603693D03*
X896652Y1601793D03*
X922726Y176302D03*
X922100Y181791D03*
X917386Y184114D03*
X924920Y196199D03*
X923836Y193563D03*
X923897Y445545D03*
X927034Y445594D03*
X912984Y458135D03*
X909584D03*
X924447Y463012D03*
X921047D03*
X909190Y473392D03*
X912288Y472430D03*
X918532Y492445D03*
X927154Y492103D03*
X924623Y492097D03*
X918078Y495177D03*
X921189Y492086D03*
X918212Y497677D03*
X918131Y503330D03*
X921060Y506086D03*
X923783Y506076D03*
X918212Y500777D03*
X909984Y496330D03*
X926173Y512391D03*
X913394Y521662D03*
X916794D03*
X909600Y521162D03*
X922879Y531976D03*
Y528576D03*
X918420Y804062D03*
X909720Y798861D03*
Y794862D03*
X913720Y799362D03*
X914152Y803294D03*
X921757Y962082D03*
X916974Y962108D03*
X923930Y976652D03*
X917980Y974952D03*
X924440Y996852D03*
X914838Y985989D03*
X918720Y1009937D03*
X910352Y1568293D03*
Y1565293D03*
Y1559293D03*
Y1562293D03*
X922352D03*
Y1559293D03*
Y1565293D03*
Y1568293D03*
X919352Y1562293D03*
Y1559293D03*
Y1565293D03*
Y1568293D03*
X916352Y1562293D03*
Y1559293D03*
Y1565293D03*
Y1568293D03*
X913352D03*
Y1565293D03*
Y1559293D03*
Y1562293D03*
X910352Y1574293D03*
Y1571293D03*
X922352Y1574293D03*
Y1571293D03*
X919352Y1574293D03*
Y1571293D03*
X916352Y1574293D03*
Y1571293D03*
X913352D03*
Y1574293D03*
X919579Y1580393D03*
X914079D03*
X919579Y1590653D03*
X914079D03*
X919579Y1585523D03*
X917052Y1600693D03*
Y1597693D03*
X914052Y1600693D03*
Y1597693D03*
X911052Y1600693D03*
Y1597693D03*
X920052Y1600693D03*
Y1597693D03*
X917052Y1611893D03*
X914052D03*
X911052D03*
X917052Y1607793D03*
X914052D03*
X911052D03*
X920052Y1611893D03*
X923052D03*
Y1607793D03*
X920052D03*
X917052Y1603693D03*
X914052D03*
X911052D03*
X920052D03*
X919488Y1660733D03*
X918020Y1672860D03*
X914500Y1671400D03*
X938160Y173389D03*
X935550Y173329D03*
X940720Y173389D03*
X938160Y176389D03*
X935550Y176329D03*
X940720Y176389D03*
X940424Y184190D03*
X936424D03*
X935770Y191419D03*
X939270D03*
X940410Y188852D03*
X930472Y246093D03*
X938603Y240063D03*
X933122Y246115D03*
X933686Y242922D03*
X935454Y241154D03*
X933217Y380693D03*
Y384693D03*
X941059Y427911D03*
Y424511D03*
X937447Y457862D03*
X934047D03*
X928394Y472201D03*
Y474701D03*
X932373Y495175D03*
X932089Y492691D03*
X929654Y492103D03*
X932218Y499314D03*
X939872Y495813D03*
X932089Y505986D03*
X932289Y502986D03*
X926637Y506069D03*
X929281Y506086D03*
X931720Y524862D03*
X940550Y517400D03*
X940140Y514925D03*
X933773Y530479D03*
X930731D03*
X941050Y532252D03*
Y528852D03*
X938742Y803831D03*
X931573Y816109D03*
X927470Y815112D03*
X935052Y812630D03*
X934260Y808312D03*
X938371Y809311D03*
X930786Y811785D03*
X925220Y817862D03*
X928237Y824844D03*
X926469Y826612D03*
X926823Y962082D03*
X940170Y962842D03*
X939740Y987762D03*
X936998Y985750D03*
X932310Y996812D03*
X927220Y1012362D03*
X931220D03*
X925352Y1562293D03*
Y1559293D03*
Y1565293D03*
Y1568293D03*
Y1574293D03*
Y1571293D03*
X938652Y1581393D03*
X928152Y1584539D03*
X938652Y1593393D03*
Y1585393D03*
X925152Y1586507D03*
X938652Y1589393D03*
X933979Y1661327D03*
X929979Y1661352D03*
X942100Y1671100D03*
X945720Y173389D03*
X943220D03*
X945720Y176389D03*
X943220D03*
X948400Y176499D03*
X949120Y184912D03*
X944250Y194489D03*
Y197889D03*
X957020Y193299D03*
X949550Y192819D03*
X957020Y264862D03*
X953046Y390103D03*
X951181Y391916D03*
X950660Y399472D03*
X956487Y394831D03*
X949920Y404602D03*
X944032Y437631D03*
Y434231D03*
X945447Y463012D03*
X942047D03*
X946727Y507952D03*
Y504552D03*
X954420Y511252D03*
Y500552D03*
Y497152D03*
Y514652D03*
X954390Y527596D03*
X945524Y515483D03*
X944261Y517871D03*
X941740Y512922D03*
X942610Y515350D03*
X945100Y534464D03*
X955123Y533642D03*
X948415Y534313D03*
X956518Y531567D03*
X957220Y582862D03*
X953594Y787477D03*
X954447Y791735D03*
X951043Y796140D03*
X950190Y791382D03*
X944272Y803410D03*
X943366Y798707D03*
X946786Y795287D03*
X947921Y799761D03*
X944170Y962842D03*
X949560Y981392D03*
X951560Y997422D03*
X956980Y1536260D03*
X953980D03*
X950980D03*
X947980D03*
X944980D03*
Y1551260D03*
X947980D03*
X950980D03*
X953980D03*
X956980D03*
X944980Y1548260D03*
X947980D03*
X950980D03*
X953980D03*
X956980D03*
X944980Y1545260D03*
X947980D03*
X950980D03*
X953980D03*
X956980D03*
X944980Y1542260D03*
X947980D03*
X950980D03*
X953980D03*
X956980D03*
Y1539260D03*
X953980D03*
X950980D03*
X947980D03*
X944980D03*
Y1554260D03*
X947980D03*
X950980D03*
X953980D03*
X956980D03*
X956800Y1663725D03*
X956600Y1666875D03*
X962604Y165313D03*
X962458Y162398D03*
X965150Y193412D03*
X966720Y198099D03*
X970720D03*
X961120Y193299D03*
X968384Y242051D03*
X965884D03*
X960020Y264862D03*
X963020D03*
X962570Y282812D03*
X962882Y314512D03*
X967239Y320073D03*
X963854Y320113D03*
X963300Y347962D03*
X962623Y350642D03*
X970730Y377872D03*
X972220Y386251D03*
Y390239D03*
X975670Y392063D03*
X963856Y398302D03*
X965890Y405967D03*
X963720Y439862D03*
X961320Y476242D03*
X968286Y483941D03*
Y480541D03*
X964347Y509462D03*
X970788Y501230D03*
X964347Y501262D03*
X969351Y512416D03*
X957790Y527596D03*
X963930Y533362D03*
X967330D03*
X959351Y533566D03*
X960920Y644762D03*
Y649762D03*
Y654762D03*
X963720Y647262D03*
Y657262D03*
Y652262D03*
X960820Y665062D03*
X960920Y659762D03*
X963720Y662262D03*
X967750Y1376460D03*
X969000Y1536262D03*
X971700D03*
X969000Y1548262D03*
X971700D03*
X969000Y1545262D03*
X971700D03*
X969000Y1551262D03*
X971700D03*
Y1542262D03*
X969000D03*
X971700Y1539262D03*
X969000D03*
X965904Y1554364D03*
X960904D03*
X969000Y1554262D03*
X971700D03*
X965622Y1579240D03*
Y1576240D03*
Y1573240D03*
X966852Y1585920D03*
X969852D03*
X960852D03*
X963852D03*
X957852D03*
X965086Y1603984D03*
X962086D03*
X980899Y-19800D03*
Y-23200D03*
Y6800D03*
Y10200D03*
X990501Y152397D03*
X986369Y155358D03*
X975690Y157220D03*
X983811Y156694D03*
X985499Y168753D03*
X985431Y181058D03*
X990115Y173039D03*
X987320Y194599D03*
Y198099D03*
Y201599D03*
X977220Y201399D03*
X986020Y191099D03*
X981795Y216623D03*
X978012Y276436D03*
X975512Y282096D03*
X978012D03*
X975512Y279266D03*
X978012D03*
X981470Y268532D03*
X979940Y292262D03*
Y289762D03*
X975512Y294996D03*
X978012D03*
X979940Y284762D03*
Y287262D03*
X988818Y346372D03*
X978000Y362462D03*
X988723Y369650D03*
X991934Y368443D03*
X988908Y373392D03*
X986400Y383123D03*
X983770Y373962D03*
X979766Y377507D03*
X977949Y384205D03*
X980916Y384286D03*
X980856Y392502D03*
X986955Y391939D03*
X983629Y397628D03*
X979559Y399362D03*
X983970Y392562D03*
X991369Y408252D03*
X979240Y425212D03*
X984254Y418379D03*
X987440Y431193D03*
X980720Y512362D03*
X986400Y503200D03*
X986273Y532996D03*
X980535Y532643D03*
X986418Y530019D03*
X975900Y1265062D03*
X987920Y1290662D03*
X985320Y1288762D03*
X992306Y1295049D03*
X979373Y1342724D03*
X974700Y1536262D03*
X980400D03*
X977700D03*
X974700Y1548262D03*
Y1545262D03*
Y1551262D03*
X980400Y1548262D03*
X977700D03*
X980400Y1545262D03*
X977700D03*
X980400Y1551262D03*
X977700D03*
Y1542262D03*
X980400D03*
X974700D03*
X977700Y1539262D03*
X980400D03*
X974700D03*
X984270Y1554364D03*
X974700Y1554262D03*
X980400D03*
X977700D03*
X989270Y1554364D03*
X988988Y1579240D03*
Y1573240D03*
Y1576240D03*
X995000Y150883D03*
X1001500D03*
X995180Y153689D03*
X1006220Y160799D03*
X1002720D03*
X1001101Y165510D03*
X999220Y185299D03*
X1002720D03*
X1006220D03*
X996415Y172579D03*
X1002920Y174799D03*
X990220Y195699D03*
Y199199D03*
X1008120Y198293D03*
X990195Y216823D03*
X990220Y202699D03*
X1000610Y211039D03*
X1005640Y210969D03*
X1001195Y219898D03*
X1005120Y230399D03*
X994743Y289843D03*
X1006232Y343983D03*
X1001440Y359702D03*
X994689Y379348D03*
X1006201Y370004D03*
X999440Y371782D03*
X996922Y367764D03*
X994322Y404090D03*
X1005123Y414662D03*
X997617Y412383D03*
X997394Y415578D03*
X993012Y421570D03*
X997225Y419162D03*
X990840Y431193D03*
X1005720Y498862D03*
X1003220Y512862D03*
X1005520Y510932D03*
X991237Y533043D03*
X1008560Y589682D03*
X1005960Y594682D03*
X1005373Y748826D03*
X995120Y773122D03*
X994942Y777055D03*
X996320Y1280683D03*
Y1284062D03*
X997920Y1278762D03*
X994574Y1297318D03*
X995066Y1536262D03*
X992466D03*
X1001066D03*
X1003766D03*
X998066D03*
X995066Y1551262D03*
X992466D03*
X995066Y1545262D03*
X992466D03*
X995066Y1548262D03*
X992466D03*
X1001066Y1551262D03*
X1003766D03*
X1001066Y1545262D03*
X1003766D03*
X1001066Y1548262D03*
X1003766D03*
X998066Y1551262D03*
Y1545262D03*
Y1548262D03*
Y1542262D03*
X1003766D03*
X1001066D03*
X992466D03*
X995066D03*
X998066Y1539262D03*
X1003766D03*
X1001066D03*
X992466D03*
X995066D03*
X1007636Y1554364D03*
X995066Y1554262D03*
X992466D03*
X1001066D03*
X1003766D03*
X998066D03*
X1002782Y1585920D03*
X999782D03*
X996782D03*
X990782D03*
X993782D03*
X996698Y1604000D03*
X993698D03*
X1008129Y150948D03*
X1009720Y160799D03*
X1013220D03*
X1012791Y157596D03*
X1012000Y185299D03*
X1014900D03*
X1017800D03*
X1017200Y175699D03*
X1014300D03*
X1019900Y175799D03*
X1020645Y190499D03*
X1011320Y202169D03*
X1019355Y218423D03*
X1019802Y214099D03*
X1010005Y208424D03*
X1011720Y229699D03*
X1019355Y222423D03*
X1019530Y226423D03*
X1007820Y229999D03*
X1021118Y294290D03*
X1020720Y310937D03*
X1015520Y302862D03*
X1009800Y343800D03*
X1021695Y364518D03*
X1006710Y372931D03*
X1015096Y373758D03*
X1017163Y367963D03*
X1009883Y367955D03*
X1010420Y416062D03*
X1015420Y410862D03*
X1009009Y419948D03*
X1021239Y416974D03*
X1016261Y432888D03*
X1012861D03*
X1024200Y510362D03*
X1018092Y520212D03*
X1020392Y521826D03*
X1016360Y594682D03*
X1016220Y590862D03*
X1019000Y601042D03*
X1021654Y606302D03*
X1011160Y594682D03*
X1007873Y748826D03*
X1007600Y1298250D03*
X1007610Y1295040D03*
X1021612Y1536262D03*
X1016012D03*
X1018612D03*
Y1551262D03*
X1016012D03*
X1018612Y1545262D03*
X1016012D03*
X1018612Y1548262D03*
X1016012D03*
X1021612Y1551262D03*
Y1545262D03*
Y1548262D03*
X1018612Y1542262D03*
X1016012D03*
X1021612D03*
Y1539262D03*
X1016012D03*
X1018612D03*
Y1554262D03*
X1016012D03*
X1021612D03*
X1012636Y1554364D03*
X1012354Y1579240D03*
Y1573240D03*
Y1576240D03*
X1021942Y1586090D03*
X1026620Y125662D03*
X1034229Y128953D03*
X1032894Y155185D03*
X1022800Y175799D03*
X1037618Y261200D03*
X1031702Y264130D03*
X1025862Y291727D03*
X1032317Y291284D03*
X1036278Y303993D03*
Y307393D03*
X1033285Y353627D03*
X1029395Y375844D03*
X1025004Y374662D03*
X1031950Y383771D03*
Y387171D03*
X1031153Y390152D03*
X1026820Y394362D03*
X1038320Y407062D03*
Y404462D03*
X1026548Y400571D03*
X1035920Y420062D03*
Y417462D03*
X1026370Y503562D03*
X1032155Y509737D03*
X1025530Y519627D03*
X1033040Y519852D03*
X1038130Y518417D03*
X1040720Y591862D03*
X1024154Y601152D03*
X1029630Y601252D03*
X1026654Y596152D03*
X1035760Y592952D03*
X1033260Y601272D03*
X1038260D03*
X1033817Y735612D03*
X1036954Y734669D03*
X1030660Y735082D03*
X1027212Y1536262D03*
X1024612D03*
Y1551262D03*
X1027212D03*
X1024612Y1545262D03*
X1027212D03*
X1024612Y1548262D03*
X1027212D03*
X1024612Y1542262D03*
X1027212D03*
Y1539262D03*
X1024612D03*
X1031002Y1554364D03*
X1024612Y1554262D03*
X1027212D03*
X1036002Y1554364D03*
X1035720Y1579240D03*
Y1573240D03*
Y1576240D03*
X1030942Y1586090D03*
X1033942D03*
X1024942D03*
X1027942D03*
X1028298Y1604000D03*
X1025298D03*
X1040970Y128332D03*
X1043720Y363462D03*
X1054820Y370162D03*
X1044120Y366362D03*
X1040120Y393962D03*
X1042720D03*
X1041420Y443962D03*
X1043920D03*
X1050470Y447062D03*
X1041444Y506504D03*
X1053690Y520760D03*
X1045720Y591672D03*
X1043260Y601272D03*
X1045760Y596272D03*
X1048260Y601272D03*
X1051680Y614772D03*
X1053745Y742341D03*
X1053354Y1286714D03*
Y1291714D03*
X1039510Y1296655D03*
X1049510D03*
X1044510D03*
X1039510Y1293155D03*
X1049510D03*
X1044510D03*
X1053354Y1296714D03*
X1041798Y1536262D03*
X1047798D03*
X1050498D03*
X1044798D03*
X1039298D03*
X1041798Y1551262D03*
X1039298D03*
X1041798Y1545262D03*
X1039298D03*
X1041798Y1548262D03*
X1039298D03*
X1047798Y1551262D03*
X1050498D03*
X1047798Y1545262D03*
X1050498D03*
X1047798Y1548262D03*
X1050498D03*
X1044798Y1551262D03*
Y1545262D03*
Y1548262D03*
X1039298Y1542262D03*
X1044798D03*
X1050498D03*
X1047798D03*
X1041798D03*
X1044798Y1539262D03*
X1050498D03*
X1047798D03*
X1039298D03*
X1041798D03*
X1054368Y1554364D03*
X1041798Y1554262D03*
X1039298D03*
X1047798D03*
X1050498D03*
X1044798D03*
X1053612Y1586010D03*
X1056898Y1604000D03*
X1067220Y145362D03*
Y142862D03*
Y148362D03*
X1059943Y435314D03*
X1062120Y477462D03*
X1056190Y520760D03*
X1058220Y585862D03*
X1061470D03*
X1056220Y605052D03*
X1055205Y744853D03*
X1063354Y1286714D03*
X1058354D03*
X1063354Y1291714D03*
X1058354D03*
X1063354Y1296714D03*
X1058290Y1296302D03*
X1071179Y1294669D03*
X1066462Y1520088D03*
X1065164Y1536262D03*
X1062464D03*
X1071164D03*
X1068164D03*
X1065164Y1551262D03*
X1062464D03*
X1065164Y1545262D03*
X1062464D03*
X1065164Y1548262D03*
X1062464D03*
X1071164Y1551262D03*
Y1545262D03*
Y1548262D03*
X1068164Y1551262D03*
Y1545262D03*
Y1548262D03*
Y1542262D03*
X1071164D03*
X1062464D03*
X1065164D03*
X1068164Y1539262D03*
X1071164D03*
X1062464D03*
X1065164D03*
Y1554262D03*
X1062464D03*
X1071164D03*
X1068164D03*
X1059368Y1554364D03*
X1059086Y1579240D03*
Y1573240D03*
Y1576240D03*
X1062612Y1586010D03*
X1065612D03*
X1056612D03*
X1059612D03*
X1059898Y1604000D03*
X1071920Y53862D03*
X1079114Y75775D03*
X1080168Y90721D03*
X1081282Y180937D03*
X1086756Y187540D03*
X1077973Y246362D03*
X1083973D03*
X1080973D03*
X1077883Y260842D03*
X1076823Y265438D03*
X1083823D03*
X1083883Y260842D03*
X1080883D03*
X1080323Y265438D03*
X1082853Y269492D03*
X1079853D03*
X1075400Y273762D03*
X1078400D03*
X1081400D03*
X1084400D03*
X1087400D03*
X1076018Y289400D03*
X1079018D03*
X1082018D03*
X1085018D03*
X1084130Y298342D03*
X1086630D03*
X1076353Y363966D03*
X1078853D03*
X1087330Y369061D03*
Y374131D03*
Y379251D03*
X1075462Y386723D03*
X1078151Y413911D03*
X1078120Y411262D03*
X1084245Y435437D03*
X1078545Y435637D03*
X1081045D03*
X1087280Y435437D03*
X1076598Y477087D03*
X1081930Y477132D03*
X1079320Y473892D03*
X1076820D03*
X1073589Y506461D03*
X1082220Y522362D03*
X1085720Y522422D03*
X1073250Y582332D03*
X1084637Y744635D03*
X1083714Y1285144D03*
Y1288144D03*
Y1291144D03*
X1077634Y1294869D03*
X1074387Y1294652D03*
X1074010Y1510650D03*
X1073864Y1536262D03*
X1085830D03*
X1073864Y1551262D03*
Y1545262D03*
Y1548262D03*
X1085830Y1551262D03*
Y1545262D03*
Y1548262D03*
Y1542262D03*
X1073864D03*
X1085830Y1539262D03*
X1073864D03*
X1077734Y1554364D03*
X1073864Y1554262D03*
X1085830D03*
X1082734Y1554364D03*
X1084000Y1647110D03*
X1094644Y67992D03*
X1090279Y126524D03*
X1105580Y132822D03*
X1100630Y130376D03*
X1099030Y245140D03*
X1088018Y289400D03*
X1089130Y298342D03*
X1091630D03*
X1094130D03*
X1089660Y408560D03*
X1095820Y420762D03*
X1090245Y435437D03*
X1093497Y744655D03*
X1089714Y1285144D03*
X1105480Y1517982D03*
X1088530Y1536262D03*
X1091530D03*
X1088530Y1551262D03*
Y1545262D03*
Y1548262D03*
X1094530Y1551262D03*
X1097230D03*
X1094530Y1545262D03*
X1097230D03*
X1094530Y1548262D03*
X1097230D03*
X1091530Y1551262D03*
Y1545262D03*
Y1548262D03*
Y1542262D03*
X1097230D03*
X1094530D03*
X1088530D03*
X1091530Y1539262D03*
X1094530D03*
X1088530D03*
X1101600Y1554364D03*
X1104750Y1549346D03*
X1088530Y1554262D03*
X1094530D03*
X1097230D03*
X1091530D03*
X1092302Y1585650D03*
X1089302D03*
X1098302D03*
X1095302D03*
X1095436Y1603944D03*
X1092436D03*
X1088790Y1641830D03*
X1094225Y1671710D03*
X1091880Y1673720D03*
X1110977Y55505D03*
X1110754Y60028D03*
X1113594Y69862D03*
X1109020Y80592D03*
X1118309Y111687D03*
X1115860Y113883D03*
X1118486Y208942D03*
X1111918Y234718D03*
X1109088Y234668D03*
X1111918Y237718D03*
Y240718D03*
X1109088Y237668D03*
Y240668D03*
X1120190Y255652D03*
X1117820Y456132D03*
X1113207Y744455D03*
X1115853Y1426342D03*
Y1435532D03*
X1114400Y1518237D03*
X1110725Y1518046D03*
X1113725Y1530935D03*
X1115802Y1615010D03*
X1117407Y1628495D03*
X1113990Y1631370D03*
X1113325Y1627975D03*
X1117182Y1625460D03*
X1106480Y1641275D03*
X1113110Y1666460D03*
X1108320Y1680200D03*
X1112130Y1711600D03*
X1112252Y1706170D03*
X1112200Y1709000D03*
X1114150Y1715726D03*
X1110663Y1719189D03*
X1119200Y1730300D03*
Y1727200D03*
X1114300Y1722700D03*
X1119300Y1724100D03*
X1132547Y64864D03*
X1129997Y69864D03*
X1122278Y107549D03*
X1120420Y109829D03*
X1124858Y197309D03*
X1128485Y198159D03*
X1133041Y194137D03*
X1124360Y259712D03*
X1125409Y305797D03*
X1122059Y305673D03*
X1124985Y302578D03*
X1127402Y456174D03*
X1136051Y503324D03*
X1124120Y643762D03*
X1136720Y641362D03*
X1133720Y642862D03*
X1129420Y644062D03*
X1122980Y741312D03*
X1127972Y747250D03*
X1135750Y1255672D03*
X1127179Y1372700D03*
X1124679D03*
Y1370200D03*
X1127179D03*
X1129729Y1372700D03*
Y1370200D03*
Y1375200D03*
X1127179D03*
X1124679D03*
X1129729Y1377700D03*
Y1380200D03*
Y1385200D03*
Y1382700D03*
X1127179D03*
X1124679D03*
X1127179Y1380200D03*
Y1377700D03*
X1124679D03*
Y1380200D03*
Y1385200D03*
X1127179D03*
X1122879Y1431474D03*
Y1434024D03*
X1125995Y1439780D03*
X1123379Y1443583D03*
X1133169Y1445690D03*
X1129169Y1442998D03*
X1135568Y1442923D03*
X1129169Y1445719D03*
X1130841Y1462953D03*
X1128341Y1465453D03*
Y1462953D03*
X1130841Y1465453D03*
X1133841Y1462953D03*
Y1465453D03*
X1128341Y1468453D03*
X1130841D03*
X1133841D03*
X1128341Y1460453D03*
X1130841D03*
X1133841D03*
Y1471453D03*
X1130841D03*
X1128341D03*
X1132187Y1582738D03*
X1135187D03*
X1132187Y1590738D03*
X1135187D03*
X1124862Y1615010D03*
X1140242Y101135D03*
X1152720Y180862D03*
X1148795Y213731D03*
X1141957Y227277D03*
X1144457D03*
X1139457D03*
X1146670Y230110D03*
X1147700Y362731D03*
X1137315Y379592D03*
X1147700Y368041D03*
X1138551Y503324D03*
X1144720Y501362D03*
Y498662D03*
X1142967Y592097D03*
X1138500Y586362D03*
X1142127Y586452D03*
X1140697Y608762D03*
X1150140Y610362D03*
X1144810Y613762D03*
X1142674Y1287608D03*
X1144247Y1372700D03*
Y1370200D03*
X1146797Y1372700D03*
X1149297D03*
X1146797Y1370200D03*
X1149297D03*
X1144247Y1375200D03*
X1146797D03*
X1149297D03*
X1144247Y1377700D03*
Y1380200D03*
Y1385200D03*
Y1382700D03*
X1146797D03*
X1149297D03*
X1146797Y1380200D03*
Y1377700D03*
X1149297Y1380200D03*
Y1377700D03*
Y1385200D03*
X1146797D03*
X1146563Y1436334D03*
X1141903D03*
X1144233Y1435584D03*
X1139573D03*
X1149469Y1437098D03*
X1151669Y1435698D03*
Y1438598D03*
X1137311Y1445191D03*
X1147203Y1441968D03*
X1149569Y1440098D03*
X1151669Y1441498D03*
X1147203Y1439068D03*
X1141591Y1462853D03*
Y1465353D03*
Y1468353D03*
Y1471353D03*
Y1460353D03*
X1150821Y1459607D03*
Y1456587D03*
X1138430Y1524150D03*
X1151497Y1524187D03*
X1153465Y1550301D03*
X1149528D03*
X1145410Y1540640D03*
X1143060Y1538380D03*
X1141654Y1550301D03*
X1137717Y1558020D03*
X1141690Y1552920D03*
X1152187Y1574738D03*
X1142187D03*
X1145187D03*
X1142187Y1582738D03*
X1145187D03*
X1152187D03*
X1141525Y1597630D03*
X1152187Y1590738D03*
X1142187D03*
X1145187D03*
X1140750Y1604330D03*
X1150380Y1602590D03*
X1146960Y1618960D03*
X1152257Y1628910D03*
X1155703Y73679D03*
X1165440Y176450D03*
X1168710Y176590D03*
X1159460Y194090D03*
X1160630Y213870D03*
X1159753Y361281D03*
X1159460Y366025D03*
X1156790Y363231D03*
X1161690Y374110D03*
X1164320Y451062D03*
X1156100Y456342D03*
X1167190Y526922D03*
X1158300Y585862D03*
X1170740Y602132D03*
X1155962Y746193D03*
X1156609Y1286685D03*
X1165279Y1372700D03*
X1162779D03*
X1167829D03*
X1162779Y1370200D03*
X1165279D03*
X1167829D03*
X1162779Y1375200D03*
X1165279D03*
X1167829D03*
Y1377700D03*
Y1380200D03*
Y1385200D03*
Y1382700D03*
X1165279D03*
X1162779D03*
X1165279Y1380200D03*
X1162779D03*
Y1377700D03*
X1165279D03*
X1162779Y1385200D03*
X1165279D03*
X1161022Y1431499D03*
Y1433999D03*
X1164138Y1439780D03*
X1154288Y1432502D03*
X1161522Y1443630D03*
X1167312Y1442998D03*
Y1445964D03*
X1159386Y1464253D03*
Y1466753D03*
X1156386Y1464253D03*
Y1466753D03*
X1159386Y1469253D03*
X1156386D03*
X1153821Y1459607D03*
Y1456587D03*
X1159386Y1461753D03*
X1159476Y1458918D03*
X1156386Y1461753D03*
X1156476Y1458918D03*
X1159446Y1456113D03*
X1156446D03*
X1167245Y1524187D03*
X1159371D03*
X1163308D03*
X1155433D03*
X1165276Y1550301D03*
X1169213D03*
X1157402D03*
X1161339D03*
X1161595Y1574738D03*
X1164595D03*
X1155187D03*
X1161595Y1582738D03*
X1164595D03*
X1155187D03*
X1163079Y1601479D03*
X1161595Y1590738D03*
X1164595D03*
X1155187D03*
X1169460Y1606630D03*
Y1616630D03*
Y1611630D03*
X1158030Y1619250D03*
X1164830Y1628830D03*
X1163970Y1620600D03*
X1169325Y1642600D03*
X1158325D03*
X1162383Y1652505D03*
X1164830Y1654632D03*
X1159930D03*
X1161076Y1680624D03*
X1157700Y1681100D03*
X1174120Y57111D03*
X1175926Y69151D03*
X1180676Y106858D03*
X1187413Y143132D03*
X1181420Y157962D03*
X1181700Y186962D03*
X1173314Y176452D03*
X1170595Y170056D03*
X1181476Y172247D03*
X1184510Y188962D03*
X1173100Y186962D03*
X1172925Y202174D03*
X1181369Y199234D03*
X1183460Y205342D03*
X1181470Y208802D03*
X1172835Y218174D03*
X1181500Y211962D03*
Y218462D03*
Y215962D03*
Y222162D03*
X1186653Y302242D03*
X1181450Y306052D03*
X1174120Y355362D03*
X1169690Y526922D03*
X1172310Y584562D03*
X1181300Y584762D03*
X1177570Y602052D03*
X1175217Y595762D03*
X1173020Y745972D03*
X1175573Y1286765D03*
X1172573D03*
X1182747Y1372700D03*
X1185297D03*
X1182747Y1370200D03*
X1185297D03*
X1182747Y1375200D03*
X1185297D03*
X1182747Y1380200D03*
Y1377700D03*
Y1385200D03*
Y1382700D03*
X1185297D03*
Y1377700D03*
Y1380200D03*
Y1385200D03*
X1184706Y1436334D03*
X1180046D03*
X1182376Y1435584D03*
X1177716D03*
X1171342Y1445650D03*
X1175454Y1445191D03*
X1173711Y1442923D03*
X1171182Y1524187D03*
X1184330Y1573260D03*
X1184290Y1570080D03*
X1171595Y1574738D03*
X1174595D03*
X1171595Y1582738D03*
X1174595D03*
X1183410Y1594450D03*
X1183440Y1591640D03*
X1171595Y1590738D03*
X1174595D03*
X1178140Y1601100D03*
X1184200Y1599900D03*
X1183320Y1597080D03*
X1169968Y1602370D03*
X1174550Y1615630D03*
X1178250Y1609100D03*
X1184200Y1602700D03*
X1185030Y1624660D03*
X1180325Y1642600D03*
X1173383Y1652505D03*
X1184383D03*
X1181930Y1654632D03*
X1175830D03*
X1170930D03*
X1183076Y1680624D03*
X1172076D03*
X1194478Y56986D03*
X1197520Y56962D03*
X1201158Y57130D03*
X1189393Y60183D03*
X1188700Y100700D03*
X1185400Y104000D03*
X1193532Y132644D03*
X1194800Y143112D03*
X1197414Y161592D03*
X1191020Y170862D03*
X1185420Y153762D03*
X1200720Y184862D03*
X1188300Y189062D03*
X1200720Y187862D03*
X1200963Y212648D03*
X1200830Y206002D03*
X1186340Y204492D03*
X1187300Y217862D03*
X1188500Y205772D03*
X1188600Y225962D03*
X1187013Y238972D03*
X1194840Y236592D03*
X1199720Y252362D03*
X1196720D03*
X1188810Y296088D03*
X1186280Y298972D03*
X1193198Y586172D03*
X1195698D03*
X1198198D03*
X1200698D03*
X1185687Y744475D03*
X1187797Y1372700D03*
Y1370200D03*
Y1375200D03*
Y1382700D03*
Y1377700D03*
Y1380200D03*
Y1385200D03*
X1187412Y1437498D03*
X1189612Y1436098D03*
X1191918Y1432516D03*
X1185346Y1442128D03*
X1187512Y1440498D03*
X1189612Y1441898D03*
X1185346Y1439228D03*
X1189612Y1438998D03*
X1187720Y1517688D03*
X1187830Y1522188D03*
X1198546Y1520188D03*
X1187830Y1526688D03*
X1198546Y1524688D03*
X1187720Y1536362D03*
X1198485Y1534313D03*
X1198436Y1529362D03*
X1187720Y1531862D03*
Y1553692D03*
X1198497Y1539667D03*
X1187720Y1548772D03*
X1198436Y1546492D03*
X1187720Y1544292D03*
X1198436Y1551192D03*
Y1556192D03*
Y1561062D03*
X1187720Y1558682D03*
Y1563182D03*
X1194510Y1563076D03*
X1187600Y1622064D03*
X1201600Y1633790D03*
X1199400Y1627800D03*
X1190895Y1642910D03*
X1186000Y1640000D03*
X1197400Y1654942D03*
X1192500D03*
X1186830Y1654632D03*
X1193646Y1680934D03*
X1201106Y1677873D03*
X1190735Y1688390D03*
X1194793Y1698295D03*
X1201505Y1688435D03*
X1192340Y1700422D03*
X1197240D03*
X1193174Y1726414D03*
X1216176Y56742D03*
X1202860Y120392D03*
X1215763Y114363D03*
X1215800Y111300D03*
X1201700Y110000D03*
X1202920Y117162D03*
X1210910Y129502D03*
X1206114Y132962D03*
X1206434Y129492D03*
X1206694Y139512D03*
X1214415Y153962D03*
X1206664Y158952D03*
X1214091Y164962D03*
X1214534Y157462D03*
X1214054Y186092D03*
X1214693Y174962D03*
X1214134Y180972D03*
X1213720Y200309D03*
Y189362D03*
X1204220D03*
X1213720Y195362D03*
X1215720Y204862D03*
X1203200Y202514D03*
X1219060Y213312D03*
X1206660Y224742D03*
X1213540Y224792D03*
X1207220Y243998D03*
X1210900Y265300D03*
X1204475Y350684D03*
X1205165Y380962D03*
X1218870Y418082D03*
X1214000Y599262D03*
X1208980Y598462D03*
X1207100Y600882D03*
X1211277Y744265D03*
X1206757Y744455D03*
X1210288Y754081D03*
X1202300Y753962D03*
X1207607Y754095D03*
X1215896Y756942D03*
X1206432Y758995D03*
X1202307Y757082D03*
X1205820Y1652910D03*
X1210830Y1676500D03*
X1217210Y1684520D03*
X1212305Y1688700D03*
X1216363Y1698605D03*
X1205563Y1698340D03*
X1207180Y1685680D03*
X1208010Y1700467D03*
X1213910Y1700732D03*
X1203110Y1700467D03*
X1203939Y1726459D03*
X1214834Y1726724D03*
X1228425Y91500D03*
X1222100Y91600D03*
X1225100Y91500D03*
X1225700Y108962D03*
X1232182Y110659D03*
X1224614Y116962D03*
X1219534Y116492D03*
X1223500Y111162D03*
X1226400Y125200D03*
X1226093Y134262D03*
X1229500Y125100D03*
X1223100Y130700D03*
X1234093Y144962D03*
X1226093Y140962D03*
X1222593D03*
X1222920Y144909D03*
Y148909D03*
X1222593Y168962D03*
X1222890Y157002D03*
X1226093Y156962D03*
X1222594Y154242D03*
X1226093Y168162D03*
X1225874Y163462D03*
X1222720Y163362D03*
X1226093Y177962D03*
X1222724Y176102D03*
X1226093Y172962D03*
X1223134Y190802D03*
X1225574Y188662D03*
X1228520Y202162D03*
X1229720Y197302D03*
X1226093Y193462D03*
X1225320Y200162D03*
X1233282Y201875D03*
X1223180Y210552D03*
X1233780Y214572D03*
X1231720Y217862D03*
Y209862D03*
X1219220Y243862D03*
Y247148D03*
X1230720Y380362D03*
X1221220D03*
X1232720Y377862D03*
X1224300Y380400D03*
X1223650Y520672D03*
X1230650D03*
X1227150D03*
X1219060Y757272D03*
X1223327Y757615D03*
X1228320Y758598D03*
X1218810Y1700732D03*
X1236620Y58862D03*
X1241010Y110782D03*
X1250010Y117121D03*
X1244200Y112862D03*
X1249362Y111600D03*
X1241035Y114399D03*
X1234746Y136040D03*
X1240728Y136198D03*
X1240904Y151592D03*
X1238604Y150062D03*
X1241100Y145842D03*
X1244120Y167462D03*
X1246272Y164889D03*
X1243100Y160181D03*
X1243184Y182422D03*
X1239874Y182322D03*
X1236410Y201462D03*
X1236220Y189362D03*
X1236593Y197462D03*
X1236584Y205762D03*
X1245486Y203000D03*
X1245593Y211762D03*
X1236620Y221562D03*
X1244720Y230362D03*
X1245514Y224302D03*
X1245593Y219662D03*
X1239045Y224062D03*
X1246878Y248615D03*
X1240500Y248332D03*
Y244332D03*
X1236720Y257362D03*
X1243589Y379595D03*
X1236720Y377862D03*
X1234720Y380362D03*
X1248150Y520672D03*
X1244650D03*
X1241150D03*
X1237650D03*
X1234150D03*
X1242260Y757602D03*
X1261227Y52061D03*
X1258727D03*
X1263454Y83060D03*
X1266464Y83090D03*
X1264098Y88787D03*
X1262320Y96012D03*
X1258539Y100900D03*
X1252520Y92022D03*
X1258539Y109263D03*
X1260641Y114399D03*
X1264220Y110462D03*
X1250424Y108943D03*
X1257581Y114579D03*
X1256093Y149462D03*
X1264663Y158946D03*
X1254994Y157382D03*
X1265010Y162222D03*
X1261899Y174648D03*
X1253624Y201362D03*
X1267315Y220701D03*
X1264874Y217462D03*
X1256504D03*
X1255613Y209568D03*
X1265207Y208442D03*
X1259703Y209808D03*
X1253440Y230552D03*
X1253860Y235622D03*
X1256070Y229512D03*
X1264584Y226592D03*
X1256593Y221462D03*
Y233972D03*
Y225972D03*
X1253950Y246692D03*
X1266715Y244692D03*
X1254370Y241302D03*
X1265065Y249982D03*
X1256494Y243177D03*
X1256574Y238662D03*
X1266518Y237042D03*
X1256584Y248002D03*
X1256454Y252122D03*
X1264854Y253996D03*
Y256496D03*
X1258883Y280558D03*
X1258250Y292986D03*
X1263150Y294726D03*
X1255150Y306211D03*
X1256220Y434362D03*
X1261220Y454362D03*
X1253220Y451362D03*
X1267220D03*
X1260220Y477362D03*
X1255920Y511362D03*
X1251650Y520672D03*
X1255150D03*
X1258667Y751405D03*
X1255520Y747362D03*
X1263486Y739949D03*
X1257672Y1351008D03*
X1276820Y58142D03*
X1282360Y58132D03*
X1279580D03*
X1279390Y87697D03*
X1275820Y87962D03*
X1270329Y101011D03*
X1266722Y101005D03*
X1278456Y96187D03*
X1279415Y90847D03*
X1281704Y95402D03*
X1282824Y108872D03*
X1271284Y108971D03*
X1282764Y135398D03*
X1277820Y140682D03*
X1281093Y144516D03*
X1271954Y159143D03*
X1271593Y165962D03*
X1278093Y184462D03*
X1278993Y193262D03*
X1273093Y200038D03*
X1278183Y201262D03*
X1275493Y193962D03*
X1267289Y192167D03*
X1269904Y192692D03*
X1272893Y191262D03*
X1271315Y220701D03*
X1267773Y208373D03*
X1273093Y213962D03*
X1275727Y209597D03*
X1267618Y225382D03*
X1277661Y225685D03*
X1267593Y229462D03*
X1278783Y221386D03*
X1282176Y221436D03*
X1282654Y226309D03*
X1278320Y239292D03*
X1279493Y248662D03*
X1282645Y255671D03*
Y252271D03*
X1277771Y255173D03*
X1273754Y256504D03*
X1276800Y276562D03*
X1269960Y294536D03*
X1271150Y305792D03*
X1272530Y429362D03*
X1284220D03*
X1280270Y434362D03*
X1272220D03*
X1278380Y463362D03*
X1276220Y477362D03*
X1283220D03*
X1269220D03*
X1274420Y463362D03*
X1275576Y730879D03*
X1266727Y752955D03*
X1279788Y1304042D03*
X1279812Y1353552D03*
X1279334Y1356089D03*
X1275856Y1358098D03*
X1271990Y1358079D03*
X1276891Y1362891D03*
X1282928Y1361833D03*
X1269012Y1371693D03*
Y1368293D03*
X1285201Y58121D03*
X1293454Y81232D03*
X1289210D03*
X1298640Y93062D03*
X1292880Y93162D03*
X1292899Y98519D03*
X1294354Y103166D03*
X1291704Y109427D03*
X1288093Y125962D03*
X1291478Y137745D03*
X1286150Y131092D03*
X1297605Y145824D03*
X1285710Y249182D03*
X1290293Y247562D03*
X1288637Y240448D03*
X1292630Y240462D03*
X1291071Y275543D03*
Y278543D03*
X1290005Y293768D03*
Y290268D03*
X1294500Y299692D03*
X1291100D03*
X1291500Y312862D03*
Y315362D03*
X1291420Y320662D03*
Y318162D03*
X1295540Y440902D03*
X1301310Y440862D03*
X1291220Y463362D03*
X1294440Y477267D03*
X1296630Y463462D03*
X1300220Y477362D03*
X1284220Y463362D03*
X1289936Y732539D03*
X1290520Y746562D03*
X1292572Y785575D03*
X1297298Y790982D03*
X1296719Y1290197D03*
X1299169Y1295467D03*
Y1297967D03*
X1296569D03*
Y1295467D03*
Y1292967D03*
X1299169D03*
X1296581Y1300474D03*
X1299181D03*
X1296576Y1303298D03*
X1299176D03*
X1290102Y1365789D03*
X1286102Y1365051D03*
X1294312Y1367279D03*
X1292840Y1364821D03*
X1286102Y1368107D03*
X1298836Y1358387D03*
X1296506Y1357637D03*
X1301820Y58672D03*
X1311424Y68652D03*
X1308174D03*
X1311960Y58152D03*
X1311260Y83032D03*
X1310857Y78542D03*
X1307120Y78562D03*
X1310906Y97807D03*
X1314406Y97756D03*
X1308274Y104162D03*
X1314059Y93877D03*
X1307244Y118452D03*
X1306836Y108242D03*
X1302080Y117032D03*
X1302060Y113852D03*
X1300990Y121812D03*
X1315156Y130656D03*
X1314920Y135361D03*
X1313117Y250605D03*
X1314685Y248651D03*
X1307431Y256099D03*
X1309283Y254162D03*
X1311275Y252297D03*
X1305552Y257974D03*
X1308736Y284948D03*
X1312136D03*
X1307042Y292636D03*
X1303642D03*
X1307442Y306998D03*
X1304042D03*
X1307677Y322996D03*
X1311077D03*
X1317100Y553900D03*
X1308600Y653500D03*
X1303576Y659671D03*
X1311420Y738262D03*
X1305187Y735630D03*
X1315020Y739862D03*
X1307469Y787772D03*
X1301034Y784165D03*
X1304260Y788265D03*
X1309930Y789852D03*
X1306701Y794779D03*
X1305117Y797125D03*
X1309210Y792802D03*
X1315169Y1274887D03*
X1315289Y1269717D03*
X1315229Y1272287D03*
X1304149Y1291317D03*
X1301889Y1284987D03*
X1301829Y1290167D03*
X1301859Y1287587D03*
X1304299Y1280967D03*
X1304269Y1283567D03*
X1304239Y1286147D03*
X1304209Y1288747D03*
X1315176Y1280218D03*
X1315181Y1277594D03*
X1299319Y1290197D03*
X1299349Y1287617D03*
X1301686Y1303268D03*
X1304196Y1299248D03*
X1304189Y1293917D03*
X1304201Y1296624D03*
X1301679Y1292937D03*
Y1295437D03*
Y1297937D03*
X1301691Y1300444D03*
X1311820Y1330518D03*
Y1333018D03*
X1314936Y1338799D03*
X1312650Y1342572D03*
X1308616Y1363345D03*
Y1360445D03*
X1306082Y1359315D03*
X1306182Y1362315D03*
X1304016Y1363945D03*
Y1361045D03*
X1308616Y1357945D03*
X1303496Y1358387D03*
X1301166Y1357637D03*
X1316459Y58697D03*
X1322248Y68487D03*
X1321279Y58767D03*
X1317831Y68652D03*
X1322415Y75480D03*
X1322906Y94212D03*
X1319968Y98266D03*
X1329891Y99455D03*
X1329646Y104954D03*
X1322906Y109733D03*
X1323912Y245111D03*
X1320387Y258901D03*
X1325769Y259001D03*
X1325414Y293556D03*
X1328814D03*
X1319903Y299176D03*
X1323303D03*
X1319618Y318073D03*
X1325080Y323902D03*
X1316218Y318073D03*
X1328480Y323902D03*
X1330101Y540049D03*
X1328530Y747702D03*
X1325210Y744322D03*
X1331519Y1262027D03*
X1331459Y1264597D03*
X1331399Y1267197D03*
X1317889Y1267147D03*
X1320399Y1267117D03*
X1317883Y1269978D03*
X1317895Y1272485D03*
X1320393Y1269948D03*
X1320405Y1272455D03*
X1331177Y1269933D03*
Y1272433D03*
X1317895Y1274985D03*
X1320405Y1274955D03*
X1331177Y1274933D03*
X1331166Y1280248D03*
X1317746D03*
X1320256Y1280218D03*
X1317895Y1277485D03*
X1320405Y1277455D03*
X1331189Y1277440D03*
X1328514Y1334603D03*
X1330844Y1335353D03*
X1322110Y1342755D03*
X1318110Y1342017D03*
X1326320Y1344245D03*
X1324848Y1341787D03*
X1318110Y1345073D03*
X1331288Y1372440D03*
X1327491Y1372358D03*
X1324491Y1372658D03*
X1327491Y1375858D03*
X1331288Y1375940D03*
X1324491Y1375858D03*
X1327491Y1381478D03*
Y1378478D03*
X1331288Y1378560D03*
X1324491Y1381478D03*
Y1378478D03*
X1331304Y1401986D03*
Y1404986D03*
X1327926D03*
X1322228Y1419890D03*
X1322186Y1411326D03*
Y1414326D03*
Y1417326D03*
X1322270Y1422454D03*
X1325084Y1420066D03*
X1325042Y1408502D03*
Y1411502D03*
Y1417502D03*
Y1414502D03*
X1331344Y1414456D03*
X1330804Y1411536D03*
Y1408536D03*
X1331386Y1420020D03*
X1328008D03*
X1331344Y1417456D03*
X1327966Y1408456D03*
Y1411456D03*
Y1417456D03*
Y1414456D03*
X1331428Y1422584D03*
X1328050D03*
X1322312Y1425018D03*
X1325126Y1422630D03*
X1325168Y1425194D03*
X1328092Y1425148D03*
X1331470D03*
X1333190Y58825D03*
X1347640Y101950D03*
X1345583Y91307D03*
X1336549Y105970D03*
X1344631Y127244D03*
X1332497Y133931D03*
X1343034Y141698D03*
X1336761Y293404D03*
X1340161D03*
X1335145Y332616D03*
X1341431Y322693D03*
X1331745Y332616D03*
X1338031Y322693D03*
X1345424Y328981D03*
X1344720Y423162D03*
X1337220D03*
X1342220D03*
X1339720D03*
X1333143Y540049D03*
X1340420Y538422D03*
Y541822D03*
X1347419Y1259257D03*
X1347379Y1256687D03*
X1336269Y1274957D03*
X1333969Y1264567D03*
X1334029Y1261997D03*
X1333909Y1267167D03*
X1336339Y1269777D03*
X1336279Y1272347D03*
X1347359Y1261857D03*
X1347371Y1264564D03*
X1336519Y1264627D03*
X1336579Y1262057D03*
X1347366Y1267188D03*
X1336459Y1267227D03*
X1333687Y1269903D03*
Y1272403D03*
Y1274903D03*
X1333676Y1280218D03*
X1336261Y1277654D03*
X1333699Y1277410D03*
X1343948Y1317092D03*
Y1319592D03*
X1344532Y1328161D03*
X1347397Y1325320D03*
X1336144Y1341147D03*
X1338288Y1339653D03*
X1340488Y1340853D03*
X1336144Y1338247D03*
X1340214Y1334853D03*
X1340410Y1338017D03*
X1338288Y1336553D03*
X1333174Y1334603D03*
X1335504Y1335353D03*
X1334288Y1372440D03*
X1340288D03*
X1346193Y1372523D03*
X1343193D03*
X1337288Y1372440D03*
Y1375940D03*
X1334288D03*
X1343193Y1376023D03*
X1346193D03*
X1340288Y1375940D03*
X1346304Y1401986D03*
X1343304D03*
X1340304D03*
X1337304D03*
X1334304D03*
Y1404986D03*
X1346304D03*
X1343304D03*
X1340304D03*
X1337304D03*
X1337344Y1414456D03*
X1346344D03*
X1343344D03*
X1340344D03*
X1346534Y1411496D03*
Y1408496D03*
X1334344Y1414456D03*
X1346344Y1417456D03*
X1340344D03*
X1337344D03*
X1334386Y1420020D03*
X1334344Y1417456D03*
X1346386Y1420020D03*
X1343386D03*
X1340386D03*
X1337386D03*
X1343344Y1417456D03*
X1337428Y1422584D03*
X1340428D03*
X1343428D03*
X1334428D03*
X1337328Y1425164D03*
X1340328D03*
X1343328D03*
X1346178Y1425254D03*
X1346278Y1422674D03*
X1334470Y1425148D03*
X1348610Y84712D03*
X1349480Y77072D03*
X1366369Y83820D03*
X1349570Y104147D03*
X1353394Y131812D03*
X1348620Y136162D03*
X1349220Y140362D03*
X1348824Y328981D03*
X1358371Y332275D03*
X1361771D03*
X1355200Y337843D03*
X1351800D03*
X1356220Y581862D03*
X1356047Y680000D03*
X1358907Y681262D03*
X1361727Y680665D03*
X1352474Y1256866D03*
X1349964Y1256896D03*
X1352486Y1259373D03*
X1349976Y1259403D03*
X1363258Y1256851D03*
Y1259351D03*
X1349876Y1267158D03*
X1352426Y1267218D03*
X1363266Y1267188D03*
X1349976Y1261903D03*
X1352486Y1261873D03*
Y1264373D03*
X1349976Y1264403D03*
X1363258Y1261851D03*
X1363270Y1264358D03*
X1360593Y1321872D03*
X1363098Y1320951D03*
X1354238Y1329329D03*
X1350238Y1328591D03*
X1358448Y1330819D03*
X1356976Y1328361D03*
X1350238Y1331647D03*
X1352666Y1378560D03*
X1349666D03*
X1352666Y1381560D03*
X1349666D03*
X1352666Y1375940D03*
X1349666D03*
X1352126Y1401986D03*
X1349426D03*
X1352126Y1404986D03*
X1349426D03*
X1349508Y1420020D03*
X1352166Y1420456D03*
Y1414456D03*
Y1411456D03*
Y1408456D03*
Y1417456D03*
X1349466Y1411456D03*
Y1408456D03*
Y1417456D03*
Y1414456D03*
X1349278Y1422674D03*
X1364860Y1455172D03*
X1362410Y1445272D03*
X1378839Y87626D03*
X1366369Y92450D03*
X1366714Y109506D03*
X1376991Y176430D03*
X1373591D03*
X1375619Y236261D03*
X1375257Y229756D03*
X1373493Y227762D03*
X1370207Y682245D03*
X1374938Y1161569D03*
Y1170069D03*
X1379579Y1259317D03*
X1368379Y1259287D03*
X1379639Y1256747D03*
X1368439Y1256717D03*
X1365768Y1256821D03*
Y1259321D03*
X1365776Y1267158D03*
X1368326Y1267218D03*
X1379519Y1261917D03*
X1379531Y1264624D03*
X1379526Y1267248D03*
X1368361Y1264594D03*
X1368369Y1261897D03*
X1365768Y1261821D03*
X1365780Y1264328D03*
X1376076Y1317092D03*
Y1319592D03*
X1379192Y1325373D03*
X1368272Y1324821D03*
X1372538Y1324591D03*
X1370338Y1323091D03*
X1372538Y1321691D03*
X1365376Y1321938D03*
X1367635Y1320904D03*
X1377214Y1327653D03*
X1368272Y1327721D03*
X1370438Y1326091D03*
X1372538Y1327491D03*
X1377054Y1394028D03*
X1367316Y1399053D03*
Y1403458D03*
X1370577Y1421899D03*
X1367436Y1414778D03*
X1370891Y1410306D03*
X1378417Y1415292D03*
X1367316Y1407458D03*
X1367889Y1419235D03*
X1377075Y1425014D03*
X1365235Y1428637D03*
X1370250Y1433715D03*
X1367620Y1431472D03*
X1367170Y1453142D03*
X1368842Y1449261D03*
X1364800Y1449231D03*
X1368980Y1457122D03*
X1370041Y1460374D03*
X1393250Y93802D03*
X1386684Y145017D03*
X1386404Y149008D03*
X1394182Y171470D03*
X1398182D03*
X1395960Y226422D03*
X1393460D03*
X1386868Y222937D03*
X1384017Y223697D03*
X1386138Y225411D03*
X1384895Y221346D03*
X1381951Y221420D03*
X1381235Y236020D03*
X1390600Y248262D03*
X1392685Y498992D03*
X1387550Y502922D03*
X1387600Y499182D03*
X1391260Y507082D03*
X1396081Y1161569D03*
Y1153369D03*
Y1170069D03*
X1384652Y1256866D03*
X1382142Y1256896D03*
X1384664Y1259373D03*
X1382154Y1259403D03*
X1395436Y1256851D03*
Y1259351D03*
X1384586Y1267278D03*
X1395426Y1267188D03*
X1382036Y1267218D03*
X1382154Y1261903D03*
X1384664Y1261873D03*
Y1264373D03*
X1382154Y1264403D03*
X1395436Y1261851D03*
X1395448Y1264358D03*
X1392770Y1321177D03*
X1395100Y1321927D03*
X1386366Y1329329D03*
X1382366Y1328591D03*
X1390576Y1330819D03*
X1389104Y1328361D03*
X1382366Y1331647D03*
X1396311Y1385712D03*
X1398680Y1380582D03*
X1390474Y1385142D03*
X1387074Y1384272D03*
X1390513Y1395452D03*
X1387066Y1401734D03*
X1387291Y1408163D03*
X1387470Y1418302D03*
X1385109Y1410427D03*
X1390170Y1423942D03*
X1387068Y1413991D03*
X1381066Y1425008D03*
X1393630Y1426562D03*
X1388557Y1431645D03*
X1395907Y1430227D03*
X1395443Y1434700D03*
X1398569Y1437860D03*
X1383429Y1427652D03*
X1392620Y1446708D03*
X1389220D03*
X1382600Y1563480D03*
X1391655Y1570037D03*
X1391055Y1565037D03*
X1384840Y1565640D03*
X1386790Y1563610D03*
X1396600Y1590200D03*
Y1586400D03*
X1393000Y1590300D03*
X1395325Y1606862D03*
X1386200Y1645700D03*
X1386600Y1641400D03*
X1407029Y152732D03*
X1410370Y138742D03*
X1406970D03*
X1407029Y156132D03*
X1401341Y177159D03*
X1404829Y184263D03*
X1404741Y177159D03*
X1408229Y184263D03*
X1407178Y171684D03*
X1403778D03*
X1413900Y225212D03*
X1396900Y228932D03*
X1398831Y1161569D03*
Y1153369D03*
Y1170069D03*
X1411909Y1259257D03*
X1400599Y1256717D03*
X1411969Y1256687D03*
X1397946Y1256821D03*
Y1259321D03*
X1400539Y1259287D03*
X1400521Y1264594D03*
X1400529Y1261897D03*
X1397936Y1267158D03*
X1400486Y1267218D03*
X1411849Y1261857D03*
X1411861Y1264564D03*
X1411856Y1267188D03*
X1397946Y1261821D03*
X1397958Y1264328D03*
X1408204Y1317092D03*
Y1319592D03*
X1411320Y1325373D03*
X1400400Y1324821D03*
X1404666Y1324591D03*
X1402466Y1323091D03*
X1404666Y1321691D03*
X1397430Y1321177D03*
X1399760Y1321927D03*
X1408969Y1327645D03*
X1402566Y1326091D03*
X1400400Y1327721D03*
X1404666Y1327491D03*
X1401655Y1384676D03*
X1406461Y1383862D03*
X1415171Y1383692D03*
X1412961Y1387387D03*
X1412608Y1391687D03*
X1414362Y1402191D03*
X1414786Y1426890D03*
X1413440Y1436774D03*
X1409680Y1430613D03*
X1401371Y1434592D03*
X1410477Y1440117D03*
X1410038Y1434670D03*
X1403687Y1444711D03*
X1400287D03*
X1400220Y1518862D03*
X1409248Y1528862D03*
X1400160Y1543342D03*
X1404433Y1565037D03*
X1400695Y1570037D03*
X1400715Y1565037D03*
X1407440Y1557552D03*
X1404433Y1570037D03*
X1402536Y1576097D03*
X1402680Y1597700D03*
X1401300Y1619917D03*
X1410900Y1624800D03*
X1400000Y1626362D03*
Y1634362D03*
Y1638362D03*
X1410500Y1638862D03*
X1396900Y1642100D03*
X1413950Y184263D03*
X1423110D03*
X1417350D03*
X1426510D03*
X1428336Y232762D03*
X1415340Y231812D03*
X1418630Y220018D03*
X1422030D03*
X1413847Y239528D03*
X1426020Y261501D03*
X1431430Y256383D03*
Y264060D03*
X1426647Y329050D03*
X1417022Y621419D03*
X1424119Y1161520D03*
X1426619D03*
X1424119Y1153369D03*
X1426619D03*
Y1169570D03*
X1424119D03*
X1416999Y1256866D03*
X1414489Y1256896D03*
X1417011Y1259373D03*
X1414501Y1259403D03*
X1427783Y1256851D03*
Y1259351D03*
X1414366Y1267158D03*
X1416916Y1267218D03*
X1427786Y1267158D03*
X1414501Y1261903D03*
X1417011Y1261873D03*
Y1264373D03*
X1414501Y1264403D03*
X1427783Y1261851D03*
X1427795Y1264358D03*
X1424898Y1321177D03*
X1427228Y1321927D03*
X1418494Y1329329D03*
X1414494Y1328591D03*
X1422704Y1330819D03*
X1421232Y1328361D03*
X1414494Y1331647D03*
X1418990Y1387452D03*
X1422594Y1383301D03*
X1419995Y1397492D03*
X1415620Y1396652D03*
X1419055Y1392497D03*
X1426872Y1405811D03*
X1423256Y1403728D03*
X1424255Y1396612D03*
X1421480Y1415731D03*
X1422371Y1407722D03*
X1421371Y1411719D03*
X1421864Y1419730D03*
X1419991Y1423404D03*
X1424930Y1433850D03*
X1416272Y1433949D03*
X1421435Y1430415D03*
X1419746Y1435932D03*
X1414350Y1516435D03*
X1426020Y1521535D03*
X1414590Y1532255D03*
X1414350Y1521335D03*
X1427120Y1537355D03*
X1414590Y1537155D03*
X1414740Y1543475D03*
Y1548375D03*
X1427320Y1548575D03*
X1425620Y1556662D03*
X1416060Y1574922D03*
X1422680Y1582100D03*
X1419450Y1596150D03*
X1423700Y1600400D03*
X1434600Y59262D03*
X1444275Y57262D03*
X1432220Y61862D03*
X1440800Y66862D03*
X1447340Y157402D03*
X1442434Y210757D03*
X1430120Y225182D03*
X1431636Y230448D03*
X1444570Y238372D03*
X1431933Y238125D03*
X1431431Y267378D03*
X1436120Y315772D03*
X1436270Y312592D03*
X1436335Y309407D03*
X1436320Y305862D03*
Y303362D03*
X1436050Y321352D03*
X1436120Y318272D03*
X1436232Y344176D03*
X1433418Y729104D03*
X1444099Y1259397D03*
X1432899Y1259257D03*
X1444159Y1256827D03*
X1432959Y1256687D03*
X1430293Y1256821D03*
Y1259321D03*
X1444051Y1264704D03*
X1444039Y1261997D03*
X1444046Y1267328D03*
X1432889Y1261867D03*
X1432881Y1264564D03*
X1432846Y1267188D03*
X1430296Y1267128D03*
X1430293Y1261821D03*
X1430305Y1264328D03*
X1440332Y1317092D03*
Y1319592D03*
X1443448Y1325373D03*
X1432528Y1324821D03*
X1436794Y1324591D03*
X1434594Y1323091D03*
X1436794Y1321691D03*
X1429558Y1321177D03*
X1431888Y1321927D03*
X1441332Y1327793D03*
X1434694Y1326091D03*
X1432528Y1327721D03*
X1436794Y1327491D03*
X1437443Y1406289D03*
X1444997Y1392885D03*
X1435462Y1393009D03*
Y1396409D03*
X1434312Y1415197D03*
X1443112Y1417929D03*
X1445020Y1412672D03*
X1443676Y1432624D03*
X1433750Y1429208D03*
X1439742Y1436924D03*
X1434720Y1454862D03*
X1440440Y1454892D03*
X1444468Y1570610D03*
X1433720Y1569762D03*
X1440105Y1593352D03*
X1446700Y1598400D03*
X1438300Y1606800D03*
Y1602600D03*
X1430250Y1612812D03*
X1441800Y1628700D03*
Y1624500D03*
X1438547Y1638212D03*
X1443617D03*
X1431575Y1634842D03*
X1442573Y1649862D03*
X1442587Y1659242D03*
X1438320Y1668292D03*
X1438220Y1673955D03*
X1446715Y1679957D03*
X1446000Y67802D03*
X1458720Y145362D03*
X1450270Y143022D03*
X1450720Y153362D03*
X1448820Y148092D03*
X1450720Y169862D03*
Y161862D03*
X1449740Y166912D03*
X1450720Y181862D03*
Y177862D03*
Y173862D03*
X1462561Y205982D03*
X1457361D03*
X1459961Y210432D03*
X1456150Y214382D03*
X1449110Y233742D03*
X1455600Y297200D03*
X1456770Y342942D03*
X1460849Y343327D03*
X1462790Y359042D03*
X1462870Y355012D03*
X1449777Y362021D03*
X1459900Y370823D03*
X1455920Y373941D03*
X1463600Y374462D03*
X1449777Y371039D03*
X1455642Y409646D03*
X1449296Y407347D03*
X1449600Y402322D03*
X1456777Y418596D03*
Y426546D03*
X1456237Y726945D03*
X1457620Y736195D03*
X1460187Y729805D03*
X1455692Y731401D03*
X1457714Y741622D03*
X1447149Y1161569D03*
X1449649D03*
X1447299Y1153369D03*
X1449799D03*
X1447149Y1170069D03*
X1449649D03*
X1449176Y1256866D03*
X1446666Y1256896D03*
X1449188Y1259373D03*
X1446678Y1259403D03*
X1459960Y1259351D03*
Y1256851D03*
X1449106Y1267358D03*
X1459886Y1267218D03*
X1446556Y1267298D03*
X1446678Y1261903D03*
X1449188Y1261873D03*
Y1264373D03*
X1446678Y1264403D03*
X1459960Y1261851D03*
X1459972Y1264358D03*
X1457026Y1321177D03*
X1461686D03*
X1459356Y1321927D03*
X1450622Y1329329D03*
X1446622Y1328591D03*
X1454832Y1330819D03*
X1453360Y1328361D03*
X1446622Y1331647D03*
X1459968Y1402765D03*
X1451176Y1399026D03*
X1451198Y1403047D03*
X1460224Y1407545D03*
X1458138Y1409955D03*
X1461062Y1413246D03*
X1455006Y1447938D03*
X1459111Y1445669D03*
Y1448669D03*
X1457577Y1526689D03*
X1457817Y1542509D03*
X1457967Y1553729D03*
X1458200Y1565037D03*
Y1560037D03*
X1448620Y1556162D03*
X1456030Y1590302D03*
X1456120Y1586262D03*
X1453600Y1595662D03*
X1451500Y1612800D03*
X1454167Y1638302D03*
X1459127D03*
X1448507Y1638212D03*
X1448920Y1675062D03*
X1474142Y61767D03*
X1462000Y153362D03*
X1470220Y169862D03*
X1473090Y204502D03*
X1472335Y209362D03*
X1467761Y205982D03*
X1471308Y230640D03*
X1463833Y230448D03*
X1474660Y252878D03*
X1463808Y244948D03*
X1463833Y235566D03*
X1473820Y265962D03*
X1471510Y252878D03*
X1471690Y259862D03*
X1463950Y258172D03*
X1463330Y264060D03*
X1463510Y273878D03*
X1475452Y289708D03*
X1475352Y306308D03*
X1476826Y312177D03*
X1467700Y370953D03*
X1472758Y370817D03*
X1465836Y408668D03*
X1470942Y409718D03*
X1475250Y401812D03*
X1469777Y418396D03*
X1469951Y429251D03*
X1469720Y434542D03*
X1469760Y452622D03*
X1471460Y633402D03*
X1468060D03*
X1465171Y647132D03*
X1469020Y647102D03*
X1470841Y721493D03*
X1464999Y1259317D03*
X1476369Y1259237D03*
X1465059Y1256747D03*
X1462470Y1259321D03*
Y1256821D03*
X1476291Y1275224D03*
X1464946Y1267248D03*
X1464989Y1261927D03*
X1464981Y1264624D03*
X1476339Y1264467D03*
Y1267037D03*
X1476309Y1261807D03*
X1476279Y1269637D03*
X1476291Y1272344D03*
X1462396Y1267188D03*
X1462470Y1261821D03*
X1462482Y1264328D03*
X1476291Y1278104D03*
X1464016Y1321927D03*
X1466819Y1324018D03*
X1469019Y1322618D03*
X1473956Y1341068D03*
X1472460Y1330493D03*
Y1333043D03*
X1475576Y1338799D03*
X1469019Y1325518D03*
X1464680Y1325772D03*
X1469019Y1328418D03*
X1466919Y1327018D03*
X1464680Y1328672D03*
X1467567Y1445669D03*
Y1448669D03*
X1475967Y1445669D03*
Y1448669D03*
X1478320Y1522962D03*
X1472565Y1623635D03*
X1478061Y1633864D03*
X1463767Y1638302D03*
X1476570Y1661124D03*
X1493120Y240412D03*
X1487958Y236062D03*
X1490060Y255378D03*
X1485320Y260362D03*
X1478745Y281508D03*
X1493289Y280027D03*
X1478526Y289677D03*
X1481445Y289708D03*
X1479745Y312208D03*
X1478426Y306277D03*
X1481345Y306308D03*
X1481484Y361688D03*
X1481766Y372288D03*
X1489443D03*
X1494784Y374188D03*
X1486040Y368392D03*
X1481766Y406238D03*
X1490384Y407292D03*
X1493384Y411313D03*
X1482650Y411190D03*
X1495527Y406215D03*
X1486880Y416863D03*
X1484805Y427577D03*
X1489310Y426822D03*
X1481539Y1259377D03*
X1478999Y1259257D03*
X1481479Y1261947D03*
X1481419Y1264547D03*
X1481431Y1267254D03*
X1478939Y1261827D03*
X1478879Y1264427D03*
X1478891Y1267134D03*
X1481359Y1271447D03*
X1492039D03*
X1481359Y1274144D03*
X1492091D03*
X1478859Y1271417D03*
Y1274114D03*
X1481361Y1280054D03*
X1492101D03*
X1478821D03*
X1481359Y1277024D03*
X1492091D03*
X1478859Y1276994D03*
X1489154Y1334603D03*
X1493814D03*
X1491484Y1335353D03*
X1482750Y1342755D03*
X1478750Y1342017D03*
X1486960Y1344245D03*
X1485488Y1341787D03*
X1478750Y1345073D03*
X1485387Y1420002D03*
X1481918Y1425579D03*
X1484442Y1445557D03*
Y1448557D03*
X1482830Y1525162D03*
X1480800Y1663600D03*
X1510500Y125992D03*
X1508959Y215802D03*
X1503020D03*
X1499922Y211240D03*
X1496720Y225292D03*
X1504484Y234562D03*
X1508410Y230842D03*
X1510017Y225516D03*
X1501840Y225502D03*
X1512420Y239116D03*
X1510810Y249742D03*
X1509040Y243362D03*
X1504890Y249862D03*
X1506600Y239092D03*
X1504650Y254392D03*
X1508049Y280056D03*
X1498984Y282797D03*
X1508558Y291175D03*
X1512244Y311522D03*
X1505922Y304583D03*
X1509539Y308467D03*
X1498184Y361723D03*
Y369798D03*
X1495150Y369842D03*
X1503450Y385843D03*
X1509638Y738627D03*
X1509350Y741315D03*
X1504747Y747293D03*
X1503514Y801361D03*
Y797961D03*
X1497199Y1275667D03*
X1497259Y1273097D03*
X1494629Y1271477D03*
X1494631Y1274144D03*
X1506569Y1285947D03*
X1508819Y1284797D03*
X1506539Y1288557D03*
X1508759Y1287367D03*
X1508699Y1289967D03*
X1494641Y1280054D03*
X1494631Y1277024D03*
X1506551Y1291254D03*
X1497199Y1278277D03*
X1497161Y1280974D03*
X1506689Y1283377D03*
X1506591Y1297014D03*
Y1294134D03*
X1508711Y1295554D03*
Y1298434D03*
Y1292674D03*
X1496784Y1341147D03*
X1498924Y1334882D03*
X1498950Y1339517D03*
X1501149Y1336287D03*
X1496784Y1338247D03*
X1496144Y1335353D03*
X1504588Y1353316D03*
Y1355816D03*
X1501033Y1341462D03*
X1498959Y1342930D03*
X1505570Y1364212D03*
X1507704Y1361597D03*
X1510027Y1425825D03*
X1507617Y1424045D03*
X1522920Y116180D03*
X1513900Y117762D03*
X1518575Y138662D03*
X1521115Y193262D03*
X1524539Y215551D03*
X1522009Y210825D03*
X1518110Y215551D03*
X1526998Y209645D03*
X1527732Y219488D03*
X1514520Y231116D03*
X1526152Y225114D03*
X1514593Y249698D03*
Y235116D03*
X1519758Y265161D03*
X1522786Y262558D03*
X1522258Y265161D03*
X1519833Y277297D03*
X1522258Y288956D03*
X1517669Y291516D03*
X1515940Y795815D03*
Y799215D03*
X1513789Y1290037D03*
X1511289Y1287397D03*
X1511199Y1290007D03*
X1513791Y1292704D03*
X1516351D03*
X1513791Y1298464D03*
Y1295584D03*
X1516351D03*
Y1298464D03*
X1511251Y1292704D03*
Y1298464D03*
Y1295584D03*
X1521282Y1357401D03*
X1525942D03*
X1514878Y1365553D03*
X1510878Y1364815D03*
X1519088Y1367043D03*
X1517616Y1364585D03*
X1510878Y1367871D03*
X1523612Y1358151D03*
X1512177Y1427795D03*
X1516137Y1432135D03*
X1513657Y1429985D03*
X1544010Y27552D03*
X1536310Y47492D03*
X1534060Y100162D03*
X1530660D03*
X1533520Y110662D03*
X1529500Y122122D03*
X1535575Y118862D03*
X1540090Y122782D03*
X1536925Y129937D03*
X1529500Y125862D03*
X1535520Y151562D03*
X1529233Y153162D03*
X1535450Y155262D03*
X1542401Y141561D03*
X1534720Y199803D03*
X1528720Y199862D03*
X1533385Y193108D03*
X1533148Y211614D03*
X1531824Y207677D03*
X1534194Y217519D03*
X1529670Y225522D03*
X1535561Y225393D03*
X1531110Y264862D03*
X1539150Y267132D03*
X1540958Y307756D03*
X1539720Y589862D03*
Y581862D03*
X1540377Y634165D03*
X1541211Y646178D03*
X1533178Y1360815D03*
X1530978Y1359315D03*
X1528912Y1361045D03*
X1531078Y1362315D03*
X1533178Y1363715D03*
X1528912Y1363945D03*
X1533178Y1357915D03*
X1528272Y1358151D03*
X1552960Y124359D03*
X1553189Y127781D03*
X1556049Y147711D03*
X1545763Y159305D03*
X1551160Y189342D03*
X1557900Y220362D03*
X1557760Y214792D03*
X1550353Y217352D03*
X1557320Y203297D03*
X1559400Y229832D03*
X1545668Y305266D03*
X1545768Y302766D03*
X1543958Y307556D03*
X1546458Y307856D03*
X1543858Y310056D03*
X1543720Y581862D03*
X1548720D03*
X1552720Y589862D03*
Y581862D03*
X1554753Y628860D03*
X1553312Y636815D03*
X1559354Y655716D03*
Y659116D03*
X1550487Y681565D03*
X1550320Y696562D03*
X1550917Y704332D03*
X1550390Y709885D03*
X1573560Y245078D03*
X1574760Y251032D03*
X1559722Y243110D03*
X1570675Y267857D03*
X1573246Y306650D03*
X1572396Y309450D03*
X1563714Y572792D03*
X1567114D03*
X1559557Y593290D03*
X1564768Y708159D03*
X1562871Y732316D03*
Y735716D03*
X1571577Y747145D03*
X1567547Y755485D03*
X1571920Y762662D03*
X1568490Y758162D03*
X1570374Y760093D03*
X1576589Y300927D03*
X1588314Y592553D03*
X1585714D03*
X1583114D03*
X1590914D03*
X1588254Y595103D03*
X1588284Y597613D03*
X1585654Y595103D03*
X1585684Y597613D03*
X1583084D03*
X1583054Y595103D03*
X1588284Y608655D03*
X1585684D03*
X1583084D03*
X1590854Y595103D03*
X1590884Y597613D03*
Y608655D03*
X1588254Y613715D03*
X1588224Y611205D03*
X1585654Y613715D03*
X1585624Y611205D03*
X1583024D03*
X1583054Y613715D03*
X1590854D03*
X1590824Y611205D03*
X1591368Y628727D03*
X1591428Y626177D03*
X1588928D03*
X1588868Y628727D03*
X1591398Y631237D03*
X1588898D03*
X1591368Y650877D03*
X1591338Y648367D03*
X1591398Y645817D03*
X1588868Y650877D03*
X1588838Y648367D03*
X1588898Y645817D03*
X1591368Y653377D03*
X1588868D03*
X1591448Y657677D03*
X1588948D03*
Y660177D03*
X1591448D03*
X1588968Y665237D03*
X1591468D03*
X1588938Y662727D03*
X1591438D03*
X1588938Y679807D03*
X1588878Y682357D03*
X1588908Y684867D03*
X1591438Y679807D03*
X1591378Y682357D03*
X1591408Y684867D03*
X1591328Y696727D03*
X1591388Y694177D03*
X1588888D03*
X1588828Y696727D03*
X1591358Y699277D03*
X1588858D03*
X1591358Y718837D03*
X1591328Y716327D03*
X1591388Y713777D03*
X1588858Y718837D03*
X1588828Y716327D03*
X1588888Y713777D03*
X1590915Y755793D03*
X1603747Y192951D03*
X1603530Y202402D03*
X1603706Y211526D03*
X1603580Y206902D03*
X1604200Y234642D03*
X1604240Y227892D03*
X1603920Y222922D03*
X1604270Y231490D03*
X1604240Y238242D03*
X1602980Y560002D03*
X1593514Y592553D03*
X1601830Y590685D03*
X1604430D03*
X1607200Y583962D03*
X1593484Y597613D03*
X1593454Y595103D03*
X1593484Y608655D03*
X1593424Y611205D03*
X1593454Y613715D03*
X1601830Y615201D03*
X1604430D03*
X1598868Y628727D03*
X1598928Y626177D03*
X1593868Y628727D03*
X1593928Y626177D03*
X1596428D03*
X1596368Y628727D03*
X1598898Y631237D03*
X1593898D03*
X1596398D03*
X1598868Y650877D03*
X1598838Y648367D03*
X1596368Y650877D03*
X1593868D03*
X1596338Y648367D03*
X1593838D03*
X1598898Y645817D03*
X1596398D03*
X1593898D03*
X1598868Y653377D03*
X1596368D03*
X1593868D03*
X1598948Y657677D03*
X1593948D03*
X1596448D03*
Y660177D03*
X1593948D03*
X1598948D03*
X1596468Y665237D03*
X1593968D03*
X1598968D03*
X1596438Y662727D03*
X1593938D03*
X1598938D03*
X1593938Y679807D03*
X1596438D03*
X1593878Y682357D03*
X1596378D03*
X1593908Y684867D03*
X1596408D03*
X1598878Y682357D03*
X1598908Y684867D03*
X1598938Y679807D03*
X1596288Y688902D03*
X1598888D03*
X1598828Y696727D03*
X1593828D03*
X1593888Y694177D03*
X1596388D03*
X1596328Y696727D03*
X1593858Y699277D03*
X1596358D03*
X1598888Y694177D03*
X1596288Y691502D03*
X1598858Y699277D03*
X1598888Y691502D03*
X1598858Y718837D03*
X1598828Y716327D03*
X1596358Y718837D03*
X1593858D03*
X1596328Y716327D03*
X1593828D03*
X1596388Y713777D03*
X1593888D03*
X1598888D03*
X1596250Y721452D03*
X1598850D03*
X1599010Y724002D03*
X1598440Y736692D03*
X1592760Y736652D03*
X1595600D03*
X1606788Y756199D03*
X1602788D03*
X1621920Y25962D03*
X1622220Y49862D03*
X1623881Y129627D03*
X1610788Y756199D03*
X1614788D03*
X1618788D03*
X1615062Y1421241D03*
X1613047Y1415669D03*
X1614927Y1426076D03*
Y1429896D03*
X1624353Y1428766D03*
Y1431316D03*
X1617215Y1440822D03*
X1633111Y206693D03*
X1632342Y216015D03*
X1635835Y343002D03*
X1636800Y429982D03*
X1639800D03*
X1636800Y426982D03*
X1639800D03*
X1636800Y438982D03*
X1639800D03*
X1636800Y435982D03*
X1639800D03*
X1636800Y432982D03*
X1639800D03*
X1638928Y756199D03*
X1630928D03*
X1634928D03*
X1638277Y1269065D03*
X1640812Y1270020D03*
X1631203Y1367492D03*
X1628653D03*
X1626153D03*
X1628653Y1372492D03*
X1631203D03*
X1626153D03*
X1631203Y1369992D03*
X1628653D03*
X1626153D03*
X1628653Y1379992D03*
Y1382492D03*
Y1377492D03*
Y1374992D03*
X1631203Y1377492D03*
Y1374992D03*
Y1379992D03*
Y1382492D03*
X1626153Y1379992D03*
Y1382492D03*
Y1374992D03*
Y1377492D03*
X1630643Y1440290D03*
X1627469Y1437072D03*
X1624853Y1440875D03*
X1634643Y1442982D03*
X1638785Y1442483D03*
X1637042Y1440215D03*
X1630643Y1443090D03*
X1635315Y1465745D03*
Y1462745D03*
X1632315Y1468745D03*
X1629815D03*
X1632315Y1465745D03*
X1629815D03*
X1632315Y1462745D03*
X1629815D03*
X1635315Y1468745D03*
Y1460245D03*
X1629815D03*
X1632315D03*
X1629815Y1457745D03*
X1632315D03*
X1635315D03*
X1639645Y1473645D03*
X1650020Y408952D03*
X1647310Y408922D03*
X1650020Y411452D03*
X1647310Y411422D03*
X1654110Y434177D03*
X1657755Y517910D03*
X1651851Y532057D03*
X1651112Y545572D03*
X1645530Y549160D03*
X1653230Y549322D03*
X1642720Y560862D03*
X1656238Y592113D03*
X1649833Y594946D03*
X1653794Y594956D03*
X1653774Y598576D03*
X1649844Y598555D03*
X1656955Y611090D03*
X1645300Y612202D03*
X1653220Y620662D03*
X1645681Y624011D03*
X1648581D03*
X1651481D03*
X1654809Y638101D03*
X1653319Y642311D03*
X1652351Y639573D03*
X1648811Y628277D03*
X1647081Y626211D03*
X1645917Y628917D03*
Y633577D03*
X1645167Y631247D03*
Y635907D03*
X1650081Y626111D03*
X1651711Y628277D03*
X1651635Y651836D03*
X1652581Y646311D03*
X1643582Y652601D03*
X1655637Y646311D03*
X1641082Y652601D03*
X1649363Y649485D03*
X1654809Y672101D03*
X1652351Y673573D03*
X1645681Y658011D03*
X1648581D03*
X1648811Y662277D03*
X1647081Y660211D03*
X1645917Y662917D03*
Y667577D03*
X1645167Y665247D03*
Y669907D03*
X1650081Y660111D03*
X1651481Y658011D03*
X1651711Y662277D03*
X1641082Y686601D03*
X1651635Y685836D03*
X1652581Y680311D03*
X1653319Y676311D03*
X1643582Y686601D03*
X1655113Y680835D03*
X1649363Y683485D03*
X1654809Y706101D03*
X1648811Y696277D03*
X1645167Y703907D03*
X1645917Y701577D03*
X1645167Y699247D03*
X1645917Y696917D03*
X1650081Y694111D03*
X1645681Y692011D03*
X1647081Y694211D03*
X1648581Y692011D03*
X1651711Y696277D03*
X1651481Y692011D03*
X1641082Y720601D03*
X1651635Y719836D03*
X1652581Y714311D03*
X1653319Y710311D03*
X1652351Y707573D03*
X1643582Y720601D03*
X1655637Y714311D03*
X1649363Y717485D03*
X1651509Y756492D03*
X1650771Y1367492D03*
X1648271D03*
X1645721D03*
X1648271Y1372492D03*
X1650771D03*
X1645721D03*
X1650771Y1369992D03*
X1648271D03*
X1645721D03*
X1648271Y1379992D03*
Y1382492D03*
X1650771Y1379992D03*
Y1382492D03*
X1648271Y1377492D03*
Y1374992D03*
X1650771Y1377492D03*
Y1374992D03*
X1645721Y1377492D03*
Y1374992D03*
Y1379992D03*
Y1382492D03*
X1641047Y1432876D03*
X1645707D03*
X1643377Y1433626D03*
X1648037D03*
X1655762Y1429794D03*
X1648677Y1436220D03*
X1653243Y1435690D03*
X1651043Y1434190D03*
X1653243Y1432790D03*
X1651143Y1437190D03*
X1653243Y1438590D03*
X1648677Y1439120D03*
X1655295Y1453879D03*
X1652295D03*
X1643065Y1462645D03*
Y1465645D03*
Y1468645D03*
Y1460145D03*
Y1457645D03*
X1655295Y1456899D03*
X1652295D03*
X1642645Y1473645D03*
X1646958Y1501553D03*
X1668100Y180852D03*
X1667739Y187187D03*
X1666690Y193290D03*
X1674432Y216981D03*
X1672596Y220541D03*
X1668426Y222432D03*
X1664866Y225162D03*
X1660861Y227548D03*
X1664970Y472112D03*
X1662447Y480619D03*
X1665790Y523417D03*
X1662262Y537334D03*
X1659740Y542222D03*
X1661872Y534703D03*
X1660243Y532071D03*
X1668917Y549992D03*
X1666902Y555115D03*
X1663502D03*
X1658738Y592113D03*
X1661238D03*
X1664197Y602191D03*
X1669222Y604490D03*
X1670700Y594562D03*
X1672500Y596462D03*
X1660660Y602273D03*
X1664410Y617953D03*
X1668920Y617637D03*
X1660754Y609837D03*
X1669397Y614064D03*
X1663471Y609837D03*
X1666686Y757162D03*
X1669303Y1372492D03*
X1664253D03*
X1666753D03*
X1669303Y1367492D03*
Y1369992D03*
X1666753Y1367492D03*
X1664253D03*
Y1369992D03*
X1666753D03*
X1669303Y1379992D03*
Y1382492D03*
Y1377492D03*
Y1374992D03*
X1666753Y1379992D03*
X1664253D03*
X1666753Y1382492D03*
X1664253D03*
X1666753Y1377492D03*
X1664253D03*
Y1374992D03*
X1666753D03*
X1662496Y1428791D03*
Y1431291D03*
X1665612Y1437072D03*
X1662996Y1440922D03*
X1672786Y1442982D03*
X1668786Y1440290D03*
Y1443256D03*
X1657920Y1453405D03*
X1660920D03*
X1657860Y1466545D03*
Y1464045D03*
X1657950Y1456210D03*
X1657860Y1459045D03*
Y1461545D03*
X1660950Y1456210D03*
X1660860Y1466545D03*
Y1464045D03*
Y1459045D03*
Y1461545D03*
X1666123Y1493362D03*
Y1501362D03*
Y1533862D03*
Y1520862D03*
Y1545862D03*
X1671673Y1550815D03*
X1666123Y1557557D03*
X1666198Y1561557D03*
X1671660Y1569412D03*
X1666198Y1581321D03*
X1678994Y217231D03*
X1690208Y421855D03*
X1689095Y462640D03*
X1684940Y463030D03*
X1685779Y491230D03*
X1690229Y481845D03*
X1687238Y485496D03*
X1681817Y495290D03*
X1675664Y513802D03*
X1690999Y513107D03*
X1683702Y514687D03*
X1676600Y523902D03*
X1688768Y518107D03*
X1689544Y543874D03*
X1689506Y539882D03*
X1679941Y552222D03*
X1678860Y556752D03*
X1683369Y562698D03*
Y566098D03*
X1676644Y655345D03*
Y652745D03*
X1679244Y655345D03*
X1681864Y655286D03*
X1679244Y652745D03*
X1676624Y642404D03*
X1676644Y644945D03*
Y647545D03*
Y650145D03*
X1679244Y642345D03*
X1681864Y642286D03*
X1679244Y644945D03*
Y647545D03*
X1681864Y644886D03*
Y647486D03*
Y650086D03*
Y652686D03*
X1679244Y650145D03*
X1673860Y726522D03*
X1681810Y752955D03*
X1688912Y1372492D03*
X1686362D03*
Y1367492D03*
Y1369992D03*
X1688912Y1367492D03*
Y1369992D03*
Y1377492D03*
Y1374992D03*
Y1382492D03*
Y1379992D03*
X1686362D03*
Y1382492D03*
Y1374992D03*
Y1377492D03*
X1679190Y1432876D03*
X1683850D03*
X1681520Y1433626D03*
X1686180D03*
X1686820Y1436520D03*
X1688886Y1434790D03*
X1688986Y1437790D03*
X1676928Y1442483D03*
X1675185Y1440215D03*
X1686820Y1439420D03*
X1680720Y1487062D03*
X1679508Y1498303D03*
X1678340Y1500862D03*
X1679508Y1517803D03*
X1677930Y1520362D03*
X1679508Y1538803D03*
X1678340Y1541362D03*
X1678230Y1590542D03*
X1674220Y1585321D03*
X1703617Y26459D03*
X1700217D03*
X1703570Y50649D03*
X1700170D03*
X1702490Y204780D03*
X1704223Y209707D03*
Y212207D03*
X1701164Y209758D03*
X1698566Y214904D03*
X1696066D03*
X1693725Y217409D03*
X1698566Y212404D03*
X1696066D03*
X1698725Y217409D03*
X1696225D03*
X1701164Y212258D03*
X1704264Y217458D03*
X1701264D03*
X1704264Y214958D03*
X1701264D03*
X1698566Y209704D03*
X1696066D03*
X1693466Y209504D03*
Y214704D03*
Y212204D03*
X1693725Y219909D03*
X1698725D03*
X1696225D03*
X1704264Y219958D03*
X1701264D03*
X1704185Y222710D03*
X1698220Y369652D03*
X1699809Y403985D03*
X1695579D03*
X1702959Y404243D03*
X1707780Y410738D03*
X1697161Y406602D03*
X1692429Y403985D03*
X1701124Y423802D03*
X1694050Y416643D03*
X1695455Y422287D03*
X1707544Y431745D03*
X1707568Y420370D03*
X1690140Y434160D03*
X1693720Y455862D03*
X1697220D03*
X1702127Y468719D03*
X1693236Y472650D03*
X1691151Y493678D03*
X1689943Y479304D03*
X1701811Y501318D03*
X1701635Y497177D03*
X1699300Y498632D03*
X1697210Y500802D03*
X1694050Y501422D03*
X1693711Y498527D03*
X1691129Y501697D03*
X1707200Y498962D03*
X1699553Y513107D03*
X1707552Y506731D03*
X1707716Y513562D03*
X1702930Y526102D03*
X1699265Y521507D03*
X1690999Y525507D03*
X1701726Y518107D03*
X1699666Y541507D03*
X1699251Y533642D03*
X1691104Y530503D03*
X1691445Y535011D03*
X1704886Y534564D03*
X1689769Y537339D03*
X1699107Y555783D03*
X1703306Y550064D03*
X1703452Y639381D03*
X1700852D03*
X1698232Y639440D03*
X1700852Y655141D03*
X1703452Y647341D03*
Y649941D03*
Y652541D03*
Y644741D03*
X1700852Y647341D03*
Y649941D03*
Y652541D03*
Y644741D03*
X1698232Y655200D03*
Y644800D03*
Y647400D03*
Y650000D03*
Y652600D03*
X1703452Y641981D03*
X1700852D03*
X1698232Y642040D03*
X1700922Y657781D03*
X1698302Y657840D03*
X1698048Y705662D03*
X1701320Y705678D03*
X1698020Y702962D03*
X1696402Y709533D03*
X1699110Y727452D03*
X1705035Y729210D03*
X1704973Y753019D03*
X1703310Y749455D03*
X1690620Y760702D03*
X1691412Y1372492D03*
Y1367492D03*
Y1369992D03*
Y1377492D03*
Y1374992D03*
Y1382492D03*
Y1379992D03*
X1691086Y1436290D03*
Y1433390D03*
X1693392Y1429808D03*
X1691086Y1439190D03*
X1704723Y1500862D03*
Y1520362D03*
Y1541362D03*
X1705003Y1564057D03*
X1707220Y15662D03*
X1715210Y18282D03*
X1714589Y21562D03*
X1709589Y26062D03*
X1719589Y25862D03*
X1717089D03*
X1710106Y48720D03*
Y40020D03*
X1720895Y68062D03*
X1716875D03*
X1712520Y117862D03*
X1712720Y111862D03*
X1719943Y112667D03*
Y116667D03*
X1713418Y130862D03*
X1721418Y135327D03*
X1717418D03*
X1714490Y142920D03*
X1717140Y148910D03*
X1711700Y140200D03*
X1717619Y165909D03*
X1718110Y159040D03*
X1719530Y162950D03*
X1722078Y189483D03*
X1720310Y191252D03*
X1707159Y217580D03*
Y215080D03*
Y210080D03*
Y222580D03*
Y225080D03*
Y220080D03*
X1713720Y381152D03*
X1717220D03*
X1719200Y371162D03*
X1713720Y391652D03*
Y384652D03*
Y388152D03*
X1717220Y391652D03*
Y388152D03*
Y384652D03*
X1709000Y413362D03*
X1706500D03*
X1709000Y415862D03*
X1706500D03*
X1721220Y458362D03*
X1713977Y457137D03*
X1708977Y458542D03*
X1721936Y469263D03*
X1716134Y478443D03*
X1715711Y474399D03*
X1713977Y470804D03*
X1708977D03*
X1716148Y483720D03*
X1716087Y495665D03*
X1716156Y487685D03*
X1716278Y491676D03*
X1707552Y503331D03*
X1709844Y516106D03*
X1707610Y534113D03*
X1709356Y541144D03*
X1709680Y545432D03*
X1716110Y532632D03*
X1707346Y547504D03*
X1717987Y569705D03*
X1716480Y691410D03*
X1710550Y691327D03*
X1712824Y696476D03*
X1710122Y703509D03*
X1713920Y700962D03*
X1709828Y719283D03*
X1713450Y728222D03*
X1719727Y1472088D03*
X1726720Y49862D03*
X1733720D03*
X1730220D03*
X1736040Y41792D03*
X1732810Y52482D03*
X1736040Y44292D03*
X1730140Y52552D03*
X1727600Y52582D03*
X1725320Y67962D03*
X1723018Y101667D03*
X1723218Y93267D03*
X1738220Y98862D03*
X1736720Y101862D03*
X1729080Y118132D03*
X1739720Y120892D03*
X1728999Y112895D03*
X1730765Y151362D03*
X1733920D03*
X1723670Y149102D03*
X1728320Y169862D03*
X1723090Y173072D03*
Y177072D03*
X1734857Y184865D03*
X1737470Y177147D03*
X1737500Y217962D03*
Y214962D03*
Y211962D03*
Y208962D03*
Y226962D03*
Y223962D03*
Y220962D03*
X1725344Y359334D03*
X1728300Y377787D03*
X1733780Y390620D03*
X1729810D03*
X1737660D03*
X1734290Y423820D03*
X1727700Y417265D03*
X1739316Y480939D03*
X1730954Y478062D03*
X1725522Y482869D03*
X1733354Y490869D03*
Y486869D03*
X1738014Y1287344D03*
X1724431Y1336311D03*
X1734717Y1404340D03*
X1729700Y1462932D03*
X1733200D03*
X1736700D03*
X1736400Y1458942D03*
Y1455442D03*
X1731600Y1457230D03*
X1726120Y1490262D03*
X1726149Y1496270D03*
X1724649Y1513945D03*
X1727674D03*
X1729310Y1520951D03*
X1735310D03*
X1724649Y1505895D03*
X1727674D03*
X1726310Y1530445D03*
X1732310D03*
X1729310D03*
X1735310D03*
X1726310Y1520951D03*
X1732310D03*
X1751065Y39017D03*
X1754620Y39062D03*
X1747720Y31862D03*
Y34362D03*
X1740858Y72330D03*
Y79830D03*
Y74830D03*
Y82330D03*
X1745220Y98862D03*
X1741720D03*
X1743720Y101862D03*
X1740220D03*
X1748720Y97362D03*
X1745010Y122952D03*
X1750820Y119972D03*
X1738520Y151362D03*
X1751220Y147562D03*
X1748465D03*
X1754120Y171562D03*
X1750920Y171662D03*
X1754234Y190836D03*
X1752078Y216728D03*
X1740500Y217962D03*
Y214962D03*
Y211962D03*
Y208962D03*
X1747600Y209062D03*
X1744600D03*
X1751800Y206762D03*
X1752078Y226728D03*
Y224228D03*
Y221728D03*
Y219228D03*
X1740500Y226962D03*
Y223962D03*
Y220962D03*
X1746484Y279682D03*
X1749450Y293862D03*
X1756204Y301695D03*
X1752000Y306562D03*
X1756933Y372452D03*
X1744380Y382892D03*
X1744510Y377452D03*
X1747080Y435870D03*
X1746720Y464862D03*
X1752316Y703969D03*
Y695669D03*
X1752217Y692988D03*
X1752276Y720529D03*
X1752316Y712269D03*
X1747814Y1287344D03*
X1742714Y1287244D03*
X1754165Y1304422D03*
Y1307422D03*
Y1301422D03*
Y1295422D03*
Y1298422D03*
Y1310422D03*
X1738740Y1451742D03*
X1740200Y1462932D03*
X1745111Y1463262D03*
X1747677Y1507388D03*
X1744677D03*
X1747304Y1524976D03*
X1744304D03*
X1762420Y21562D03*
X1765238Y22062D03*
X1768026Y24165D03*
X1769669Y15244D03*
X1761998Y15187D03*
X1765260Y18262D03*
X1757320Y15872D03*
X1758672Y26431D03*
X1755272D03*
X1767220Y26962D03*
X1758669Y50649D03*
X1755269D03*
X1762738Y53262D03*
X1767220Y53342D03*
X1767185Y48817D03*
X1767400Y39915D03*
X1769274Y50742D03*
X1771774Y53682D03*
X1758063Y72623D03*
X1767170Y83607D03*
X1767990Y76797D03*
X1760478Y90027D03*
X1770368Y72691D03*
X1757978Y116727D03*
X1760978D03*
X1763678Y106127D03*
X1769278Y108027D03*
Y110927D03*
Y113727D03*
X1755978Y108427D03*
Y111027D03*
X1760478Y106127D03*
X1758300Y128242D03*
X1763435Y166862D03*
X1765820Y182282D03*
X1767300Y174587D03*
X1755078Y216928D03*
X1761500Y214062D03*
X1765000D03*
X1768500D03*
X1755078Y219428D03*
Y221928D03*
Y224428D03*
X1760104Y301648D03*
X1761936Y310709D03*
X1769230Y310478D03*
X1756800Y364048D03*
Y368048D03*
X1770280Y372452D03*
X1770220Y377452D03*
Y382952D03*
X1757066Y435721D03*
X1757650Y461393D03*
X1768560Y539042D03*
X1766060D03*
X1768317Y686375D03*
X1755112Y703948D03*
Y695648D03*
X1755013Y692967D03*
X1757612Y703948D03*
Y695648D03*
X1755072Y720508D03*
X1755112Y712248D03*
X1757572Y720508D03*
X1757612Y712248D03*
X1757165Y1304422D03*
X1760165D03*
Y1307422D03*
X1757165D03*
X1769165Y1301422D03*
X1766165D03*
X1763165D03*
X1757165D03*
X1760165D03*
X1769165Y1295422D03*
X1766165D03*
X1763165D03*
X1760165D03*
X1757165D03*
X1760165Y1298422D03*
X1757165D03*
X1763165D03*
X1766165D03*
X1769165D03*
X1758352Y1317368D03*
Y1322168D03*
X1757165Y1310422D03*
X1760165D03*
X1759987Y1325375D03*
Y1328275D03*
X1763829Y1337548D03*
X1766829D03*
Y1340448D03*
X1769829Y1337548D03*
Y1340448D03*
X1766829Y1343348D03*
X1769829Y1346248D03*
Y1343348D03*
Y1349148D03*
Y1351858D03*
X1782305Y13647D03*
X1775556Y21471D03*
X1775830Y26522D03*
X1777754Y37746D03*
X1781774Y54462D03*
X1774274Y50742D03*
X1776710Y53562D03*
X1779411Y50692D03*
X1774328Y60087D03*
X1779778Y70027D03*
X1774328Y62987D03*
X1775580Y73330D03*
X1779778Y72927D03*
X1787790Y85132D03*
X1781485Y88192D03*
X1785142Y76032D03*
X1773611Y88293D03*
X1778578Y97927D03*
X1778478Y90627D03*
X1784178Y108227D03*
Y111127D03*
Y113927D03*
X1780320Y153162D03*
X1774950Y167392D03*
X1779500Y171692D03*
X1777520Y178403D03*
Y173903D03*
X1782600Y175932D03*
X1778778Y216928D03*
X1783878D03*
X1772000Y214062D03*
X1778778Y219428D03*
Y221928D03*
X1783878Y224428D03*
Y226928D03*
Y219428D03*
Y221928D03*
X1786089Y287641D03*
X1783563D03*
X1777354Y295489D03*
X1783018Y301729D03*
X1782324Y410432D03*
Y403932D03*
Y425432D03*
Y418932D03*
X1782420Y447137D03*
X1781470Y452065D03*
X1778310Y591152D03*
X1781720Y592742D03*
X1778165Y1307422D03*
Y1304422D03*
Y1301422D03*
X1775165D03*
X1772165D03*
X1778165Y1295422D03*
X1775165D03*
X1772165D03*
Y1298422D03*
X1775165D03*
X1778165D03*
X1784165Y1307422D03*
Y1304422D03*
X1781165Y1307422D03*
Y1304422D03*
X1784165Y1301422D03*
Y1295422D03*
Y1298422D03*
X1781165Y1301422D03*
Y1295422D03*
Y1298422D03*
X1781829Y1324448D03*
X1784829D03*
X1778829D03*
X1778165Y1310422D03*
Y1312922D03*
X1784165Y1310422D03*
Y1312922D03*
X1781165Y1310422D03*
Y1312922D03*
X1781829Y1333148D03*
Y1330248D03*
Y1327348D03*
X1784829Y1333148D03*
Y1330248D03*
Y1327348D03*
X1781829Y1337548D03*
Y1340448D03*
X1784829Y1337548D03*
Y1340448D03*
X1778829Y1333148D03*
Y1330248D03*
Y1327348D03*
Y1337548D03*
X1772829D03*
X1775829D03*
X1778829Y1340448D03*
X1775829D03*
X1772829D03*
X1781829Y1346248D03*
Y1343348D03*
Y1349148D03*
Y1351858D03*
Y1354758D03*
X1772829Y1346248D03*
X1775829D03*
X1778829D03*
X1772829Y1343348D03*
X1775829D03*
X1778829D03*
X1772829Y1349148D03*
X1775829D03*
X1778829D03*
X1772829Y1351858D03*
X1775829D03*
X1778829D03*
X1772829Y1354758D03*
X1775829D03*
X1778829D03*
X1799920Y52594D03*
X1788238Y82292D03*
Y78062D03*
Y74912D03*
X1803215Y154032D03*
X1793269Y287641D03*
X1790743D03*
X1791619Y294441D03*
X1789093D03*
X1800160Y362542D03*
X1800340Y387062D03*
X1791494Y386536D03*
X1792450Y410615D03*
X1792507Y403932D03*
X1792220Y425432D03*
X1792335Y418775D03*
X1796020Y451162D03*
X1791888Y683805D03*
X1800450Y1505230D03*
X1795561Y1524729D03*
X1806920Y150862D03*
X1808910Y143902D03*
X1813335Y155435D03*
X1813325Y177257D03*
X1807220Y179897D03*
X1817157Y373829D03*
X1816224Y410432D03*
X1816994Y398052D03*
X1815724Y423932D03*
X1810792Y417432D03*
X1812161Y472521D03*
X1814537Y1322105D03*
X1813700Y1494762D03*
X1807150Y1505675D03*
X1818289Y1501591D03*
X1811494Y1505349D03*
X1813994Y1507891D03*
X1825762Y167662D03*
X1835760Y185772D03*
X1829695Y226333D03*
X1832295D03*
X1827095D03*
X1824095D03*
X1834895D03*
Y223733D03*
X1824095D03*
X1827095D03*
X1832295D03*
X1829695D03*
X1832295Y233933D03*
X1829695D03*
X1827095D03*
X1824095D03*
X1829695Y231433D03*
X1832295D03*
X1829695Y228933D03*
X1832295D03*
X1827095Y231433D03*
X1824095D03*
X1827095Y228933D03*
X1824095D03*
X1834895Y233933D03*
Y231433D03*
Y228933D03*
X1828204Y328654D03*
X1829189Y363731D03*
X1829434Y406348D03*
X1834005Y401421D03*
X1821280Y413432D03*
X1834600Y406442D03*
X1826914Y431718D03*
X1829514Y1498198D03*
Y1500807D03*
X1832114Y1498198D03*
Y1500807D03*
X1824995Y1502201D03*
X1846691Y166450D03*
X1844157Y182210D03*
X1848435Y172187D03*
X1838880Y195162D03*
X1837895Y226333D03*
Y223733D03*
Y233933D03*
Y231433D03*
Y228933D03*
X1836294Y383592D03*
X1838379Y453921D03*
G54D31*
X174685Y647210D03*
X174393Y678354D03*
X195316Y1430034D03*
X383224Y1354446D03*
X412990D03*
X443326D03*
X458600Y1379662D03*
X472700Y1353962D03*
X526478Y1449795D03*
X708795Y1429579D03*
X1131715Y1532913D03*
X1168627Y1466363D03*
X1175215Y1532913D03*
X1359365Y1353946D03*
X1389131D03*
X1419467D03*
X1434200Y1379362D03*
X1449233Y1353946D03*
X1502956Y1449373D03*
X1670101Y1463655D03*
X1682882Y628017D03*
Y678952D03*
X1769790Y204632D03*
X1799350D03*
X1826405Y269763D03*
Y299056D03*
G54D27*
X70472Y173228D03*
Y236220D03*
G54D46*
X450000Y278543D03*
X470000D03*
X483500Y246362D03*
X473500D03*
X480000Y278543D03*
X490000D03*
X500000D03*
X498563Y607067D03*
X510000Y278543D03*
X520000D03*
X518563Y607067D03*
X508563D03*
X549236Y1441207D03*
X569236D03*
X688500Y1611900D03*
Y1621900D03*
X1041435Y143357D03*
X1056225Y143131D03*
X1041435Y163357D03*
X1056225Y163131D03*
X1099970Y1712570D03*
Y1722570D03*
X1689646Y115669D03*
X1679646D03*
X1689646Y125669D03*
Y135669D03*
X1679646Y125669D03*
Y135669D03*
X1689646Y145669D03*
Y155669D03*
X1679646Y145669D03*
Y155669D03*
X1689646Y165669D03*
X1679646D03*
X1689646Y175669D03*
X1679646D03*
X1771457Y1624646D03*
Y1644646D03*
G54D17*
X27699Y1258727D03*
Y1255381D03*
Y1265420D03*
Y1262074D03*
X43841Y994357D03*
Y1255381D03*
Y1258727D03*
Y1252034D03*
Y1262074D03*
Y1265420D03*
X57299Y766798D03*
X52541Y957546D03*
Y954200D03*
X57399Y1258727D03*
X52820Y1253862D03*
X57399Y1265420D03*
Y1262074D03*
X66099Y1061286D03*
X73541Y1255381D03*
Y1258727D03*
Y1252034D03*
Y1265420D03*
Y1262074D03*
X86999Y766798D03*
X82241Y957546D03*
Y954200D03*
Y994357D03*
X87099Y1258727D03*
X82241Y1248688D03*
X84334Y1254263D03*
X87099Y1265420D03*
Y1262074D03*
X103241Y994357D03*
Y1255381D03*
Y1258727D03*
Y1252034D03*
Y1265420D03*
Y1262074D03*
X116567Y766775D03*
X111941Y957546D03*
Y954200D03*
X125499Y1061286D03*
X116799Y1258727D03*
X111941Y1248688D03*
X114191Y1254604D03*
X116799Y1265420D03*
Y1262074D03*
X141641Y957546D03*
Y954200D03*
Y994357D03*
Y1057940D03*
X129933Y1238461D03*
X132941Y1255381D03*
Y1258727D03*
Y1252034D03*
X141641Y1248688D03*
X143675Y1255567D03*
X132941Y1265420D03*
Y1262074D03*
X146367Y766775D03*
X160130Y1251847D03*
X146499Y1258727D03*
Y1265420D03*
Y1262074D03*
X176099Y766798D03*
X171341Y957546D03*
Y954200D03*
X162641Y994357D03*
X176199Y1258727D03*
X162641Y1255381D03*
Y1258727D03*
Y1252034D03*
X171341Y1248688D03*
X171947Y1255837D03*
X176199Y1265420D03*
X162641D03*
Y1262074D03*
X176199D03*
X184899Y1061286D03*
X192341Y1255381D03*
Y1258727D03*
Y1252034D03*
Y1265420D03*
Y1262074D03*
X188897Y1578182D03*
X192297D03*
X205799Y766798D03*
X201041Y957546D03*
Y954200D03*
Y994357D03*
X205899Y1258727D03*
X201041Y1248688D03*
X201193Y1257900D03*
X205899Y1265420D03*
Y1262074D03*
X200957Y1578182D03*
X204357D03*
X222041Y957546D03*
Y954200D03*
Y994357D03*
Y1255381D03*
X219660Y1260492D03*
X222041Y1252034D03*
Y1265420D03*
Y1262074D03*
X225077Y1578182D03*
X213017D03*
X216417D03*
X235499Y766798D03*
X236391Y1002557D03*
X240521Y1000395D03*
X237841Y1000437D03*
X233891Y1002557D03*
X231391D03*
X228891D03*
X235599Y1258727D03*
X230741Y1248688D03*
X235480Y1265406D03*
X235599Y1262074D03*
X237137Y1578182D03*
X240537D03*
X228477D03*
X251741Y957546D03*
Y954200D03*
Y994357D03*
X254881Y999650D03*
X257561Y999608D03*
X244299Y1061286D03*
X248047Y1259155D03*
X250467Y1259175D03*
X251707Y1252034D03*
X249603Y1266204D03*
X251699Y1265254D03*
X249197Y1578182D03*
X252597D03*
X272529Y111053D03*
X265442D03*
X261899D03*
Y108553D03*
X265442D03*
X268985Y111053D03*
Y108553D03*
X272529D03*
X260441Y1057940D03*
Y1248688D03*
X273317Y1578182D03*
X261257D03*
X264657D03*
X285377D03*
X288777D03*
X276717D03*
X297437D03*
X300837D03*
X321557D03*
X309497D03*
X312897D03*
X333617D03*
X337017D03*
X324957D03*
X345677D03*
X349077D03*
X369797D03*
X357737D03*
X361137D03*
X373197D03*
X476451D03*
X485111D03*
X473051D03*
X500571D03*
X488511D03*
X497171D03*
X512631D03*
X509231D03*
X524691D03*
X533351D03*
X521291D03*
X536751D03*
X548811D03*
X545411D03*
X560871D03*
X557471D03*
X572931D03*
X581591D03*
X569531D03*
X597051D03*
X584991D03*
X593651D03*
X609111D03*
X605711D03*
X629658Y766478D03*
X623347Y999665D03*
X625780Y1000198D03*
X620899Y1061286D03*
X629931Y1258727D03*
X632080Y1262074D03*
X629699Y1255381D03*
X631270Y1264942D03*
X621171Y1578182D03*
X629831D03*
X617771D03*
X636941Y957546D03*
Y954200D03*
X644347Y1003135D03*
X640327D03*
X640467Y1000735D03*
X647447Y1002865D03*
X647397Y1000135D03*
X644257Y1000325D03*
X636946Y1258414D03*
X647690Y1260812D03*
X637041Y1252034D03*
X645897Y1248785D03*
X647877Y1254076D03*
X636877Y1261235D03*
X645291Y1578182D03*
X633231D03*
X641891D03*
X667677Y441636D03*
X650107Y1002825D03*
X650599Y1258727D03*
X666741Y1255381D03*
X664630Y1259442D03*
X649587Y1266766D03*
X661400Y1263522D03*
X657351Y1578182D03*
X653951D03*
X674628Y424313D03*
X671479Y421163D03*
X667660Y429037D03*
X674628Y427462D03*
X677778Y414864D03*
Y424313D03*
X671479Y414864D03*
X674628Y421163D03*
Y418013D03*
X677778D03*
Y421163D03*
X668329D03*
X677778Y427462D03*
Y430612D03*
X674628Y436911D03*
X671479D03*
X677778Y433761D03*
X668329Y436911D03*
X677778Y440061D03*
X674628D03*
X677778Y436911D03*
Y443210D03*
X680928Y440061D03*
X674628Y430612D03*
X671479Y443211D03*
X677778Y449510D03*
X668329Y452659D03*
X674628D03*
X671479D03*
X677778D03*
X668329Y455809D03*
X671479Y458959D03*
X674628D03*
X668329D03*
X677778D03*
Y455809D03*
X674628D03*
X668067Y462090D03*
X677778Y462108D03*
X671479Y455809D03*
X680928Y458959D03*
X674628Y449510D03*
Y462108D03*
X677778Y477856D03*
Y471557D03*
Y474707D03*
X671479Y465258D03*
X674628D03*
X668329D03*
X677778D03*
Y468407D03*
X671479Y481006D03*
X667350Y470680D03*
X671479Y474707D03*
X674628Y484006D03*
X680299Y766798D03*
X666641Y957546D03*
Y954200D03*
X672063Y998632D03*
X680299Y1061286D03*
Y1258727D03*
X666741Y1252034D03*
X675537Y1248885D03*
X677980Y1262074D03*
X666741D03*
X666646Y1264464D03*
X680046Y1264964D03*
X695055Y112678D03*
Y115178D03*
X687227Y414864D03*
X690376Y421163D03*
Y418013D03*
Y414864D03*
X693526Y427462D03*
X687227Y424313D03*
X690376Y427462D03*
X680928Y414864D03*
Y418013D03*
X684077Y421163D03*
X680928Y427462D03*
X684077Y418013D03*
Y427462D03*
X680928Y421163D03*
X684077Y424313D03*
X687227Y427462D03*
X696676D03*
X693526Y421163D03*
Y424313D03*
X690376D03*
X696676Y421163D03*
Y424313D03*
Y418013D03*
X680928Y436911D03*
Y433761D03*
X693526Y430612D03*
X696676Y440061D03*
Y443210D03*
X684077Y430612D03*
Y440061D03*
X687227Y436911D03*
Y443210D03*
X684077D03*
Y436911D03*
X680928Y443210D03*
X690376Y436911D03*
Y443210D03*
X687227Y440061D03*
X693526Y433761D03*
X696676D03*
X684077D03*
X687227Y430612D03*
X690376D03*
X696676D03*
X687227Y433761D03*
X680928Y430612D03*
X687227Y462108D03*
X680928Y455809D03*
X693526Y462108D03*
X680928Y449510D03*
X687227D03*
X690376Y462108D03*
X684077Y449510D03*
X680928Y452659D03*
X684077D03*
X687227Y455809D03*
X684077D03*
X680928Y462108D03*
X696676Y449510D03*
Y452659D03*
X690376Y449510D03*
Y455809D03*
X687227Y452659D03*
X693526Y458959D03*
X696676D03*
Y462108D03*
X687227Y458959D03*
X684077D03*
Y468407D03*
X687227Y471557D03*
Y474707D03*
Y477856D03*
X684077Y471557D03*
X690376Y465258D03*
X684077D03*
X680928Y471557D03*
Y474707D03*
Y477856D03*
X693526Y465258D03*
Y471557D03*
X690376Y468407D03*
Y477856D03*
Y471557D03*
X687227Y465258D03*
X690376Y474707D03*
X687227Y468407D03*
X693526D03*
X684077Y474707D03*
X696676Y465258D03*
Y474707D03*
Y468407D03*
X693526Y474707D03*
X696676Y471557D03*
X693526Y477856D03*
X696441Y957546D03*
Y954200D03*
Y994357D03*
Y1255381D03*
X694100Y1261562D03*
X696441Y1248688D03*
X692233Y1252480D03*
X696046Y1263764D03*
X698598Y115178D03*
X705685D03*
X702141D03*
X698598Y112678D03*
X705685D03*
X702141D03*
X706125Y418013D03*
X712424Y424313D03*
X699825Y427462D03*
X699826Y414864D03*
X699825Y424313D03*
X712424Y430612D03*
X709274Y440061D03*
Y443210D03*
X706125D03*
X699825D03*
X709274Y433761D03*
X712424D03*
X699825D03*
X706125D03*
X699825Y430612D03*
X706125Y462108D03*
X709274D03*
X712424D03*
X709274Y449510D03*
X699825D03*
X706125D03*
X709274Y452659D03*
X699825Y458959D03*
X706125D03*
X709274D03*
X712424D03*
X699825Y462108D03*
X709274Y474707D03*
Y471557D03*
Y465258D03*
Y468407D03*
X712424Y474707D03*
Y468407D03*
Y465258D03*
X706125Y471557D03*
Y468407D03*
X699825Y471557D03*
Y474707D03*
X706125Y477856D03*
X699825Y465258D03*
X712424Y471557D03*
X706125Y481006D03*
X709899Y766798D03*
X709999Y1258727D03*
X708090Y1262074D03*
X705037Y1252034D03*
X706493Y1256563D03*
X705167Y1262074D03*
X709977Y1264985D03*
X721873Y427462D03*
X725022D03*
X728172Y418013D03*
X718723D03*
X715574Y427462D03*
X728172Y421163D03*
X718723Y414864D03*
X725022Y424313D03*
X721873D03*
X725022Y421163D03*
X728172Y427462D03*
X731322Y421163D03*
X725022Y418013D03*
X718723Y427462D03*
Y424313D03*
Y421163D03*
X715574Y424313D03*
Y421163D03*
Y418013D03*
X728172Y424313D03*
X718723Y436911D03*
X721873Y433761D03*
Y436911D03*
Y440061D03*
Y430612D03*
X718723Y433761D03*
Y440061D03*
X725022Y436911D03*
Y433761D03*
X728172D03*
X718723Y430612D03*
X715574D03*
X725022D03*
X728172Y436911D03*
X715574D03*
Y440061D03*
Y443210D03*
X728172D03*
Y430612D03*
X725022Y440061D03*
X718723Y443210D03*
X721873D03*
X725022D03*
X728172Y440061D03*
X731322D03*
X728172Y455809D03*
Y458959D03*
X718723Y455809D03*
X721873Y458959D03*
Y452659D03*
X725022D03*
X728172D03*
X715574Y462108D03*
X725022Y458959D03*
X721873Y455809D03*
X725022Y462108D03*
X718723Y452659D03*
X715574Y449510D03*
Y452659D03*
Y455809D03*
X728172Y462108D03*
X718723Y449510D03*
X721873D03*
X725022D03*
X718723Y458959D03*
X721873Y462108D03*
X718723D03*
X725022Y468407D03*
X721873Y465258D03*
Y477856D03*
X718723Y468407D03*
X715574Y474707D03*
Y471557D03*
Y468407D03*
Y465258D03*
X718723Y474707D03*
Y471557D03*
X728172Y477856D03*
X721873Y471557D03*
X725022D03*
X718723Y465258D03*
X728172D03*
X725022Y474707D03*
X728172Y468407D03*
X721873Y474707D03*
Y468407D03*
X728172Y474707D03*
Y471557D03*
X725022Y465258D03*
X718723Y477856D03*
X725132Y481116D03*
X728272Y481006D03*
X726041Y957546D03*
Y954200D03*
Y994357D03*
X726141Y1057940D03*
Y1255381D03*
X723700Y1258727D03*
X726141Y1248688D03*
Y1262074D03*
X726107Y1265420D03*
X734471Y418013D03*
X731322Y427462D03*
Y418013D03*
X734471Y421163D03*
X731322Y424313D03*
X734471D03*
X737621D03*
X731322Y414864D03*
Y433761D03*
X734471Y436911D03*
X731322D03*
X734471Y443210D03*
X737621D03*
X731322D03*
Y455809D03*
X737621Y458959D03*
X731322D03*
X734471Y452659D03*
X731322D03*
Y449510D03*
X734471Y458959D03*
X731322Y465258D03*
Y477856D03*
X737621Y471557D03*
X734471Y468407D03*
X731322D03*
X731321Y474707D03*
X731322Y471557D03*
X734471Y481006D03*
X739699Y766798D03*
Y1061286D03*
Y1258727D03*
X734967Y1252034D03*
X737580Y1262074D03*
X739697Y1265420D03*
X755841Y957546D03*
Y954200D03*
Y994357D03*
X755541Y1057940D03*
X750890Y1248500D03*
X755890Y1255381D03*
X753000Y1261352D03*
X755841Y1252034D03*
Y1248688D03*
X750040Y1254179D03*
X755841Y1262074D03*
X755797Y1265420D03*
X769399Y766798D03*
Y1258727D03*
X767080Y1262074D03*
X766148Y1255882D03*
X769399Y1265420D03*
X785541Y957546D03*
Y954200D03*
Y994357D03*
Y1255381D03*
X783130Y1259372D03*
X794157Y1252034D03*
X785541Y1248688D03*
X796880Y1262074D03*
X796280Y1254402D03*
X785541Y1265420D03*
Y1262074D03*
X797417Y767345D03*
X799099Y1061286D03*
Y1258727D03*
X812440D03*
X799099Y1265420D03*
X815241Y957546D03*
Y954200D03*
Y994357D03*
Y1255381D03*
X826750Y1262074D03*
X823877Y1252034D03*
X815241Y1248688D03*
X826501Y1254553D03*
X815241Y1265420D03*
Y1262074D03*
X828699Y766798D03*
X828799Y1258727D03*
X842630Y1256912D03*
X828799Y1265420D03*
X844841Y957546D03*
Y954200D03*
Y994357D03*
X844941Y1258727D03*
Y1252034D03*
X844997Y1248155D03*
X844941Y1265420D03*
Y1262074D03*
X998205Y195735D03*
Y192191D03*
X1000705Y195735D03*
Y192191D03*
X998205Y199278D03*
X1000705D03*
X998205Y202821D03*
X1000705D03*
X1001970Y1251522D03*
X1003831Y1259077D03*
X1002070Y1256942D03*
X1003841Y1265420D03*
Y1262074D03*
X1012769Y766798D03*
X1019983Y994357D03*
X1017900Y1247632D03*
X1019983Y1255381D03*
Y1252034D03*
Y1248688D03*
Y1262074D03*
Y1265420D03*
X1033441Y766798D03*
X1028683Y957546D03*
Y954200D03*
X1033541Y1258727D03*
X1030830Y1261302D03*
X1030270Y1256042D03*
X1033541Y1265420D03*
X1042241Y1061286D03*
X1047010Y1259222D03*
X1049683Y1258727D03*
Y1265420D03*
Y1262074D03*
X1044930Y1263492D03*
X1063141Y766798D03*
X1058383Y957546D03*
Y954200D03*
Y994357D03*
X1063241Y1258727D03*
X1061330Y1262074D03*
X1058383Y1248688D03*
X1059410Y1252272D03*
X1063241Y1265420D03*
X1079383Y994357D03*
X1076520Y1259072D03*
X1079383Y1258727D03*
X1088262Y1252293D03*
X1079383Y1265420D03*
Y1262074D03*
X1092709Y766775D03*
X1088083Y957546D03*
Y954200D03*
X1101641Y1061286D03*
X1090273Y1246800D03*
X1092941Y1258727D03*
X1088083Y1248688D03*
X1091000Y1262074D03*
X1106200Y1250162D03*
X1092941Y1265420D03*
X1103530Y1263602D03*
X1117783Y957546D03*
Y954200D03*
Y994357D03*
Y1057940D03*
X1120800Y1262074D03*
X1117783Y1248688D03*
X1109083Y1265420D03*
X1109050Y1262972D03*
X1106740Y1267902D03*
X1122541Y766798D03*
X1122641Y1258727D03*
X1133200Y1255702D03*
X1122620Y1264622D03*
X1152241Y766798D03*
X1147483Y957546D03*
Y954200D03*
X1138783Y994357D03*
X1152341Y1258727D03*
X1138783Y1255381D03*
Y1258727D03*
Y1252034D03*
X1147483Y1248688D03*
X1150400Y1262074D03*
X1148563Y1257097D03*
X1152341Y1265420D03*
X1138783Y1262027D03*
X1137980Y1264212D03*
X1161041Y1061286D03*
X1168483Y1255381D03*
Y1258727D03*
Y1252034D03*
Y1265420D03*
Y1262074D03*
X1177183Y957546D03*
Y954200D03*
Y994357D03*
X1177120Y1248688D03*
X1177222Y1255567D03*
X1182041Y1265420D03*
X1181850Y1260192D03*
X1179180Y1265872D03*
X1198183Y957546D03*
Y954200D03*
Y994357D03*
Y1252034D03*
X1198180Y1262112D03*
X1196470Y1265382D03*
X1193590Y1267912D03*
X1195470Y1262802D03*
X1211641Y766798D03*
X1213983Y1000437D03*
X1216663Y1000395D03*
X1212533Y1002557D03*
X1205033D03*
X1207533D03*
X1210033D03*
X1208830Y1256692D03*
X1206883Y1248688D03*
X1207048Y1255174D03*
X1211240Y1265502D03*
X1208750Y1266546D03*
X1214132Y1602380D03*
X1202072D03*
X1217532D03*
X1205472D03*
X1227883Y957546D03*
Y954200D03*
Y994357D03*
X1233703Y999608D03*
X1231023Y999650D03*
X1220441Y1061286D03*
X1224189Y1259155D03*
X1226899Y1257968D03*
X1227847Y1251715D03*
X1227670Y1265162D03*
X1225540Y1266402D03*
X1226192Y1602380D03*
X1229592D03*
X1236583Y1057940D03*
Y1248688D03*
X1238252Y1602380D03*
X1241652D03*
X1262372D03*
X1250312D03*
X1265772D03*
X1253712D03*
X1274432D03*
X1277832D03*
X1298552D03*
X1286492D03*
X1289892D03*
X1310612D03*
X1314012D03*
X1301952D03*
X1322672D03*
X1326072D03*
X1346792D03*
X1334732D03*
X1338132D03*
X1358852D03*
X1362252D03*
X1350192D03*
X1370912D03*
X1374312D03*
X1382972D03*
X1386372D03*
X1477755Y1578182D03*
X1462295D03*
X1474355D03*
X1465695D03*
X1489815D03*
X1486415D03*
X1501875D03*
X1498475D03*
X1525995D03*
X1513935D03*
X1522595D03*
X1510535D03*
X1538055D03*
X1534655D03*
X1550115D03*
X1558775D03*
X1546715D03*
X1574235D03*
X1562175D03*
X1570835D03*
X1586295D03*
X1582895D03*
X1605800Y766478D03*
X1601922Y1000198D03*
X1599489Y999665D03*
X1597041Y1061286D03*
X1606481Y1258649D03*
X1608000Y1261662D03*
X1607897Y1264445D03*
X1598355Y1578182D03*
X1607015D03*
X1594955D03*
X1613083Y957546D03*
Y954200D03*
X1616609Y1000735D03*
X1616469Y1003135D03*
X1623539Y1000135D03*
X1620489Y1003135D03*
X1623589Y1002865D03*
X1620399Y1000325D03*
X1621983Y1258727D03*
X1624600Y1262074D03*
X1613183Y1252034D03*
X1613027Y1248805D03*
X1609056Y1250602D03*
X1623930Y1252242D03*
X1613019Y1261235D03*
X1622475Y1578182D03*
X1610415D03*
X1619075D03*
X1626741Y766798D03*
X1626249Y1002825D03*
X1626741Y1258727D03*
X1634535Y1578182D03*
X1631135D03*
X1656441Y766798D03*
X1642783Y957546D03*
Y954200D03*
X1648205Y998632D03*
X1656441Y1061286D03*
X1642883Y1255381D03*
Y1258727D03*
Y1252034D03*
X1651679Y1248885D03*
X1653140Y1257862D03*
X1656188Y1264964D03*
X1642788Y1264464D03*
X1642883Y1262074D03*
X1656170Y1260352D03*
X1654600Y1262742D03*
X1646595Y1578182D03*
X1643195D03*
X1672583Y957546D03*
Y954200D03*
Y994357D03*
Y1255381D03*
Y1258727D03*
Y1248688D03*
X1672188Y1263764D03*
X1686041Y766798D03*
X1686141Y1258727D03*
X1681179Y1252034D03*
X1683578Y1253780D03*
X1686119Y1264985D03*
X1681309Y1262074D03*
X1683500Y1264312D03*
X1702183Y957546D03*
Y954200D03*
Y994357D03*
X1702283Y1057940D03*
X1699852Y1245418D03*
X1699089Y1258842D03*
X1702283Y1248688D03*
X1702249Y1265420D03*
X1702283Y1262074D03*
X1699030Y1263912D03*
X1715841Y766798D03*
Y1061286D03*
X1713620Y1258512D03*
X1711109Y1252034D03*
X1713930Y1262074D03*
X1715839Y1265420D03*
X1737020Y112177D03*
Y109677D03*
X1731983Y957546D03*
Y954200D03*
Y994357D03*
X1731683Y1057940D03*
X1727041Y1248688D03*
X1731983Y1255381D03*
Y1258727D03*
Y1252034D03*
Y1248688D03*
X1731939Y1265420D03*
X1731983Y1262074D03*
X1747650Y109677D03*
Y112177D03*
X1744106Y109677D03*
Y112177D03*
X1740563Y109677D03*
Y112177D03*
X1745541Y766798D03*
Y1258727D03*
X1743710Y1262074D03*
X1742337Y1252300D03*
X1745541Y1265420D03*
X1761683Y957546D03*
Y954200D03*
Y994357D03*
X1756922Y1247632D03*
X1761683Y1255381D03*
Y1258727D03*
X1770299Y1252034D03*
X1761683Y1248688D03*
Y1262074D03*
Y1265420D03*
X1773559Y767345D03*
X1775241Y1061286D03*
Y1258727D03*
X1788219Y1259312D03*
X1773390Y1262074D03*
X1773480Y1253692D03*
X1775241Y1265420D03*
X1788360Y1264522D03*
X1791383Y957546D03*
Y954200D03*
Y994357D03*
X1788373Y1241769D03*
X1800427Y1248125D03*
X1803100Y1262074D03*
X1800019Y1252034D03*
X1791383Y1248688D03*
Y1265420D03*
Y1262074D03*
X1804841Y766798D03*
X1815063Y1233103D03*
X1804941Y1258727D03*
X1813814Y1254693D03*
X1804941Y1265420D03*
X1820983Y957546D03*
Y954200D03*
Y994357D03*
X1830379Y1250358D03*
X1829920Y1258322D03*
X1821139Y1248155D03*
X1821083Y1262074D03*
Y1265420D03*
X1829940Y1263662D03*
G54D29*
X159474Y1328627D03*
X183847Y1328652D03*
X208247D03*
X275289Y583576D03*
Y607735D03*
Y631889D03*
Y656043D03*
X270252Y676260D03*
Y700414D03*
X387897Y1242785D03*
X412297D03*
X436619D03*
X461019D03*
X485419D03*
X673093Y1328652D03*
X697466Y1328677D03*
X721866D03*
X1100800Y259362D03*
X1100700Y283662D03*
X1131100Y1364962D03*
X1155500D03*
X1179900D03*
X1364038Y1242785D03*
X1388438D03*
X1412760D03*
X1437160D03*
X1461560D03*
X1577000Y599762D03*
Y624262D03*
Y648762D03*
Y673162D03*
Y697662D03*
Y722162D03*
X1634259Y1362248D03*
X1658632Y1362273D03*
X1683032D03*
G54D52*
X705760Y-26500D03*
Y-16500D03*
D03*
Y-6500D03*
X730760Y-26500D03*
Y-16500D03*
D03*
Y-6500D03*
X822720Y3500D03*
Y13500D03*
D03*
Y23500D03*
X847720Y3500D03*
Y13500D03*
D03*
Y23500D03*
X973180Y-26500D03*
Y-16500D03*
D03*
Y-6500D03*
Y3500D03*
Y13500D03*
Y23500D03*
Y13500D03*
X998180Y-26500D03*
Y-16500D03*
D03*
Y-6500D03*
Y3500D03*
Y13500D03*
Y23500D03*
Y13500D03*
X1015152Y-26511D03*
Y-36511D03*
Y-26511D03*
Y-16511D03*
D03*
Y-6511D03*
D03*
Y3489D03*
D03*
Y13489D03*
D03*
Y23489D03*
X1040152Y-26511D03*
Y-36511D03*
Y-26511D03*
Y-16511D03*
D03*
Y-6511D03*
D03*
Y3489D03*
D03*
Y13489D03*
D03*
Y23489D03*
X1282572Y-36511D03*
Y-26511D03*
D03*
Y-16511D03*
D03*
Y-6511D03*
Y3489D03*
Y-6511D03*
Y3489D03*
Y13489D03*
Y23489D03*
Y13489D03*
X1307572Y-36511D03*
Y-26511D03*
D03*
Y-16511D03*
D03*
Y-6511D03*
Y3489D03*
Y-6511D03*
Y3489D03*
Y13489D03*
Y23489D03*
Y13489D03*
X1324471Y-26511D03*
Y-36511D03*
Y-26511D03*
Y-16511D03*
D03*
Y-6511D03*
D03*
Y3489D03*
D03*
Y13489D03*
D03*
Y23489D03*
X1349471Y-26511D03*
Y-36511D03*
Y-26511D03*
Y-16511D03*
D03*
Y-6511D03*
D03*
Y3489D03*
D03*
Y13489D03*
D03*
Y23489D03*
X1474931Y-36511D03*
Y-26511D03*
D03*
Y-16511D03*
D03*
Y-6511D03*
Y3489D03*
Y-6511D03*
Y3489D03*
Y13489D03*
Y23489D03*
Y13489D03*
X1499931Y-36511D03*
Y-26511D03*
D03*
Y-16511D03*
D03*
Y-6511D03*
Y3489D03*
Y-6511D03*
Y3489D03*
Y13489D03*
Y23489D03*
Y13489D03*
X1565236Y184783D03*
Y264035D03*
G54D55*
X793879Y194881D03*
X789942Y204724D03*
X793879Y214567D03*
X805690Y188976D03*
Y220472D03*
X817501Y194881D03*
Y214567D03*
X821438Y204724D03*
X841240Y1407480D03*
X832154Y1411244D03*
X828390Y1420330D03*
X832154Y1429416D03*
X841240Y1433180D03*
X850326Y1411244D03*
X854090Y1420330D03*
X850326Y1429416D03*
X1003390Y1420330D03*
X1016240Y1407480D03*
X1007154Y1411244D03*
Y1429416D03*
X1016240Y1433180D03*
X1025326Y1411244D03*
X1029090Y1420330D03*
X1025326Y1429416D03*
X1045847Y194881D03*
X1041910Y204724D03*
X1045847Y214567D03*
X1069469Y194881D03*
X1057658Y188976D03*
X1069469Y214567D03*
X1057658Y220472D03*
X1073406Y204724D03*
G54D11*
X3010Y63308D03*
Y123308D03*
Y163308D03*
Y183308D03*
Y203308D03*
Y223308D03*
Y243308D03*
Y263308D03*
Y283308D03*
Y303308D03*
X10884Y321693D03*
Y341693D03*
Y361693D03*
Y381693D03*
Y401693D03*
Y421693D03*
Y441693D03*
Y461693D03*
Y481693D03*
Y501693D03*
Y521693D03*
Y661693D03*
Y681693D03*
Y701693D03*
Y721693D03*
Y741693D03*
Y781693D03*
Y801693D03*
Y821693D03*
Y841693D03*
Y861693D03*
Y881693D03*
Y901693D03*
Y921693D03*
Y941693D03*
Y961693D03*
Y981693D03*
Y1001693D03*
Y1021693D03*
Y1041693D03*
Y1061693D03*
Y1081693D03*
Y1101693D03*
Y1121693D03*
Y1141693D03*
Y1161693D03*
Y1181693D03*
Y1201693D03*
Y1221693D03*
Y1241693D03*
Y1401693D03*
Y1421693D03*
Y1441693D03*
Y1461693D03*
Y1481693D03*
Y1501693D03*
Y1521693D03*
Y1541693D03*
Y1561693D03*
Y1581693D03*
X26615Y670036D03*
X28601Y1617541D03*
Y1637541D03*
Y1657541D03*
Y1677541D03*
X38220Y595862D03*
X54593Y19183D03*
X87565Y670441D03*
X94473Y698926D03*
X127313Y649765D03*
X114021Y669409D03*
X118021D03*
X127738Y659226D03*
X117220Y1680287D03*
X130067Y650213D03*
X134205Y643603D03*
X128193Y662015D03*
X128275Y665515D03*
X190800Y675662D03*
X219752Y1405499D03*
Y1401999D03*
Y1398599D03*
X259845Y461117D03*
X282640Y214102D03*
X301751Y127466D03*
Y124466D03*
Y121466D03*
X311758Y124469D03*
Y121469D03*
Y127469D03*
X313995Y237724D03*
X335285Y210609D03*
X332285D03*
X325755Y230719D03*
X338985Y229509D03*
X325855Y227619D03*
X325055Y237219D03*
X328965Y237214D03*
X332465D03*
X381068Y1674824D03*
X373320Y1688202D03*
X388220Y1631404D03*
X445944Y359053D03*
X446730Y382432D03*
X443744Y429553D03*
X451421D03*
X443744Y452462D03*
X437520Y484837D03*
X447520D03*
X442520D03*
X451520D03*
X448079Y1562177D03*
X443910Y1555602D03*
X450020Y1570412D03*
X453621Y359053D03*
X462720Y404762D03*
X465421Y424928D03*
X466520Y475812D03*
X456520Y484837D03*
X461520D03*
X456961Y1559697D03*
X456020Y1580412D03*
X464020D03*
X462079Y1572177D03*
X454661Y1596755D03*
X459779Y1609235D03*
X480393Y429412D03*
X479169Y484696D03*
X474169D03*
X484169D03*
X478308Y1439986D03*
X502070Y424787D03*
X488070Y429412D03*
X498169Y484696D03*
X493169D03*
X488169D03*
X513444Y473281D03*
X503169Y475671D03*
X550024Y369123D03*
Y401023D03*
X557701Y369123D03*
X649218Y504277D03*
X641386Y1687283D03*
X661534Y41748D03*
X656877Y514716D03*
X661743Y521166D03*
X657734Y528255D03*
X656725Y1657619D03*
X669004Y41698D03*
X694720Y491962D03*
X690720D03*
X702462Y1673258D03*
X725537Y-23978D03*
Y-19022D03*
Y-13978D03*
Y-9022D03*
X719194Y172909D03*
X714202D03*
X719194Y177865D03*
X714202D03*
X719194Y184909D03*
X714202D03*
X719194Y189865D03*
X714202D03*
X719194Y196409D03*
X714202D03*
X719194Y201365D03*
X714202D03*
X719194Y208243D03*
X714202D03*
X719194Y213199D03*
X714202D03*
X714203Y1639776D03*
X745685Y265322D03*
Y269322D03*
X742655Y1682362D03*
Y1678362D03*
X761720Y283262D03*
X748085Y278942D03*
X758360Y276122D03*
X755859Y1686090D03*
X755183Y1709850D03*
X764850Y249792D03*
X763359Y1729520D03*
X785135Y281822D03*
Y267822D03*
X842497Y6022D03*
Y16022D03*
Y20978D03*
Y10978D03*
X908675Y455386D03*
X913913Y455396D03*
X957420Y153699D03*
X960420D03*
X968022Y1620730D03*
X965022D03*
X971022D03*
X965022Y1632730D03*
X968022Y1629730D03*
X965022D03*
X968022Y1626730D03*
X965022D03*
Y1623730D03*
X968022D03*
X971022Y1626730D03*
Y1623730D03*
Y1629730D03*
Y1632730D03*
X968022D03*
X981445Y181058D03*
X1002735Y153943D03*
X999735D03*
X999915Y180548D03*
X996415D03*
X992505Y180553D03*
X993205Y174053D03*
X993305Y170953D03*
X990495Y212923D03*
X1001065Y304622D03*
Y307122D03*
Y309622D03*
X996662Y1620870D03*
X999662D03*
X1002662D03*
Y1626870D03*
Y1623870D03*
X996662Y1629870D03*
X999662Y1626870D03*
X996662D03*
Y1623870D03*
X999662D03*
X996662Y1632870D03*
X1021908Y60392D03*
Y120392D03*
X1015300Y148736D03*
X1012187Y148749D03*
X1006435Y172843D03*
X1009895Y192359D03*
X1008067Y194356D03*
X1019935Y206463D03*
Y203333D03*
X1010828Y304822D03*
Y307322D03*
Y309822D03*
X1034929Y-33989D03*
Y-29033D03*
Y-13989D03*
Y-9033D03*
Y-23989D03*
Y-19033D03*
Y-3989D03*
Y967D03*
X1036915Y290969D03*
X1035920Y428962D03*
X1034252Y1623870D03*
Y1626870D03*
X1031252Y1623870D03*
Y1626870D03*
X1028252Y1623870D03*
Y1626870D03*
X1031252Y1620870D03*
X1034252D03*
X1028252D03*
X1065721Y1633043D03*
X1068721D03*
Y1624043D03*
Y1627043D03*
Y1630043D03*
X1065721Y1624043D03*
Y1627043D03*
Y1630043D03*
X1062721Y1633043D03*
Y1624043D03*
Y1627043D03*
Y1630043D03*
X1059721Y1633043D03*
Y1624043D03*
Y1627043D03*
Y1630043D03*
X1068721Y1621043D03*
X1065721D03*
X1062721D03*
X1059721D03*
X1099901Y1633203D03*
Y1624203D03*
Y1627203D03*
Y1630203D03*
Y1621203D03*
X1093901Y1633203D03*
X1096901D03*
Y1624203D03*
Y1627203D03*
Y1630203D03*
X1093901Y1624203D03*
Y1627203D03*
Y1630203D03*
X1090901Y1633203D03*
X1087901D03*
X1090901Y1624203D03*
X1087901D03*
Y1627203D03*
X1090901D03*
X1087901Y1630203D03*
X1090901D03*
X1096901Y1621203D03*
X1093901D03*
X1087901D03*
X1090901D03*
X1132142Y1555301D03*
X1120472Y1615010D03*
X1127377Y1628485D03*
X1131632Y1625969D03*
X1148220Y501362D03*
X1139392Y1620851D03*
X1172720Y527862D03*
X1202600Y759662D03*
X1245574Y234042D03*
X1245593Y241462D03*
Y237462D03*
X1280223Y256841D03*
X1279841Y253052D03*
X1344248Y-33989D03*
Y-29033D03*
Y-13989D03*
Y-9033D03*
Y-23989D03*
Y-19033D03*
Y-3989D03*
Y967D03*
X1412954Y138742D03*
X1404402D03*
X1409716Y171696D03*
X1418268D03*
X1454829Y1439732D03*
X1465179Y213102D03*
X1477700Y236522D03*
X1466292Y631634D03*
X1473228D03*
X1486884Y374338D03*
X1479207D03*
X1478203Y406207D03*
X1493384Y419263D03*
X1481384Y419392D03*
X1505378Y225502D03*
X1509571Y239053D03*
X1507860Y249792D03*
X1513110Y247412D03*
X1522883Y305187D03*
X1526216Y306909D03*
X1529002Y32290D03*
X1528716Y306909D03*
X1533716D03*
X1536216D03*
X1534899Y310447D03*
X1559387Y589340D03*
X1564690Y663302D03*
X1619980Y590685D03*
X1615800Y584062D03*
X1620170Y623762D03*
X1622770D03*
X1612980D03*
X1620170Y626362D03*
X1622770D03*
X1612980D03*
X1615580Y650092D03*
Y657762D03*
X1620170D03*
X1622770D03*
X1622109Y652469D03*
X1619509D03*
X1612980Y657762D03*
Y650092D03*
X1615580Y660362D03*
X1620170D03*
X1622770D03*
X1612980D03*
X1622109Y686469D03*
X1619509D03*
X1615580Y684092D03*
X1612980D03*
X1622770Y691762D03*
Y694362D03*
X1620170Y691762D03*
Y694362D03*
X1615580D03*
X1612980D03*
X1615580Y691762D03*
X1612980D03*
X1619509Y720469D03*
X1622109D03*
X1612980Y718092D03*
X1615580D03*
X1610100Y725152D03*
X1637667Y587844D03*
Y590444D03*
X1629867D03*
Y587844D03*
X1632467Y590444D03*
Y587844D03*
X1635067Y590444D03*
Y587844D03*
X1626606Y616576D03*
X1629206D03*
X1631806D03*
X1634406D03*
X1637006D03*
X1639606D03*
X1630570Y623762D03*
X1627970D03*
X1625370D03*
X1636412Y638451D03*
X1636417Y630007D03*
X1640061Y639497D03*
X1636412Y641051D03*
X1630570Y626362D03*
X1627970D03*
X1625370D03*
X1630198Y638651D03*
Y636051D03*
Y641251D03*
X1633305Y638651D03*
Y641251D03*
X1630198Y632851D03*
X1630214Y629907D03*
X1633321D03*
X1640061Y644457D03*
Y641977D03*
X1630570Y657762D03*
X1627970D03*
X1625370D03*
X1629909Y652469D03*
X1632509D03*
X1624709D03*
X1627309D03*
X1630198Y643851D03*
X1633305Y646451D03*
Y643851D03*
X1630198Y646451D03*
X1636412Y672451D03*
X1636417Y664007D03*
X1640061Y673497D03*
X1630570Y660362D03*
X1627970D03*
X1625370D03*
X1630198Y672651D03*
Y670051D03*
X1633305Y672651D03*
X1630198Y666851D03*
X1630214Y663907D03*
X1633321D03*
X1629909Y686469D03*
X1632509D03*
X1624709D03*
X1627309D03*
X1640061Y678457D03*
Y675977D03*
X1636412Y675051D03*
X1630198Y677851D03*
Y675251D03*
X1633305Y680451D03*
Y675251D03*
Y677851D03*
X1630198Y680451D03*
X1636417Y698007D03*
X1636412Y706451D03*
X1630214Y697907D03*
X1633321D03*
X1630198Y704051D03*
Y706651D03*
X1633305D03*
X1630198Y700851D03*
X1625370Y691762D03*
Y694362D03*
X1630570D03*
Y691762D03*
X1627970D03*
Y694362D03*
X1640061Y707497D03*
Y712457D03*
Y709977D03*
X1636412Y709051D03*
X1632509Y720469D03*
X1627309D03*
X1629909D03*
X1624709D03*
X1633305Y711851D03*
Y709251D03*
X1630198D03*
Y711851D03*
X1633305Y714451D03*
X1630198D03*
X1642873Y604206D03*
Y607206D03*
X1645625Y600495D03*
Y603295D03*
X1642873Y601206D03*
Y598206D03*
X1645625Y597795D03*
Y594995D03*
X1642873Y595006D03*
X1642340Y618546D03*
X1642873Y610206D03*
X1645661Y639497D03*
X1656550Y653086D03*
X1645661Y644457D03*
Y641977D03*
Y673497D03*
X1656550Y687086D03*
X1645661Y678457D03*
Y675977D03*
Y707497D03*
Y709977D03*
Y712457D03*
X1665700Y583462D03*
X1661510Y583442D03*
X1672770Y580512D03*
X1669770D03*
X1663720Y620434D03*
X1659914Y649681D03*
Y683681D03*
Y717681D03*
X1686154Y434160D03*
X1704444Y407045D03*
X1697914Y427155D03*
X1698014Y424055D03*
X1701124Y433650D03*
X1697214Y433655D03*
X1704624Y433650D03*
X1717280Y174970D03*
X1707444Y407045D03*
X1711144Y425945D03*
X1765870Y179392D03*
X1780320Y177602D03*
G54D14*
X26054Y195148D03*
X25752Y203274D03*
X24754Y220220D03*
X24814Y236472D03*
X35600Y227380D03*
X45182Y426310D03*
X45034Y449106D03*
X62833Y410047D03*
X62808Y418425D03*
X50138Y426310D03*
X60393D03*
X49990Y449106D03*
X73020Y28406D03*
Y40020D03*
X65349Y426310D03*
X75516Y436519D03*
X73865Y763164D03*
X94279Y28406D03*
X87193D03*
X80106D03*
X94279Y40020D03*
X87193D03*
X80106D03*
X85826Y424319D03*
Y420319D03*
X82661Y449604D03*
X79451Y699517D03*
X92895Y1737108D03*
X108453Y28406D03*
X101366D03*
X108453Y40020D03*
X101366D03*
X104220Y400862D03*
X101720D03*
X113597Y488434D03*
X102152Y509374D03*
X102334Y500628D03*
X102359Y497374D03*
X102152Y513374D03*
X108909Y654926D03*
X102909Y648926D03*
Y642926D03*
Y655102D03*
X108909Y642926D03*
X122626Y28406D03*
X115539D03*
X122626Y40020D03*
X115539D03*
X125007Y392071D03*
Y388071D03*
Y384071D03*
Y396071D03*
X114507Y404571D03*
X117597Y488434D03*
X114909Y654926D03*
Y648926D03*
Y642926D03*
X116798Y1617262D03*
X112895Y1737108D03*
X129713Y28406D03*
Y40020D03*
X136301Y179095D03*
X143340Y204622D03*
X140974Y396885D03*
Y401885D03*
Y399385D03*
X142166Y490835D03*
X144263Y1412275D03*
X138492Y1717592D03*
X132895Y1737108D03*
X158492Y28406D03*
X151405D03*
X158492Y40020D03*
X151405D03*
X147901Y188852D03*
X159125Y448664D03*
X152171Y490615D03*
X149472Y502810D03*
X149486Y498810D03*
X149518Y522810D03*
X159898Y1360790D03*
X152895Y1737108D03*
X172665Y28406D03*
X165579D03*
X172665Y40020D03*
X165579D03*
X175640Y453779D03*
X162398Y1360790D03*
X164898D03*
X172895Y1737108D03*
X166761Y1732967D03*
X179752Y28406D03*
Y40020D03*
X184490Y402203D03*
X191305Y430216D03*
X188221Y454048D03*
X184147Y447078D03*
X192895Y1737108D03*
X202626Y28406D03*
X195539D03*
X202626Y40020D03*
X195539D03*
X199047Y428626D03*
X199139Y422882D03*
X196215Y447565D03*
X194858Y684348D03*
X203441Y1360790D03*
X198041D03*
X200941D03*
X223886Y28406D03*
X216799D03*
X209713D03*
X223886Y40020D03*
X216799D03*
X209713D03*
X223330Y426467D03*
X220843Y430004D03*
X220874Y442079D03*
X224137Y1414345D03*
X224077Y1416975D03*
X224350Y1432032D03*
X212895Y1737108D03*
X230972Y28406D03*
Y40020D03*
X242215Y151788D03*
X253000Y28362D03*
X256500D03*
X249500D03*
X252195Y144320D03*
X257434Y415896D03*
X252895Y1737108D03*
X260000Y28362D03*
X258746Y407842D03*
X260807Y424403D03*
X270322Y740207D03*
X272895Y1737108D03*
X286071Y28406D03*
X278984D03*
X279277Y99183D03*
X289557Y121803D03*
X280687Y140746D03*
X284482Y569548D03*
X286582Y630757D03*
X305025Y144202D03*
X302891Y141811D03*
X292895Y1737108D03*
X324733Y148598D03*
X321119Y1313108D03*
X317119D03*
X313119D03*
X330417Y380482D03*
X336370Y406302D03*
X325119Y1313108D03*
X328915Y1326704D03*
X331515D03*
X332895Y1737108D03*
X344776Y148462D03*
X343411Y363143D03*
Y375364D03*
X343354Y387988D03*
X343720Y400628D03*
X339769Y1299868D03*
X342769D03*
X352895Y1737108D03*
X366675Y158702D03*
X364179Y394596D03*
X371066Y400628D03*
X369690Y431812D03*
X365970Y444662D03*
X361769Y1300008D03*
X364769D03*
X383140Y119822D03*
X375330Y121182D03*
X374981Y131433D03*
X376770Y387272D03*
X385520Y429262D03*
X373190Y438342D03*
X384510Y438662D03*
X385730Y460922D03*
X382860Y471122D03*
X383239Y1286578D03*
X378069Y1286568D03*
X375069D03*
X386239Y1286578D03*
X372895Y1737108D03*
X403700Y402422D03*
X390892Y406863D03*
X403260Y439352D03*
X391150Y445302D03*
X396570Y472602D03*
X391360Y495712D03*
X402780Y499372D03*
X394860Y518812D03*
X403200Y572622D03*
X396139Y1286708D03*
X399139D03*
X400926Y1402207D03*
X391249Y1401048D03*
X396921Y1549810D03*
X396946Y1560810D03*
X419012Y368762D03*
X418602Y394722D03*
X417010Y439352D03*
X415130Y480202D03*
X410532Y1153341D03*
X407948Y1153370D03*
Y1161570D03*
X410532Y1161541D03*
X407948Y1169597D03*
X410532D03*
X429050Y117491D03*
X430980Y132672D03*
X432006Y363644D03*
X431596Y389604D03*
X424980Y439462D03*
X427790Y500862D03*
X427880Y506442D03*
X428510Y515842D03*
X436822Y1161570D03*
Y1153370D03*
X431722D03*
Y1161570D03*
X434272Y1153370D03*
Y1161570D03*
X436822Y1170070D03*
X431722D03*
X434272D03*
X430999Y1286758D03*
X423229D03*
X426229D03*
X433999D03*
X436920Y1541562D03*
X422566Y1550046D03*
X432996Y1558322D03*
X436840Y1632682D03*
X436880Y1622442D03*
X432895Y1737108D03*
X447100Y1622562D03*
X447020Y1632632D03*
X452895Y1737108D03*
X465236Y293823D03*
X467736Y312938D03*
X455326Y520389D03*
X457196Y1161570D03*
X459696D03*
X462196D03*
X459696Y1153370D03*
X457196D03*
X462196D03*
X459696Y1170070D03*
X462196D03*
X457196D03*
X460049Y1286978D03*
X463049D03*
X469019Y1286718D03*
X465749Y1401238D03*
X455602Y1412334D03*
X473870Y506622D03*
X474220Y572782D03*
X471940Y597532D03*
X483030Y1153370D03*
Y1161570D03*
Y1170070D03*
X474509Y1286848D03*
X481509D03*
X477509D03*
X484509D03*
X475285Y1395402D03*
X477835Y1673462D03*
Y1685462D03*
X472895Y1737108D03*
X498636Y293123D03*
X501136Y312238D03*
X486861Y309398D03*
X490759Y1291978D03*
X495309Y1300058D03*
X498309D03*
X492895Y1737108D03*
X517914Y42257D03*
X517902Y49194D03*
X510815D03*
X517989Y1300108D03*
X514989D03*
X508881Y1404880D03*
X506181D03*
X503559Y1405025D03*
X508775Y1409889D03*
X508828Y1407385D03*
X508802Y1412420D03*
X506075Y1409889D03*
X506128Y1407385D03*
X503572Y1407539D03*
Y1415039D03*
Y1412539D03*
X506102Y1412420D03*
X503572Y1410039D03*
X512895Y1737108D03*
X525000Y42257D03*
X524988Y49194D03*
X532533Y299500D03*
X529533D03*
X526941Y447802D03*
X521561Y550819D03*
X526280Y569122D03*
X520710Y592552D03*
X532895Y1737108D03*
X549610Y120682D03*
X535290Y572932D03*
X543450Y590262D03*
X562780Y32842D03*
X564430Y45132D03*
X565849Y1346968D03*
X552895Y1737108D03*
X578620Y45112D03*
X573849Y1346968D03*
X569849D03*
X572895Y1737108D03*
X596840Y45152D03*
X593925Y49193D03*
X590350Y294402D03*
X607890Y34389D03*
X615420Y42342D03*
X605060Y42402D03*
X615185Y49193D03*
X611310Y266272D03*
X612895Y1737108D03*
X621740Y265952D03*
X632895Y1737108D03*
X661681Y49193D03*
X654595D03*
X652895Y1737108D03*
X675854Y49193D03*
X668768D03*
X673517Y1360815D03*
X676017D03*
X678517D03*
X671112Y1639962D03*
X672895Y1737108D03*
X697122Y1632667D03*
X683592Y1634844D03*
X697197Y1644667D03*
X712433Y103308D03*
X712060Y1360815D03*
X722580Y49182D03*
X724133Y141288D03*
X713820Y488762D03*
Y484662D03*
X714560Y1360815D03*
X717060D03*
X744800Y1664840D03*
X732895Y1737108D03*
X762198Y129684D03*
Y126684D03*
X758110Y172636D03*
X752895Y1737108D03*
X777283Y320892D03*
X772208Y1731911D03*
X792208D03*
X810781Y372615D03*
X821164Y372312D03*
X812208Y1731911D03*
X836502Y161553D03*
X837975Y210064D03*
X832208Y1731911D03*
X856776Y129268D03*
X846846Y127064D03*
X851895Y160262D03*
X849710Y212062D03*
X845220Y216532D03*
X854706Y229878D03*
X852206D03*
X856842Y410760D03*
X852208Y1731911D03*
X874295Y163862D03*
X863488Y176332D03*
X872208Y1731911D03*
X886280Y174085D03*
X887671Y487831D03*
Y494767D03*
X878931Y509051D03*
X878941Y503813D03*
X892208Y1731911D03*
X899625Y473856D03*
X893321Y480293D03*
X893311Y485531D03*
X893572Y503050D03*
Y496114D03*
X920246Y184138D03*
X914550Y239924D03*
X923403Y983327D03*
X923322Y990227D03*
X921880Y1525110D03*
X924380D03*
X921880Y1527610D03*
X924380D03*
X912208Y1731911D03*
X935496Y195925D03*
Y203012D03*
Y210098D03*
Y217185D03*
Y224272D03*
Y231358D03*
X940596Y498648D03*
X939097Y527257D03*
X939282Y534020D03*
X930233Y983298D03*
X930274Y990237D03*
X939380Y1525110D03*
X926880D03*
X929380D03*
X931880D03*
X934380D03*
X936880D03*
X926880Y1527610D03*
X929380D03*
X931880D03*
X934380D03*
X936880D03*
X939380D03*
X932208Y1731911D03*
X947190Y527330D03*
X952208Y1731911D03*
X972208D03*
X989910Y-27961D03*
X989925Y-25446D03*
X983632Y-26655D03*
X989925Y-21572D03*
X983632Y-16626D03*
X989910Y-17932D03*
X989925Y-15417D03*
Y-11543D03*
X989910Y-7903D03*
X989925Y-5388D03*
X983632Y-6597D03*
X989925Y4641D03*
X989910Y2126D03*
X983632Y3432D03*
X989925Y14670D03*
X989910Y12155D03*
X989925Y8515D03*
X983632Y13461D03*
X989925Y19044D03*
X983632Y23990D03*
X987259Y276094D03*
X998500Y269862D03*
X1002500D03*
X992208Y1731911D03*
X1014500Y269862D03*
X1018000D03*
X1006500D03*
X1010500D03*
X1021419Y305704D03*
X1012208Y1731911D03*
X1032208D03*
X1053028Y246518D03*
X1053428Y261118D03*
X1052208Y1731911D03*
X1058028Y246518D03*
X1055528D03*
X1068093Y265503D03*
X1058428Y261118D03*
X1055928D03*
X1067618Y273800D03*
X1070718Y273700D03*
X1067718Y285600D03*
X1070618D03*
X1072208Y1731911D03*
X1102561Y78461D03*
X1117574Y1448604D03*
X1111866Y1737108D03*
X1135709Y1397119D03*
X1133209D03*
X1127008Y1524203D03*
X1135748Y1524187D03*
X1131866Y1737108D03*
X1138209Y1397119D03*
X1170337Y607327D03*
X1171752Y1397119D03*
X1176752D03*
X1174252D03*
X1179922Y1524203D03*
X1201110Y1681767D03*
X1191866Y1737108D03*
X1211866D03*
X1231866D03*
X1253586Y1334649D03*
X1257586D03*
X1251866Y1737108D03*
X1276745Y125850D03*
X1275807Y132922D03*
X1281600Y137962D03*
X1282568Y212722D03*
X1272707Y1334865D03*
X1271866Y1737108D03*
X1293024Y-36695D03*
Y-26666D03*
Y-16637D03*
Y-6608D03*
Y3421D03*
Y13450D03*
Y23979D03*
X1291280Y58262D03*
X1293860Y58312D03*
X1284930Y124922D03*
X1285793Y141562D03*
X1288258Y145501D03*
X1283781Y149115D03*
Y155788D03*
X1283425Y179272D03*
X1283397Y202085D03*
X1295150Y1323217D03*
X1298150D03*
X1291010Y1323307D03*
X1288010D03*
X1291866Y1737108D03*
X1299317Y-35486D03*
Y-31612D03*
X1299302Y-38001D03*
Y-27972D03*
X1299317Y-25457D03*
Y-21583D03*
X1299302Y-17943D03*
X1299317Y-15428D03*
Y-11554D03*
X1299302Y-7914D03*
X1299317Y-5399D03*
Y4630D03*
X1299302Y2115D03*
X1299317Y-1525D03*
Y14659D03*
X1299302Y12144D03*
X1299317Y8504D03*
Y19033D03*
X1304066Y1323578D03*
X1307656Y1326704D03*
X1305056D03*
X1311866Y1737108D03*
X1323958Y146227D03*
X1333811Y235348D03*
X1338652Y536654D03*
Y543590D03*
X1337663Y1301001D03*
X1340663D03*
X1331866Y1737108D03*
X1349704Y145385D03*
X1357888Y145893D03*
X1361111Y236448D03*
X1353982Y1287048D03*
X1362382D03*
X1359382D03*
X1350982D03*
X1351866Y1737108D03*
X1366868Y147341D03*
X1369593Y147462D03*
X1369916Y154132D03*
X1379969Y176330D03*
X1370586Y176366D03*
X1370405Y186938D03*
X1369479Y208384D03*
X1370636Y227292D03*
X1369410Y224504D03*
X1375463Y1287048D03*
X1372463D03*
X1376666Y1402778D03*
X1376686Y1399758D03*
X1371866Y1737108D03*
X1384173Y1161549D03*
X1384089Y1153369D03*
X1386673Y1161520D03*
Y1153340D03*
X1384173Y1169599D03*
X1386673Y1169570D03*
X1391866Y1737108D03*
X1407613Y177159D03*
X1398770D03*
X1402258Y184263D03*
X1411101D03*
X1407913Y1161569D03*
X1410413Y1153369D03*
X1407913D03*
X1410613Y1161569D03*
X1407913Y1170069D03*
X1410613D03*
X1410819Y1287198D03*
X1407819D03*
X1399419D03*
X1402419D03*
X1411866Y1737108D03*
X1420222Y184263D03*
X1429250Y1623391D03*
X1419270Y1631000D03*
X1429382Y184263D03*
X1430000Y220018D03*
X1435387Y1161569D03*
X1435837Y1153369D03*
X1432887Y1161569D03*
X1433337Y1153369D03*
X1435387Y1170069D03*
X1432887D03*
X1437258Y1287198D03*
X1445106Y1287158D03*
X1440258Y1287198D03*
X1431829Y1412370D03*
X1443325Y1410068D03*
X1431717Y1424125D03*
X1441800Y1620300D03*
Y1632900D03*
X1431866Y1737108D03*
X1458911Y1161569D03*
Y1170069D03*
X1453366Y1287198D03*
X1458766D03*
X1461766D03*
X1450366D03*
X1474180Y1300407D03*
X1471180D03*
X1491661Y-27972D03*
X1491676Y-25457D03*
X1485383Y-26666D03*
X1491661Y-38001D03*
X1491676Y-35486D03*
Y-31612D03*
X1485383Y-36695D03*
X1491661Y-17943D03*
X1491676Y-15428D03*
Y-11554D03*
X1485383Y-16637D03*
X1491676Y-21583D03*
X1485383Y3421D03*
X1491661Y2115D03*
X1491676Y4630D03*
X1491661Y-7914D03*
X1491676Y-5399D03*
Y-1525D03*
X1485383Y-6608D03*
X1491676Y14659D03*
X1491661Y12144D03*
X1485383Y13450D03*
X1491676Y8504D03*
Y19033D03*
X1485383Y23979D03*
X1487058Y281456D03*
X1484958Y289656D03*
X1487658D03*
X1484758Y312356D03*
X1487458D03*
X1484858Y305956D03*
X1487558D03*
X1491840Y1300447D03*
X1479658Y1405397D03*
X1485301Y1409442D03*
X1485274Y1406911D03*
X1485380Y1412202D03*
X1479671Y1410411D03*
Y1412911D03*
Y1407911D03*
X1482201Y1409442D03*
X1482174Y1406911D03*
X1482280Y1412202D03*
X1491866Y1737108D03*
X1504602Y312867D03*
X1494840Y1300447D03*
X1511866Y1737108D03*
X1540937Y576522D03*
X1536527Y589012D03*
X1531866Y1737108D03*
X1547429Y28406D03*
X1554515D03*
Y40020D03*
X1547429D03*
X1547312Y579080D03*
X1551866Y1737108D03*
X1561602Y28406D03*
X1568688D03*
Y40020D03*
X1561602D03*
X1575775Y28406D03*
X1582862D03*
X1589948D03*
Y40020D03*
X1582862D03*
X1575775D03*
X1591866Y1737108D03*
X1597035Y28406D03*
X1604122D03*
Y40020D03*
X1597035D03*
X1623881Y117627D03*
X1619980Y615201D03*
X1614116Y1411169D03*
X1611866Y1737108D03*
X1625814Y28406D03*
X1632901D03*
X1639988D03*
X1625814Y40020D03*
X1632901D03*
X1639988D03*
X1637183Y1394411D03*
X1639683D03*
X1634683D03*
X1631866Y1737108D03*
X1654161Y28406D03*
X1647074D03*
Y40020D03*
X1654161D03*
X1652113Y527325D03*
X1652138Y524071D03*
X1651931Y540071D03*
Y536071D03*
X1649291Y556057D03*
X1649149Y607022D03*
X1653929Y604546D03*
X1649139Y604576D03*
X1653736Y607033D03*
X1649117Y602139D03*
X1653930Y602099D03*
X1651866Y1737108D03*
X1669948Y28406D03*
Y40020D03*
X1663376Y515531D03*
X1667376D03*
X1664997Y604762D03*
X1659458Y637149D03*
X1658085Y639511D03*
X1659458Y671149D03*
X1658085Y673511D03*
X1659458Y705149D03*
X1658085Y707511D03*
X1673226Y1394411D03*
X1671866Y1737108D03*
X1677035Y28406D03*
X1684122D03*
X1677035Y40020D03*
X1684122D03*
X1681612Y499290D03*
X1675926Y1394411D03*
X1678426D03*
X1691208Y28406D03*
X1698295D03*
X1705381D03*
X1697824Y39974D03*
X1691208Y40020D03*
X1693987Y230174D03*
Y233174D03*
X1703487Y232174D03*
X1699265Y525507D03*
X1699291Y537507D03*
X1699251Y529507D03*
X1699297Y549507D03*
X1705723Y1583821D03*
X1691866Y1737108D03*
X1711866D03*
X1738200Y193862D03*
X1731866Y1737108D03*
X1753388Y28360D03*
X1754398Y100307D03*
X1752200Y197762D03*
X1748500Y193862D03*
X1745500D03*
X1741200D03*
X1740831Y489362D03*
X1740886Y493960D03*
X1751866Y1737108D03*
X1760475Y28360D03*
X1764678Y122927D03*
X1766880Y234842D03*
Y231842D03*
X1758500Y231822D03*
Y234822D03*
X1755378Y233528D03*
X1782000Y128455D03*
X1771915Y128393D03*
X1782000Y125955D03*
Y123455D03*
X1771915Y125893D03*
Y123393D03*
X1783800Y231762D03*
Y234762D03*
X1775140Y234792D03*
Y231792D03*
X1779226Y275604D03*
X1783563Y273471D03*
X1786089D03*
X1771866Y1737108D03*
X1797663Y269571D03*
X1800189D03*
X1790563Y273471D03*
X1793089D03*
X1802763Y308671D03*
X1795763D03*
X1798289D03*
X1788763D03*
X1791289D03*
X1814349Y269634D03*
X1811823D03*
X1807249D03*
X1804723D03*
X1812349Y308734D03*
X1809823D03*
X1805289Y308671D03*
X1828777Y156520D03*
X1841257Y151402D03*
G54D19*
X20188Y1599396D03*
G54D67*
X1156378Y133866D03*
G54D71*
X1850331Y311946D03*
G54D26*
X60303Y20354D03*
X312921Y24291D03*
X505185Y41142D03*
X757803Y45079D03*
X922441Y237697D03*
X929331Y160413D03*
X1534712Y20354D03*
X1787330Y24291D03*
G54D42*
X337778Y854584D03*
X335924Y857789D03*
X334079Y880219D03*
X332228Y877014D03*
X335928D03*
X334078Y893036D03*
X335928Y896240D03*
X332229Y902649D03*
X332228Y915466D03*
X335928D03*
X332229Y921875D03*
Y941100D03*
X332228Y934692D03*
X335928D03*
X334079Y957122D03*
X335928Y953917D03*
X332228D03*
X332229Y973143D03*
X334079Y976347D03*
X338210Y996480D03*
X332661Y1006093D03*
X338211Y1002888D03*
X332661Y1025318D03*
Y1018910D03*
X338211Y1015705D03*
Y1022114D03*
X332661Y1044544D03*
X338211Y1041340D03*
X334511D03*
X338211Y1060565D03*
X336360Y1082995D03*
X338211Y1111834D03*
Y1105426D03*
Y1124651D03*
X336361Y1115039D03*
Y1127856D03*
X347028Y844971D03*
X345178Y848176D03*
X350727Y844971D03*
X347027Y851380D03*
X343327D03*
X354429D03*
X341478Y854584D03*
X339628Y857789D03*
X347029Y864197D03*
Y857789D03*
X348878Y854584D03*
X345179Y860993D03*
X343327Y857789D03*
X354429Y864197D03*
X350729D03*
X341479Y867401D03*
X348879D03*
X352579D03*
X354429Y877014D03*
X339629D03*
X341479Y873810D03*
X345179Y880219D03*
Y873810D03*
X343329Y877014D03*
X352579Y880219D03*
X350729Y877014D03*
X339629Y883423D03*
X347029D03*
X350729D03*
X352578Y899445D03*
X339629Y896240D03*
Y889832D03*
X348879Y886627D03*
X345179Y893036D03*
X343328Y896240D03*
X352578Y893036D03*
Y886627D03*
X345179Y899445D03*
X348878Y905853D03*
X352578D03*
X341479Y912262D03*
X341478Y905853D03*
X347029Y909057D03*
Y902649D03*
X345179Y912262D03*
X352578D03*
X339629Y915466D03*
X343329D03*
X348878Y925079D03*
X352578D03*
Y918670D03*
X341478Y925079D03*
X347029Y928283D03*
Y921875D03*
X345179Y918670D03*
X341479Y931488D03*
X345179D03*
X352578D03*
X341478Y944304D03*
X352578D03*
X347029Y941100D03*
X348878Y944304D03*
X347029Y947509D03*
X352578Y937896D03*
X339629Y934692D03*
X345179Y937896D03*
X343328Y934692D03*
X348878Y963530D03*
X347029Y960326D03*
X343328D03*
X343329Y966735D03*
X339629D03*
Y953917D03*
X343328D03*
X345179Y957122D03*
X352578D03*
X347029Y966735D03*
X352578Y963530D03*
X341479Y950713D03*
X345179D03*
X352578D03*
X354428Y973143D03*
X339629D03*
X345179Y976347D03*
Y969939D03*
X350729Y973143D03*
X347029Y979552D03*
X352579Y976347D03*
X352578Y969939D03*
X348878Y982756D03*
X352578D03*
X339629Y979552D03*
X343329Y973143D03*
X341911Y1009297D03*
Y1002888D03*
X347461Y999684D03*
X345611Y1009297D03*
X343761Y1006093D03*
X345611Y1002888D03*
X351162Y1006093D03*
X354861D03*
X353011Y1009297D03*
Y1002888D03*
X347461Y1012501D03*
X353011Y1028523D03*
Y1015705D03*
X341911Y1022114D03*
Y1015705D03*
X349311D03*
X347461Y1018910D03*
X345611Y1028523D03*
X343761Y1018910D03*
X345611Y1022114D03*
Y1015705D03*
X353011Y1022114D03*
X343761Y1031727D03*
X347461D03*
X353011Y1034931D03*
Y1047749D03*
X341911Y1041340D03*
X343761Y1038136D03*
X349311Y1034931D03*
X347461Y1038136D03*
X345611Y1041340D03*
X343761Y1044544D03*
X353011Y1041340D03*
X345611Y1047749D03*
X349311Y1054157D03*
X353011Y1060565D03*
Y1054157D03*
X343761Y1057361D03*
Y1050952D03*
X347461D03*
Y1057361D03*
X345611Y1060565D03*
X343761Y1063770D03*
X353011Y1073383D03*
X343761Y1076587D03*
Y1070178D03*
X340062Y1076587D03*
X347461D03*
Y1070178D03*
X349312Y1073383D03*
X345611Y1066974D03*
X353011D03*
X345611Y1079791D03*
X341911D03*
X353011D03*
Y1086200D03*
X349310Y1092609D03*
X347461Y1089404D03*
X345610Y1086200D03*
X343760Y1082995D03*
X340060D03*
X353011Y1092608D03*
X340061Y1095813D03*
X347461Y1108630D03*
X354861D03*
X353011Y1099017D03*
X340061Y1108630D03*
Y1102221D03*
X349311Y1099017D03*
X347461Y1102221D03*
X343761D03*
X340061Y1115039D03*
X349311Y1124651D03*
X349312Y1118243D03*
X345611D03*
X343761Y1115039D03*
X341911Y1124651D03*
X354861Y1115039D03*
X351161Y1121447D03*
Y1115039D03*
X345611Y1137469D03*
Y1131060D03*
X349311D03*
X343761Y1134264D03*
X353011Y1137469D03*
Y1131060D03*
X361829Y851380D03*
X358129D03*
X365529Y864197D03*
X361829D03*
X359979Y854584D03*
X358129Y864197D03*
X369229D03*
X367379Y854584D03*
X359979Y867401D03*
X367379D03*
X365529Y877014D03*
X361829D03*
X358129D03*
X369229D03*
X367379Y880219D03*
X356278Y886627D03*
X365529Y896240D03*
Y889832D03*
X361828Y896240D03*
X361829Y889832D03*
X359979Y893036D03*
X358128Y889832D03*
X369229Y896240D03*
Y889832D03*
X356278Y905853D03*
X365529Y909057D03*
Y902649D03*
X359978Y912262D03*
X358128Y909057D03*
X358129Y902649D03*
X371079Y912262D03*
X365529Y915466D03*
X361828D03*
X369229D03*
X356279Y925079D03*
X365529Y928283D03*
Y921875D03*
X358128Y928283D03*
X358129Y921875D03*
X371078Y918670D03*
X359978Y931488D03*
X371079D03*
X358128Y947509D03*
X358129Y941100D03*
X356279Y944304D03*
X365529Y947509D03*
Y934691D03*
X361828D03*
X369229D03*
X356279Y963530D03*
X358129Y960326D03*
X359979Y957122D03*
X358128Y966735D03*
X361829Y953917D03*
X359978Y950713D03*
X371078Y957122D03*
X371079Y950713D03*
X365529Y953917D03*
X367378Y963530D03*
X363679D03*
X365529Y960326D03*
X365528Y966735D03*
X369229Y953917D03*
X359979Y976347D03*
X358129Y979552D03*
X359978Y969939D03*
X361828Y973143D03*
X356279Y982756D03*
X371078Y976347D03*
X371079Y969939D03*
X369229Y973143D03*
X365529Y979552D03*
Y973143D03*
X365962Y999684D03*
Y1006093D03*
X362261D03*
X360411Y1009297D03*
X360412Y1002888D03*
X358562Y999684D03*
X371512Y1009297D03*
X365961Y1012501D03*
X358561D03*
X356712Y1015705D03*
X365962Y1025318D03*
Y1018910D03*
X364112Y1015705D03*
X360411Y1028523D03*
X362261Y1025318D03*
X360412Y1022114D03*
X358562Y1018910D03*
X369662Y1025318D03*
X367811Y1015705D03*
X371511Y1028523D03*
Y1022114D03*
X365962Y1031727D03*
X358561D03*
X356712Y1034931D03*
X365962Y1044544D03*
Y1038136D03*
X362261Y1044544D03*
X360412Y1041340D03*
X358562Y1038136D03*
X369662Y1044544D03*
X371511Y1041340D03*
X360411Y1047749D03*
X371511D03*
X356712Y1054157D03*
X365962Y1057361D03*
Y1050952D03*
X360412Y1060565D03*
X358562Y1057361D03*
X358561Y1050952D03*
X371511Y1060565D03*
X365962Y1063770D03*
X362261D03*
X369662D03*
X356712Y1073383D03*
X365962Y1070178D03*
X360411Y1066974D03*
X358561Y1070178D03*
X358562Y1076587D03*
X371512Y1066974D03*
X360412Y1079791D03*
X371511D03*
X365962Y1089404D03*
Y1082995D03*
X362261D03*
X360411Y1086200D03*
X358561Y1089404D03*
X356712Y1092608D03*
X369662Y1082995D03*
X371512Y1086200D03*
X365962Y1095813D03*
X358561D03*
X365962Y1102221D03*
X362262D03*
X360411Y1099017D03*
X356711Y1105426D03*
Y1099017D03*
X371512Y1105426D03*
Y1099017D03*
X364112Y1111834D03*
X356712D03*
X371512D03*
X364111Y1118243D03*
X362261Y1115039D03*
X360411Y1118243D03*
X356711D03*
X367811D03*
X371511D03*
X365962Y1127856D03*
X358561D03*
X365961Y1140973D03*
X364112Y1131060D03*
X360412D03*
X358561Y1140973D03*
X356712Y1131060D03*
X367811D03*
X371511D03*
X382179Y854584D03*
X380329Y864197D03*
X376629D03*
X374779Y854584D03*
X372929Y864197D03*
X384029D03*
X387729D03*
X382179Y867401D03*
X374779D03*
X382179Y880219D03*
X380329Y877014D03*
X376629D03*
X374779Y880219D03*
X372929Y877014D03*
X384029D03*
X387729D03*
X380329Y889832D03*
X378479Y893036D03*
X376629Y889832D03*
X372929D03*
X384029D03*
X387729Y896240D03*
Y889832D03*
X378478Y899445D03*
X385879D03*
X382179Y905853D03*
X378478Y912262D03*
Y905853D03*
X374778D03*
X372929Y909057D03*
X372928Y902649D03*
X385878Y912262D03*
X384028Y909057D03*
X384029Y902649D03*
X387728Y915466D03*
X382179Y925079D03*
X378478D03*
Y918670D03*
X374778Y925079D03*
X372929Y928283D03*
X372928Y921875D03*
X385879Y918670D03*
X384028Y928283D03*
X384029Y921875D03*
X385878Y931488D03*
X384029Y941100D03*
X384028Y947509D03*
X374778Y944304D03*
X372929Y947509D03*
X372928Y941100D03*
X382179Y944304D03*
X378478D03*
Y937896D03*
X385879D03*
X387728Y934691D03*
X387729Y953917D03*
X372928Y960326D03*
X374778Y963530D03*
X372929Y966735D03*
X382179Y963530D03*
X378478D03*
Y957122D03*
X384029Y960326D03*
X385879Y957122D03*
X384028Y966735D03*
X385878Y950713D03*
X378478D03*
X387728Y973143D03*
X376629D03*
X380328D03*
X378479Y976347D03*
X378478Y969939D03*
X385879Y976347D03*
X384029Y979552D03*
X385878Y969939D03*
X374778Y982756D03*
X382179D03*
X378478D03*
X372928Y979552D03*
X375210Y996480D03*
X373361Y999684D03*
X378911Y1009297D03*
Y1002888D03*
X386311Y1009297D03*
X386312Y1002888D03*
X384462Y999684D03*
X373362Y1012501D03*
X384461D03*
X382612Y1015705D03*
X378911Y1028523D03*
Y1022114D03*
Y1015705D03*
X375211D03*
X373361Y1018910D03*
X386311Y1028523D03*
X386312Y1022114D03*
X384462Y1018910D03*
X373362Y1031727D03*
X384461D03*
X382612Y1034931D03*
X378911Y1041340D03*
Y1034931D03*
X375211D03*
X373361Y1038136D03*
X386312Y1041340D03*
X384462Y1038136D03*
X378911Y1047749D03*
X386311D03*
X382612Y1054157D03*
X378911D03*
X375211D03*
X373361Y1057361D03*
X373362Y1050952D03*
X386312Y1060565D03*
X384462Y1057361D03*
X384461Y1050952D03*
X382612Y1073383D03*
X378911D03*
Y1066974D03*
X375211Y1073383D03*
X373361Y1076587D03*
X373362Y1070178D03*
X386311Y1066974D03*
X384462Y1076587D03*
X384461Y1070178D03*
X378911Y1079791D03*
X386311D03*
X382611Y1092608D03*
X378911D03*
Y1086200D03*
X375211Y1092608D03*
X373362Y1089404D03*
X386311Y1086200D03*
X384461Y1089404D03*
X373362Y1095813D03*
X384462D03*
X380762Y1108630D03*
X378911Y1099017D03*
X377062Y1102221D03*
X373361Y1108630D03*
Y1102221D03*
X386312Y1099017D03*
X384462Y1102221D03*
X382611Y1118243D03*
X378911D03*
X377061Y1115039D03*
X375211Y1118243D03*
X373361Y1115039D03*
X386311Y1118243D03*
X384461Y1115039D03*
X380761Y1127856D03*
X373361D03*
X382611Y1131060D03*
X380761Y1140973D03*
X378911Y1131060D03*
X375211D03*
X373361Y1140973D03*
X386311Y1131060D03*
X396979Y841467D03*
X398829Y851380D03*
X395129D03*
X391429D03*
X402529D03*
X398829Y864197D03*
X396979Y854584D03*
X395129Y864197D03*
X391429D03*
X389579Y854584D03*
X402529Y864197D03*
X396979Y867401D03*
X389579D03*
X398829Y877014D03*
X396979Y880219D03*
X395129Y877014D03*
X391429D03*
X389579Y880219D03*
X402529Y877014D03*
X398829Y889832D03*
X395129Y896240D03*
Y889832D03*
X391428Y896240D03*
X391429Y889832D03*
X389579Y893036D03*
X402529Y889832D03*
X398829Y909057D03*
X398828Y902649D03*
X396979Y912262D03*
X391429Y909057D03*
Y902649D03*
X395129Y915466D03*
X391429D03*
X398829Y928283D03*
X398828Y921875D03*
X396978Y918670D03*
X391429Y928283D03*
Y921875D03*
X400678Y925079D03*
X396979Y931488D03*
X398828Y941100D03*
X395129Y934691D03*
X391429Y941100D03*
Y934691D03*
X400678Y937896D03*
X398829Y947509D03*
X391429D03*
X398828Y960326D03*
X396978Y957122D03*
X396979Y950713D03*
X395129Y953917D03*
X391429Y960326D03*
Y953917D03*
X400678Y957122D03*
X398829Y966735D03*
X391429D03*
X400678Y963530D03*
X398828Y979552D03*
X396978Y976347D03*
X396979Y969939D03*
X395129Y973143D03*
X391429Y979552D03*
Y973143D03*
X400678Y982756D03*
Y969939D03*
X397412Y1009297D03*
X397411Y1002888D03*
X395562Y1006093D03*
X391862D03*
Y999684D03*
X388161Y1006093D03*
X401111Y1002888D03*
X399262Y1012501D03*
X391861D03*
X399261Y1018910D03*
X397411Y1028523D03*
Y1022114D03*
X395562Y1025318D03*
X393711Y1015705D03*
X391862Y1025318D03*
Y1018910D03*
X390012Y1015705D03*
X388161Y1025318D03*
X399262Y1031727D03*
X391862D03*
X399261Y1038136D03*
X397411Y1041340D03*
X395562Y1044544D03*
X391862D03*
Y1038136D03*
X388161Y1044544D03*
X397411Y1047749D03*
X399261Y1057361D03*
X399262Y1050952D03*
X397411Y1060565D03*
X391862Y1057361D03*
Y1050952D03*
X395562Y1063770D03*
X391862D03*
X388161D03*
X399261Y1076587D03*
X399262Y1070178D03*
X397412Y1066974D03*
X391862Y1076587D03*
Y1070178D03*
X401111Y1073383D03*
X397411Y1079791D03*
X401111D03*
X399262Y1089404D03*
X397412Y1086200D03*
X395562Y1082995D03*
X391862Y1089404D03*
Y1082995D03*
X388161D03*
X401112Y1092608D03*
X401111Y1086200D03*
X399261Y1095813D03*
X391862D03*
X402962D03*
X399262Y1102221D03*
X397412Y1099017D03*
X395562Y1102221D03*
X390011Y1105426D03*
X388162Y1108630D03*
Y1102221D03*
X401111Y1105426D03*
X397411Y1111834D03*
X390011D03*
X397411Y1118243D03*
X395561Y1115039D03*
X393711Y1118243D03*
X390011D03*
X388161Y1115039D03*
X401111Y1118243D03*
X395561Y1127856D03*
X388161D03*
X402961D03*
X397411Y1131060D03*
X395561Y1140973D03*
X393711Y1131060D03*
X390011D03*
X388161Y1140973D03*
X402961D03*
X401111Y1131060D03*
X419179Y841467D03*
X404379D03*
X411779D03*
X413629Y851380D03*
X409929D03*
X406229D03*
X417329D03*
X404379Y854584D03*
X413629Y864197D03*
X411779Y854584D03*
X409929Y864197D03*
X406229D03*
X419179Y854584D03*
X417329Y864197D03*
X404379Y867401D03*
X411779D03*
X419179D03*
X404379Y880219D03*
X413629Y877014D03*
X411779Y880219D03*
X409929Y877014D03*
Y870606D03*
X406229Y877014D03*
X419179Y880219D03*
X417329Y877014D03*
X413629Y889832D03*
X411779Y893036D03*
X409929Y889832D03*
X408079Y893036D03*
X406229Y889832D03*
X419179Y893036D03*
X417329Y889832D03*
X413629Y902649D03*
X409929Y909057D03*
Y902649D03*
X404378Y912262D03*
Y905853D03*
X419178Y912262D03*
X419179Y905853D03*
X417329Y902649D03*
X409929Y915466D03*
Y921875D03*
X404378Y918670D03*
X418229Y926896D03*
X419178Y918670D03*
X405048Y930812D03*
X405145Y946239D03*
Y948539D03*
X414093Y942098D03*
X405048Y938046D03*
Y935746D03*
X416393Y942098D03*
X418693D03*
X405122Y965896D03*
Y963596D03*
X414365Y971140D03*
X416755D03*
X404861Y981269D03*
Y978969D03*
Y986421D03*
X405101Y992971D03*
Y995271D03*
X404861Y988721D03*
X405227Y1007156D03*
X405231Y1004848D03*
X417575Y1000060D03*
X415185D03*
X404986Y1022427D03*
X404998Y1026821D03*
X408325Y1031971D03*
Y1034271D03*
X408511Y1041340D03*
X417762Y1044544D03*
X412211Y1047749D03*
X404811D03*
X415911Y1060565D03*
Y1054157D03*
X412211Y1060565D03*
X410361Y1050952D03*
X408511Y1054157D03*
X404811Y1060565D03*
X417761Y1050952D03*
X415911Y1066974D03*
X410362Y1076587D03*
Y1070178D03*
X406661Y1076587D03*
X404811Y1066974D03*
X419611Y1073383D03*
X412211Y1079791D03*
X404811D03*
X415911Y1092608D03*
X415912Y1086200D03*
X412211Y1092608D03*
X408511Y1086200D03*
X417761Y1089404D03*
Y1082995D03*
X410362Y1095813D03*
X406662D03*
X415912Y1099017D03*
X414062Y1108630D03*
X412211Y1099017D03*
X410362Y1102221D03*
X406661Y1108630D03*
Y1102221D03*
X404812Y1105426D03*
X417762Y1102221D03*
X404812Y1111834D03*
X415911Y1118243D03*
X414061Y1121447D03*
X412211Y1124651D03*
Y1118243D03*
X410361Y1115039D03*
X408511Y1118243D03*
X406661Y1115039D03*
X404811Y1118243D03*
X417761Y1115039D03*
X410361Y1127856D03*
X414062Y1134264D03*
X412212Y1131060D03*
X410361Y1140973D03*
X408511Y1131060D03*
X404811D03*
X432128Y844671D03*
X426579Y841467D03*
X432129Y851380D03*
X428429D03*
X424729D03*
X421029D03*
X432129Y864197D03*
X428429D03*
X426579Y854584D03*
X424729Y864197D03*
X421029D03*
X433979Y854584D03*
X426579Y867401D03*
X433979D03*
X432129Y877014D03*
X428429D03*
X426579Y880219D03*
X424729Y877014D03*
X421029D03*
X433979Y880219D03*
X432129Y889832D03*
X428429D03*
X426579Y893036D03*
X424729Y889832D03*
X421029D03*
X433979Y893036D03*
X424729Y902649D03*
X432129D03*
X428429Y909057D03*
Y902649D03*
X421029D03*
X428429Y915466D03*
X433980Y925079D03*
Y931487D03*
X426875Y947199D03*
Y949499D03*
X427875Y936470D03*
X426905Y965935D03*
Y963635D03*
Y980336D03*
Y978036D03*
Y994722D03*
Y992422D03*
Y1006875D03*
Y1009175D03*
Y1021963D03*
Y1019663D03*
X428862Y1044544D03*
X430712Y1047749D03*
X423311D03*
X425162Y1057361D03*
X432561Y1050952D03*
X434411Y1060565D03*
Y1054157D03*
X421462Y1063770D03*
X430711Y1073383D03*
X427011D03*
Y1066974D03*
X425162Y1076587D03*
X423311Y1066974D03*
X432561Y1076587D03*
X434411Y1073383D03*
Y1066974D03*
X427012Y1079791D03*
X434411D03*
X428861Y1082995D03*
X425162Y1089404D03*
X421462Y1082995D03*
X432561Y1089404D03*
Y1082995D03*
X434411Y1086200D03*
X428861Y1095813D03*
X421462D03*
X432561D03*
X427011Y1099017D03*
X425161Y1102221D03*
X423311Y1105426D03*
X421462Y1108630D03*
X434411Y1105426D03*
X423311Y1111834D03*
X434411D03*
X423311Y1124651D03*
Y1118243D03*
X421462Y1115039D03*
X434411Y1124651D03*
Y1118243D03*
X423312Y1137469D03*
X423311Y1131060D03*
X434412Y1137769D03*
X434411Y1131060D03*
X452478Y848176D03*
X445078D03*
X441378D03*
X439529Y844671D03*
X446929Y851380D03*
X443228D03*
X439529D03*
X448779Y854584D03*
X446929Y864197D03*
X443229D03*
X441379Y854584D03*
X439529Y864197D03*
X439528Y857789D03*
X437680Y860992D03*
X450629Y864197D03*
X448779Y867401D03*
X441379D03*
X448779Y880219D03*
X446929Y877014D03*
X443229D03*
X441379Y880219D03*
X439529Y877014D03*
X448779Y893036D03*
X446929Y889832D03*
X443229D03*
X441379Y893036D03*
X439529Y896240D03*
Y889832D03*
X437678Y886627D03*
X450629Y889832D03*
X437679Y899445D03*
X446929Y909057D03*
Y902649D03*
X443229D03*
X439528D03*
X437679Y905853D03*
X450629Y902649D03*
X446929Y915466D03*
X446930Y928283D03*
X441379Y925079D03*
Y931487D03*
X446929Y921875D03*
X437678Y918670D03*
X448779Y937897D03*
X447360Y1038136D03*
X452911Y1041340D03*
X451061Y1044544D03*
X449211Y1047749D03*
X447361Y1057361D03*
Y1050952D03*
X452911Y1060565D03*
X447361Y1063770D03*
Y1076587D03*
Y1070178D03*
X449211Y1073383D03*
X452911Y1079791D03*
X449211D03*
X447361Y1082995D03*
X452911Y1092608D03*
X451062Y1089404D03*
X449212Y1086200D03*
X451062Y1095813D03*
X447361Y1108630D03*
Y1102221D03*
X452911Y1099017D03*
X447361Y1121447D03*
Y1115039D03*
Y1127856D03*
Y1134264D03*
X461729Y851380D03*
X458029D03*
X454328D03*
X456179Y841467D03*
X463579D03*
X469129Y851380D03*
X465429D03*
X456179Y854584D03*
X463579D03*
X461729Y864197D03*
X458029D03*
X454329D03*
X469129D03*
X465429D03*
X456179Y867401D03*
X463579D03*
X461729Y877014D03*
X458029D03*
X456179Y880219D03*
X454329Y877014D03*
X463579Y880219D03*
X469129Y877014D03*
X465429D03*
X461729Y889832D03*
X458029D03*
X456179Y893036D03*
X454329Y889832D03*
X463579Y893036D03*
X469129Y896240D03*
Y889832D03*
X465429D03*
X461729Y902649D03*
X458029D03*
X456178Y905853D03*
X454329Y902649D03*
X465429D03*
Y909057D03*
Y915466D03*
X454103Y931359D03*
Y933659D03*
X456178Y918670D03*
X454434Y1022186D03*
Y1019886D03*
X460311Y1041340D03*
X467372Y1036874D03*
X465861Y1044544D03*
X456611Y1047749D03*
X464011D03*
X456611Y1054157D03*
X462162Y1050952D03*
X454761Y1076587D03*
X462162Y1070178D03*
X456612Y1079791D03*
X467711D03*
X458461Y1082995D03*
X456611Y1086200D03*
X460311Y1092608D03*
X464011Y1086200D03*
X467712D03*
Y1092608D03*
X460312Y1105426D03*
X458462Y1102221D03*
X456611Y1099017D03*
X464012Y1105426D03*
Y1099017D03*
X462162Y1108630D03*
X465861D03*
Y1102221D03*
X464012Y1111834D03*
X467711Y1105426D03*
Y1111834D03*
X458462Y1121447D03*
Y1115039D03*
X467712Y1124651D03*
X467711Y1118243D03*
X465862Y1121447D03*
Y1115039D03*
X458462Y1127856D03*
Y1134264D03*
X478379Y841467D03*
X470979D03*
X476529Y851380D03*
X480229D03*
X472829D03*
X483929D03*
X480229Y864197D03*
X478379Y854584D03*
X476529Y864197D03*
X470979Y854584D03*
X472829Y864197D03*
X483929D03*
X478379Y867401D03*
X470979D03*
X480229Y877014D03*
X478379Y880219D03*
X476529Y877014D03*
X472829D03*
X472828Y870606D03*
X470979Y880219D03*
Y873810D03*
X483929Y877014D03*
X480228Y896240D03*
X480229Y889832D03*
X478379Y893036D03*
X470979D03*
X476529Y889832D03*
X472829D03*
X483929D03*
X482078Y899445D03*
X474678Y905853D03*
X483929Y909057D03*
X482079Y912262D03*
X483928Y902649D03*
X476285Y930126D03*
X476528Y921875D03*
X474678Y918670D03*
X483929Y928283D03*
X482078Y918670D03*
X483928Y921875D03*
X482079Y931488D03*
X476285Y934726D03*
X476180Y945355D03*
Y947655D03*
X478378Y944304D03*
X480229Y934691D03*
X483928Y941100D03*
X482079Y944304D03*
X482078Y937896D03*
X483928Y947509D03*
X476285Y962326D03*
Y960026D03*
Y964626D03*
X483928Y960326D03*
X482078Y957122D03*
X482079Y950713D03*
X483929Y966735D03*
X476285Y966926D03*
X476192Y977670D03*
X476335Y980737D03*
X482079Y969939D03*
X483928Y979552D03*
X482078Y976347D03*
X476285Y996826D03*
Y994526D03*
Y989926D03*
Y987626D03*
X476295Y1010500D03*
X476285Y1012926D03*
Y1006026D03*
Y1003726D03*
X484361Y999684D03*
X482512Y1009297D03*
X482511Y1002888D03*
X484362Y1012501D03*
X476275Y1022636D03*
X476285Y1017526D03*
X482511Y1028523D03*
Y1022114D03*
X484361Y1018910D03*
Y1031727D03*
X471282Y1036526D03*
X473507Y1035928D03*
X475111Y1041340D03*
X482511D03*
X482512Y1034931D03*
X484361Y1038136D03*
X471411Y1047749D03*
X482511D03*
X480662Y1050952D03*
X471411Y1054157D03*
X482511Y1060565D03*
X484362Y1050952D03*
Y1070178D03*
X482511Y1079791D03*
X480662Y1082995D03*
X476962Y1089404D03*
X473262Y1082995D03*
X469561Y1089404D03*
X482512Y1086200D03*
X484362Y1089404D03*
X480661Y1095813D03*
X469562D03*
X484362D03*
X480662Y1108630D03*
X478811Y1099017D03*
X473262Y1108630D03*
X476962Y1102221D03*
X475112Y1099017D03*
X471411D03*
X469562Y1102221D03*
X482511Y1105426D03*
Y1111834D03*
X484362Y1108630D03*
X475111Y1111834D03*
X471411D03*
X478811Y1105426D03*
X469562Y1108630D03*
X473262Y1102221D03*
X482511Y1099017D03*
X478811Y1111834D03*
X476962Y1108630D03*
X471411Y1105426D03*
X475111D03*
X484362Y1102221D03*
X480661Y1115039D03*
X478811Y1118243D03*
X476961Y1115039D03*
X475111Y1118243D03*
X471411D03*
X469561Y1115039D03*
X482511Y1118243D03*
X476961Y1127856D03*
X469562D03*
X484361D03*
X484362Y1115039D03*
X473262D03*
X478811Y1131060D03*
X476961Y1140973D03*
X475111Y1131060D03*
X471412Y1137469D03*
Y1131060D03*
X469561Y1140973D03*
X473261Y1134264D03*
X482511Y1131060D03*
X484361Y1140973D03*
X493179Y841467D03*
X485779D03*
X500579D03*
X495029Y851380D03*
X491329D03*
X487629D03*
X498729D03*
X495029Y864197D03*
X493179Y854584D03*
X491329Y864197D03*
X487629D03*
X485779Y854584D03*
X498729Y864197D03*
X500579Y854584D03*
X493179Y867401D03*
X485779D03*
X500579D03*
X495029Y877014D03*
X493179Y880219D03*
X491329Y877014D03*
X487629D03*
X485779Y880219D03*
X500579D03*
X498729Y877014D03*
X489479Y893036D03*
X495029Y889832D03*
X491329D03*
X487629D03*
X498729D03*
X500579Y893036D03*
X498729Y896240D03*
X496879Y899445D03*
X489478D03*
X496878Y912262D03*
X495029Y909057D03*
X489478Y905853D03*
X495029Y902649D03*
X493179Y905853D03*
X485778D03*
X498728Y915466D03*
X495028Y928283D03*
X493179Y925079D03*
X489478D03*
Y918670D03*
X485778Y925079D03*
X496879Y918670D03*
X495029Y921875D03*
X496878Y931488D03*
X489478D03*
X496879Y937896D03*
X495029Y941100D03*
X493179Y944304D03*
X489478D03*
Y937896D03*
X485778Y944304D03*
X498729Y934691D03*
X495028Y947509D03*
X496879Y957122D03*
X495029Y960326D03*
X489478Y957122D03*
Y950713D03*
X496878D03*
X498729Y953917D03*
X495028Y966735D03*
X493179Y963530D03*
X485778D03*
X489478D03*
X500579D03*
X496879Y976347D03*
X496878Y969939D03*
X489478Y976347D03*
Y969939D03*
X495029Y979552D03*
X498728Y973143D03*
X493179Y982756D03*
X489478D03*
X485778D03*
X497311Y1009297D03*
X497312Y1002888D03*
X495462Y999684D03*
X489911Y1009297D03*
X489912Y1002888D03*
X491761Y1006093D03*
X488062D03*
X499161D03*
X495461Y1012501D03*
X497311Y1028523D03*
X489911D03*
Y1022114D03*
Y1015705D03*
X497311Y1022114D03*
X495462Y1018910D03*
X493612Y1015705D03*
X486211D03*
X501012D03*
X499161Y1025318D03*
X495461Y1031727D03*
X497312Y1041340D03*
X489911D03*
Y1034931D03*
X495462Y1038136D03*
X493612Y1034931D03*
X486211D03*
X499161Y1044544D03*
X489911Y1047749D03*
X497311D03*
Y1060565D03*
X489911D03*
Y1054157D03*
X495461Y1050952D03*
X493611Y1054157D03*
X486211D03*
X489911Y1066974D03*
X495461Y1070178D03*
X489911Y1073383D03*
X497312Y1079791D03*
X489911D03*
X497311Y1086200D03*
X493612Y1092608D03*
X489911D03*
Y1086200D03*
X486211Y1092608D03*
X495461Y1089404D03*
X499161Y1082995D03*
X495462Y1095813D03*
X499162D03*
X491762D03*
X497312Y1105426D03*
X493611D03*
X491762Y1102221D03*
X488061D03*
X486211Y1105426D03*
X486212Y1099017D03*
X499161Y1108630D03*
Y1102221D03*
X497312Y1111834D03*
X489911D03*
Y1099017D03*
X495462Y1102221D03*
X501011Y1099017D03*
X493611D03*
X497311D03*
X489911Y1105426D03*
X486211Y1111834D03*
X491762Y1108630D03*
X488062D03*
X497311Y1118243D03*
X495462Y1121447D03*
X493612Y1118243D03*
X489911D03*
X486211D03*
X501011D03*
X499161Y1115039D03*
X491761Y1127856D03*
X499161D03*
X491762Y1115039D03*
X495462D03*
X497311Y1131060D03*
X493611D03*
X489911D03*
X486211D03*
X491761Y1140973D03*
X501011Y1131060D03*
X499161Y1140973D03*
X507979Y841467D03*
X515379D03*
X506129Y851380D03*
X502429D03*
X513529D03*
X509829D03*
X517229D03*
X513529Y864197D03*
X509829D03*
X506129D03*
X502429D03*
X507979Y854584D03*
X515379D03*
X517229Y864197D03*
X507979Y867401D03*
X515379D03*
X509829Y877014D03*
X507979Y880219D03*
X502429Y877014D03*
X513529D03*
X506129D03*
X515379Y880219D03*
X517229Y877014D03*
X506129Y889832D03*
X502428Y896240D03*
X502429Y889832D03*
X513529D03*
X509829D03*
X506128Y896240D03*
X504279Y893036D03*
X515379D03*
X517229Y889832D03*
X507978Y899445D03*
X515378D03*
X511678Y905853D03*
X509829Y909057D03*
X507979Y912262D03*
X502429Y909057D03*
Y902649D03*
X509828D03*
X515378Y912262D03*
Y905853D03*
X502429Y915466D03*
X506129D03*
X511678Y925079D03*
X509829Y928283D03*
X502429D03*
Y921875D03*
X509828D03*
X507978Y918670D03*
X515378Y925079D03*
Y918670D03*
X507979Y931488D03*
X515378D03*
X511678Y944304D03*
X509828Y941100D03*
X506129Y934691D03*
X502429Y941100D03*
Y934691D03*
X515378Y944304D03*
Y937896D03*
X502429Y947509D03*
X509828Y960326D03*
X507978Y957122D03*
X506129Y953917D03*
X502429Y960326D03*
Y953917D03*
X507979Y950713D03*
X515378Y957122D03*
Y950713D03*
X509829Y966735D03*
X502428D03*
X511678Y963530D03*
X504278D03*
X515378D03*
X507978Y976347D03*
X507979Y969939D03*
X502429Y979552D03*
Y973143D03*
X513529D03*
X509828Y979552D03*
X506129Y973143D03*
X515379Y976347D03*
X515378Y969939D03*
X517228Y973143D03*
X511678Y982756D03*
X515378D03*
X510261Y999684D03*
X508411Y1002888D03*
X506562Y1006093D03*
X502862Y999684D03*
X502861Y1012501D03*
X508412Y1009297D03*
X510262Y1012501D03*
X515811Y1009297D03*
Y1002888D03*
X508411Y1028523D03*
X502862Y1025318D03*
Y1018910D03*
X510261D03*
X508411Y1022114D03*
X506562Y1025318D03*
X504711Y1015705D03*
X515811Y1028523D03*
Y1022114D03*
X510262Y1031727D03*
X502862D03*
X515811Y1015705D03*
X512111D03*
X502862Y1044544D03*
Y1038136D03*
X512111Y1034931D03*
X510261Y1038136D03*
X508411Y1041340D03*
X506562Y1044544D03*
X515811Y1034931D03*
Y1041340D03*
X508411Y1047749D03*
X515811D03*
X508411Y1060565D03*
X502862Y1057361D03*
Y1050952D03*
X512111Y1054157D03*
X510262Y1050952D03*
X515811Y1054157D03*
Y1060565D03*
X502862Y1063770D03*
X510262Y1070178D03*
X502862Y1076587D03*
Y1070178D03*
X515811Y1073383D03*
Y1079791D03*
X512112Y1092608D03*
X510262Y1089404D03*
X508412Y1086200D03*
X506562Y1082995D03*
X502862Y1089404D03*
Y1082995D03*
X515812Y1092608D03*
X513961Y1095813D03*
X502862D03*
X517662D03*
X513962Y1108630D03*
Y1102221D03*
X512112Y1099017D03*
X508411D03*
X506562Y1108630D03*
X504711Y1099017D03*
X502862Y1102221D03*
X515811Y1105426D03*
Y1111834D03*
X517662Y1108630D03*
X513961Y1115039D03*
X512111Y1118243D03*
X508411D03*
X504711D03*
X510261Y1115039D03*
X515811Y1118243D03*
X513961Y1127856D03*
X506561D03*
X517662Y1115039D03*
X513961Y1140973D03*
X512111Y1131060D03*
X508411D03*
X504711D03*
X506561Y1140973D03*
X515811Y1131060D03*
X528329Y844671D03*
X522779Y841467D03*
X528329Y851380D03*
X524629D03*
X520929D03*
X532029D03*
X528329Y864197D03*
X524629D03*
X520929D03*
X530179Y860993D03*
Y854584D03*
X522779D03*
X532028Y857789D03*
X533879Y860993D03*
X530178Y867401D03*
X522779D03*
X533879D03*
X528329Y877014D03*
X522779Y880219D03*
X520929Y877014D03*
X530179Y880219D03*
X524629Y877014D03*
X532029D03*
X533879Y880219D03*
Y873810D03*
X532028Y883423D03*
X528329Y896240D03*
Y889832D03*
X524629D03*
X526479Y893036D03*
X524629Y896240D03*
X520929Y889832D03*
X532029D03*
Y896240D03*
X533879Y893036D03*
X522779Y899445D03*
X533879D03*
X528329Y902649D03*
X522778Y912262D03*
X520928Y909057D03*
X519079Y905853D03*
X520929Y902649D03*
X528329Y915466D03*
X524628D03*
X532029D03*
X528329Y909057D03*
X533879Y912262D03*
X528329Y921875D03*
X520928Y928283D03*
X519079Y925079D03*
X522779Y918670D03*
X520929Y921875D03*
X522778Y931488D03*
X528329Y928283D03*
X533879Y918670D03*
X533878Y931488D03*
X528329Y941100D03*
Y934691D03*
X524628D03*
X522779Y937896D03*
X520929Y941100D03*
X519079Y944304D03*
X520928Y947509D03*
X532029Y934691D03*
X533879Y937896D03*
X528329Y947509D03*
Y960326D03*
Y953917D03*
X524629D03*
X522779Y957122D03*
X520929Y960326D03*
X522778Y950713D03*
X520928Y966735D03*
X526479Y963530D03*
X519079D03*
X533879Y957122D03*
X532029Y953917D03*
X533879Y950713D03*
X530178Y963530D03*
X528329Y966735D03*
Y979552D03*
Y973143D03*
X522779Y976347D03*
X522778Y969939D03*
X524628Y973143D03*
X520929Y979552D03*
X533879Y976347D03*
X519079Y982756D03*
X533901Y980606D03*
X533879Y969939D03*
X532029Y973143D03*
X521361Y1012501D03*
Y999684D03*
X528762Y1006093D03*
Y999684D03*
X525061Y1006093D03*
X523211Y1009297D03*
X523212Y1002888D03*
X534311Y1009297D03*
Y1002888D03*
X532461Y1006093D03*
X528761Y1012501D03*
X528762Y1025318D03*
X523211Y1028523D03*
X525061Y1025318D03*
X528762Y1031727D03*
X521361D03*
X519512Y1015705D03*
X521362Y1018910D03*
X523211Y1022114D03*
X526912Y1015705D03*
X528762Y1018910D03*
X530611Y1015705D03*
X534311Y1028523D03*
X534310Y1022114D03*
X532461Y1025318D03*
X528762Y1044544D03*
X525061D03*
X523212Y1041340D03*
X521362Y1038136D03*
X519512Y1034931D03*
X532462Y1044544D03*
X523211Y1047749D03*
X528762Y1038136D03*
X534311Y1041340D03*
Y1047749D03*
X528762Y1057361D03*
Y1050952D03*
X523212Y1060565D03*
X521361Y1050952D03*
X519512Y1054157D03*
X528762Y1063770D03*
X534311Y1060565D03*
X528762Y1076587D03*
Y1070178D03*
X521361D03*
X523212Y1079791D03*
X534311D03*
X523211Y1086200D03*
X521361Y1089404D03*
X519511Y1092608D03*
X528762Y1089404D03*
Y1082995D03*
X525061D03*
X532462Y1082996D03*
X534311Y1086200D03*
X528761Y1095813D03*
X526911Y1105426D03*
X521361Y1102221D03*
X519511Y1105426D03*
X519512Y1099017D03*
X532461Y1108630D03*
X530612Y1111834D03*
X523211D03*
X526911Y1099017D03*
X534311D03*
X532460Y1102221D03*
X521362Y1108630D03*
X525062D03*
X534311Y1111834D03*
X523211Y1105426D03*
X534311D03*
X528762Y1108630D03*
X519511Y1111834D03*
X526911D03*
X530611Y1124651D03*
Y1118243D03*
X528762Y1121447D03*
X523211Y1118243D03*
X521361Y1115039D03*
X519511Y1118243D03*
X532461Y1115039D03*
X528761Y1127856D03*
X521361D03*
X525062Y1115039D03*
X528762D03*
X530612Y1137469D03*
Y1131060D03*
X526912D03*
X523211D03*
X519511D03*
X528761Y1134264D03*
X521361Y1140973D03*
X534311Y1131060D03*
X537580Y848176D03*
X535729Y844671D03*
Y851380D03*
X544979Y860993D03*
Y854584D03*
X539428Y864197D03*
X537579Y854584D03*
Y860993D03*
X544979Y867401D03*
X541279D03*
X537579D03*
X546829Y870606D03*
X541279Y873810D03*
X535729Y870606D03*
Y883423D03*
X541279Y880219D03*
X546829Y883423D03*
X537579Y893036D03*
X541279Y886627D03*
X544979D03*
X537579D03*
X535729Y889832D03*
X550529D03*
X537579Y899445D03*
X548679Y912262D03*
X537579D03*
X539429Y909057D03*
X537579Y905853D03*
X535729Y909057D03*
X543129D03*
X535729Y902649D03*
X548679Y905853D03*
X537579Y918670D03*
X535729Y921875D03*
X537578Y931488D03*
X548678D03*
X537579Y937896D03*
X535729Y941100D03*
X539429Y947509D03*
X535729D03*
X537579Y957122D03*
Y950713D03*
X535729Y960326D03*
Y966735D03*
X537579Y963530D03*
X539429Y979552D03*
X537579Y982756D03*
X541279Y969939D03*
X539429Y973143D03*
X535729D03*
X539862Y1006092D03*
X539861Y999684D03*
X536161D03*
Y1006093D03*
X543563Y1006092D03*
X549254Y1000648D03*
X536161Y1012501D03*
Y1025318D03*
X539861Y1018910D03*
X541712Y1015705D03*
X545412D03*
X538012D03*
X536161Y1018910D03*
X549112Y1015705D03*
X536161Y1031727D03*
X545412Y1034931D03*
X539862Y1044544D03*
X539861Y1038136D03*
X541711Y1034931D03*
X538011D03*
X536161Y1038136D03*
X549112Y1034931D03*
X541711Y1054157D03*
X538011D03*
X545411D03*
X538011Y1060565D03*
X536161Y1050952D03*
X538011Y1066974D03*
X539861Y1076587D03*
X536162Y1082996D03*
X538011Y1092608D03*
X536161Y1089404D03*
X545411Y1092608D03*
X547262Y1082996D03*
X543561Y1095813D03*
X536161D03*
X547261D03*
X545412Y1105426D03*
X541711D03*
X539861Y1108630D03*
Y1102221D03*
X536161D03*
X541711Y1111834D03*
X545411D03*
X538011Y1105426D03*
X536161Y1108630D03*
X538011Y1111834D03*
X543561Y1108630D03*
X545411Y1124651D03*
Y1118243D03*
X543562Y1115039D03*
X539862D03*
X538011Y1124651D03*
X536161Y1115039D03*
X541711Y1131060D03*
X536162Y1134264D03*
X551429Y979057D03*
X550701Y972608D03*
X550961Y1031727D03*
X560571Y1614292D03*
X580431Y1602380D03*
X688999Y1051247D03*
X748399D03*
X1293802Y162999D03*
X1297007Y161149D03*
X1297012Y168549D03*
X1297007Y164849D03*
X1293802Y183349D03*
Y187049D03*
Y190749D03*
Y198149D03*
Y194449D03*
Y201849D03*
X1296999Y209249D03*
X1300774Y155288D03*
X1309832Y161149D03*
X1303417D03*
X1309832Y168549D03*
X1303417D03*
X1303422Y172249D03*
X1313033Y174099D03*
X1306622D03*
X1300207Y185199D03*
X1306617Y181499D03*
X1300207Y192599D03*
X1309817Y187049D03*
X1306617Y192599D03*
X1313023Y199999D03*
X1306617D03*
X1300207D03*
X1303407Y201849D03*
X1303422Y209249D03*
X1313032Y214799D03*
X1306622Y218499D03*
X1303417Y212949D03*
Y216649D03*
X1300207Y214799D03*
X1301151Y225450D03*
X1309828Y224049D03*
X1306622Y222199D03*
X1309100Y236477D03*
X1313920Y854584D03*
X1312266Y857972D03*
X1312070Y877014D03*
X1310221Y880219D03*
X1308370Y877014D03*
X1312070Y896240D03*
X1310220Y893036D03*
X1308371Y902649D03*
X1312070Y915466D03*
X1308370D03*
X1308371Y921875D03*
X1312070Y934692D03*
X1308371Y941100D03*
X1308370Y934692D03*
X1312070Y953917D03*
X1308370D03*
X1310221Y957122D03*
X1308371Y973143D03*
X1310221Y976347D03*
X1314352Y996480D03*
X1314353Y1002888D03*
X1308803Y1006093D03*
X1314353Y1015705D03*
Y1022114D03*
X1308803Y1025318D03*
Y1018910D03*
X1314353Y1041340D03*
X1308803Y1044544D03*
X1310653Y1041340D03*
X1314353Y1060565D03*
X1312502Y1082995D03*
X1314353Y1111834D03*
Y1105426D03*
X1312503Y1115039D03*
Y1127856D03*
X1320469Y155288D03*
X1322652Y161149D03*
X1316242D03*
X1319452Y166699D03*
X1329062Y168549D03*
X1319442Y170399D03*
X1318502Y176574D03*
Y186024D03*
Y182874D03*
X1329062Y172249D03*
X1316237D03*
X1331102Y176574D03*
X1327952Y186024D03*
Y182874D03*
X1318502Y189174D03*
X1315352Y195474D03*
X1327952Y189174D03*
X1331102Y195474D03*
X1327952Y198624D03*
X1321652D03*
X1325852Y214799D03*
X1319442Y218499D03*
X1329062Y209249D03*
X1319442Y207399D03*
X1329062Y216649D03*
X1319442Y222199D03*
X1329061Y224049D03*
X1326377Y235784D03*
X1321986Y236726D03*
X1326869Y844971D03*
X1323170D03*
X1321320Y848176D03*
X1330571Y851380D03*
X1323170D03*
X1319469D03*
X1317620Y854584D03*
X1315770Y857789D03*
X1330571Y864197D03*
X1326871D03*
X1323171D03*
Y857789D03*
X1325020Y854584D03*
X1321321Y860993D03*
X1319469Y857789D03*
X1317621Y867401D03*
X1328721D03*
X1325021D03*
X1330571Y877014D03*
X1328722Y880219D03*
X1326871Y877014D03*
X1321321Y873810D03*
X1315771Y877014D03*
X1317621Y873810D03*
X1321321Y880219D03*
X1319471Y877014D03*
X1315771Y883423D03*
X1326871D03*
X1323171D03*
X1328720Y899445D03*
X1315771Y896240D03*
Y889832D03*
X1328720Y893036D03*
Y886627D03*
X1325021D03*
X1321321Y893036D03*
X1319470Y896240D03*
X1321321Y899445D03*
X1328720Y905853D03*
X1325020D03*
X1317621Y912262D03*
X1317620Y905853D03*
X1328720Y912262D03*
X1323171Y909057D03*
Y902649D03*
X1321321Y912262D03*
X1315771Y915466D03*
X1319471D03*
X1328720Y925079D03*
Y918670D03*
X1325020Y925079D03*
X1317620D03*
X1323171Y928283D03*
Y921875D03*
X1321321Y918670D03*
X1317621Y931488D03*
X1328720D03*
X1321321D03*
X1323171Y941100D03*
X1325020Y944304D03*
X1323171Y947509D03*
X1317620Y944304D03*
X1328720D03*
Y937896D03*
X1315771Y934692D03*
X1321321Y937896D03*
X1319470Y934692D03*
X1321321Y957122D03*
X1323171Y966735D03*
X1325020Y963530D03*
X1323171Y960326D03*
X1321321Y950713D03*
X1315771Y953917D03*
Y966735D03*
X1319470Y953917D03*
X1319471Y966735D03*
X1319470Y960326D03*
X1317621Y950713D03*
X1328720Y957122D03*
Y963530D03*
Y950713D03*
X1321321Y969939D03*
X1325020Y982756D03*
X1323171Y979552D03*
X1321321Y976347D03*
X1315771Y973143D03*
X1319471D03*
X1328720Y969939D03*
X1330570Y973143D03*
X1326871D03*
X1328720Y982756D03*
X1328721Y976347D03*
X1315771Y979552D03*
X1318053Y1009297D03*
Y1002888D03*
X1327304Y1006093D03*
X1331003D03*
X1329153Y1009297D03*
Y1002888D03*
X1323603Y999684D03*
X1321753Y1009297D03*
X1319903Y1006093D03*
X1321753Y1002888D03*
X1323603Y1012501D03*
X1329153Y1028523D03*
Y1015705D03*
X1318053Y1022114D03*
Y1015705D03*
X1329153Y1022114D03*
X1325453Y1015705D03*
X1323603Y1018910D03*
X1321753Y1028523D03*
X1319903Y1018910D03*
X1321753Y1022114D03*
Y1015705D03*
X1319903Y1031727D03*
X1323603D03*
X1329153Y1034931D03*
Y1047749D03*
X1318053Y1041340D03*
X1319903Y1038136D03*
X1329153Y1041340D03*
X1325453Y1034931D03*
X1323603Y1038136D03*
X1321753Y1041340D03*
X1319903Y1044544D03*
X1321753Y1047749D03*
X1329153Y1060565D03*
Y1054157D03*
X1325453D03*
X1319903Y1057361D03*
Y1050952D03*
X1323603D03*
Y1057361D03*
X1321753Y1060565D03*
X1319903Y1063770D03*
X1329153Y1073383D03*
X1319903Y1076587D03*
Y1070178D03*
X1316204Y1076587D03*
X1329153Y1066974D03*
X1323603Y1076587D03*
Y1070178D03*
X1325454Y1073383D03*
X1321753Y1066974D03*
X1329153Y1079791D03*
X1321753D03*
X1318053D03*
X1329153Y1086200D03*
Y1092608D03*
X1325452Y1092609D03*
X1323603Y1089404D03*
X1321752Y1086200D03*
X1319902Y1082995D03*
X1316202D03*
X1316203Y1095813D03*
X1331003Y1108630D03*
X1329153Y1099017D03*
X1323603Y1108630D03*
X1316203D03*
Y1102221D03*
X1325453Y1099017D03*
X1323603Y1102221D03*
X1319903D03*
X1316203Y1115039D03*
X1331003D03*
X1327303Y1121447D03*
Y1115039D03*
X1325453Y1124651D03*
X1325454Y1118243D03*
X1321753D03*
X1319903Y1115039D03*
X1329152Y1137469D03*
X1329153Y1131060D03*
X1321752Y1137469D03*
X1325453Y1131060D03*
X1319903Y1134264D03*
X1344103Y155288D03*
X1342936Y159301D03*
X1335472Y161149D03*
X1346137Y168549D03*
X1342907Y166699D03*
X1332268D03*
X1346137Y164849D03*
X1339727D03*
X1335472Y168549D03*
X1339568Y176028D03*
X1339727Y179649D03*
X1342937Y181499D03*
Y185199D03*
X1346137Y172249D03*
X1335472D03*
X1339727Y190749D03*
X1342937Y188899D03*
X1334252Y195474D03*
X1346137Y194449D03*
Y190749D03*
X1346147Y209248D03*
X1332262Y218499D03*
Y214799D03*
X1332285Y226210D03*
X1342937Y222199D03*
X1332267D03*
X1343521Y841467D03*
X1336121D03*
X1345371Y851380D03*
X1341671D03*
X1337971D03*
X1334271D03*
X1345371Y864197D03*
X1343521Y854584D03*
X1341671Y864197D03*
X1337971D03*
X1336121Y854584D03*
X1334271Y864197D03*
X1343521Y867401D03*
X1336121D03*
X1345371Y877014D03*
X1343521Y880219D03*
X1341671Y877014D03*
X1337971D03*
X1334271D03*
X1332420Y886627D03*
X1345371Y896240D03*
Y889832D03*
X1341671Y896240D03*
Y889832D03*
X1337970Y896240D03*
X1337971Y889832D03*
X1336121Y893036D03*
X1334270Y889832D03*
X1332420Y905853D03*
X1341671Y909057D03*
Y902649D03*
X1336120Y912262D03*
X1334270Y909057D03*
X1334271Y902649D03*
X1347221Y912262D03*
X1345371Y915466D03*
X1341671D03*
X1337970D03*
X1332421Y925079D03*
X1341671Y928283D03*
Y921875D03*
X1334270Y928283D03*
X1334271Y921875D03*
X1347220Y918670D03*
X1336120Y931488D03*
X1347221D03*
X1341671Y947509D03*
X1334270D03*
X1334271Y941100D03*
X1332421Y944304D03*
X1345371Y934691D03*
X1341671D03*
X1337970D03*
X1337971Y953917D03*
X1345371D03*
X1341671D03*
Y960326D03*
X1347220Y957122D03*
X1343520Y963530D03*
X1339821D03*
X1341670Y966735D03*
X1347221Y950713D03*
X1334271Y960326D03*
X1336121Y957122D03*
X1332421Y963530D03*
X1334270Y966735D03*
X1336120Y950713D03*
X1347221Y969939D03*
X1337970Y973143D03*
X1347220Y976347D03*
X1345371Y973143D03*
X1341671Y979552D03*
Y973143D03*
X1336120Y969939D03*
X1336121Y976347D03*
X1334271Y979552D03*
X1332421Y982756D03*
X1342104Y999684D03*
Y1006093D03*
X1338403D03*
X1336553Y1009297D03*
X1336554Y1002888D03*
X1334704Y999684D03*
X1347654Y1009297D03*
X1342103Y1012501D03*
X1334703D03*
X1332854Y1015705D03*
X1345804Y1025318D03*
X1343953Y1015705D03*
X1342104Y1025318D03*
Y1018910D03*
X1340254Y1015705D03*
X1336553Y1028523D03*
X1338403Y1025318D03*
X1336554Y1022114D03*
X1334704Y1018910D03*
X1347653Y1028523D03*
Y1022114D03*
X1342104Y1031727D03*
X1334703D03*
X1332854Y1034931D03*
X1345804Y1044544D03*
X1342104D03*
Y1038136D03*
X1338403Y1044544D03*
X1336554Y1041340D03*
X1334704Y1038136D03*
X1347653Y1041340D03*
X1336553Y1047749D03*
X1347653D03*
X1332854Y1054157D03*
X1342104Y1057361D03*
Y1050952D03*
X1336554Y1060565D03*
X1334704Y1057361D03*
X1334703Y1050952D03*
X1347653Y1060565D03*
X1345804Y1063770D03*
X1342104D03*
X1338403D03*
X1332854Y1073383D03*
X1342104Y1070178D03*
X1336553Y1066974D03*
X1334703Y1070178D03*
X1334704Y1076587D03*
X1347654Y1066974D03*
X1336554Y1079791D03*
X1347653D03*
X1345804Y1082995D03*
X1342104Y1089404D03*
Y1082995D03*
X1338403D03*
X1336553Y1086200D03*
X1334703Y1089404D03*
X1332854Y1092608D03*
X1347654Y1086200D03*
X1342104Y1095813D03*
X1334703D03*
X1342104Y1102221D03*
X1338404D03*
X1336553Y1099017D03*
X1332853Y1105426D03*
Y1099017D03*
X1347654Y1105426D03*
Y1099017D03*
X1340254Y1111834D03*
X1332854D03*
X1347654D03*
X1343953Y1118243D03*
X1340253D03*
X1338403Y1115039D03*
X1336553Y1118243D03*
X1332853D03*
X1347653D03*
X1342104Y1127856D03*
X1334703D03*
X1343953Y1131060D03*
X1342103Y1140973D03*
X1340254Y1131060D03*
X1336554D03*
X1334703Y1140973D03*
X1332854Y1131060D03*
X1347653D03*
X1349351Y159298D03*
X1355758D03*
X1355761Y162998D03*
X1358865Y166732D03*
Y158854D03*
Y162793D03*
X1349351Y166698D03*
X1352557Y164848D03*
X1358865Y170671D03*
Y174603D03*
Y182484D03*
Y178544D03*
X1355761Y170398D03*
X1352557Y179648D03*
X1358371Y188778D03*
X1358865Y195240D03*
Y199180D03*
X1349351Y196298D03*
X1352561Y194448D03*
X1352551Y190748D03*
X1349345Y188898D03*
X1355761Y192598D03*
X1358865Y207060D03*
Y203120D03*
Y213994D03*
Y217934D03*
X1352560Y205549D03*
X1355765Y207399D03*
X1349351Y214798D03*
X1352561Y212948D03*
X1349351Y211098D03*
Y222198D03*
X1358321Y841467D03*
X1350921D03*
X1360171Y851380D03*
X1356471D03*
X1352771D03*
X1349071D03*
X1363871D03*
X1360171Y864197D03*
X1358321Y854584D03*
X1356471Y864197D03*
X1352771D03*
X1350921Y854584D03*
X1349071Y864197D03*
X1363871D03*
X1358321Y867401D03*
X1350921D03*
X1360171Y877014D03*
X1358321Y880219D03*
X1356471Y877014D03*
X1352771D03*
X1350921Y880219D03*
X1349071Y877014D03*
X1363871D03*
X1360171Y889832D03*
X1356471D03*
X1354621Y893036D03*
X1352771Y889832D03*
X1349071D03*
X1363871Y896240D03*
Y889832D03*
X1362021Y899445D03*
X1354620D03*
X1362020Y912262D03*
X1360170Y909057D03*
X1360171Y902649D03*
X1358321Y905853D03*
X1354620Y912262D03*
Y905853D03*
X1350920D03*
X1349071Y909057D03*
X1349070Y902649D03*
X1363870Y915466D03*
X1362021Y918670D03*
X1360170Y928283D03*
X1360171Y921875D03*
X1358321Y925079D03*
X1354620D03*
Y918670D03*
X1350920Y925079D03*
X1349071Y928283D03*
X1349070Y921875D03*
X1362020Y931488D03*
X1360171Y941100D03*
X1358321Y944304D03*
X1354620D03*
X1360170Y947509D03*
X1350920Y944304D03*
X1349071Y947509D03*
X1349070Y941100D03*
X1362021Y937896D03*
X1354620D03*
X1363870Y934691D03*
X1363871Y953917D03*
X1360171Y960326D03*
X1362021Y957122D03*
X1354620D03*
X1358321Y963530D03*
X1354620D03*
X1360170Y966735D03*
X1354620Y950713D03*
X1362020D03*
X1349070Y960326D03*
X1350920Y963530D03*
X1349071Y966735D03*
X1362020Y969939D03*
X1354620D03*
X1363870Y973143D03*
X1362021Y976347D03*
X1360171Y979552D03*
X1358321Y982756D03*
X1356470Y973143D03*
X1354620Y982756D03*
X1354621Y976347D03*
X1350920Y982756D03*
X1349070Y979552D03*
X1352771Y973143D03*
X1351352Y996480D03*
X1349503Y999684D03*
X1362453Y1009297D03*
X1362454Y1002888D03*
X1360604Y999684D03*
X1355053Y1009297D03*
Y1002888D03*
X1360603Y1012501D03*
X1349504D03*
X1362453Y1028523D03*
X1362454Y1022114D03*
X1360604Y1018910D03*
X1358754Y1015705D03*
X1355053Y1028523D03*
Y1022114D03*
Y1015705D03*
X1351353D03*
X1349503Y1018910D03*
X1360603Y1031727D03*
X1349504D03*
X1362454Y1041340D03*
X1360604Y1038136D03*
X1358754Y1034931D03*
X1355053Y1041340D03*
Y1034931D03*
X1351353D03*
X1349503Y1038136D03*
X1362453Y1047749D03*
X1355053D03*
X1362454Y1060565D03*
X1360604Y1057361D03*
X1360603Y1050952D03*
X1358754Y1054157D03*
X1355053D03*
X1351353D03*
X1349503Y1057361D03*
X1349504Y1050952D03*
X1362453Y1066974D03*
X1360604Y1076587D03*
X1360603Y1070178D03*
X1358754Y1073383D03*
X1355053D03*
Y1066974D03*
X1351353Y1073383D03*
X1349503Y1076587D03*
X1349504Y1070178D03*
X1362453Y1079791D03*
X1355053D03*
X1362453Y1086200D03*
X1360603Y1089404D03*
X1358753Y1092608D03*
X1355053D03*
Y1086200D03*
X1351353Y1092608D03*
X1349504Y1089404D03*
X1360604Y1095813D03*
X1349504D03*
X1362454Y1099017D03*
X1360604Y1102221D03*
X1356904Y1108630D03*
X1355053Y1099017D03*
X1353204Y1102221D03*
X1349503Y1108630D03*
Y1102221D03*
X1362453Y1118243D03*
X1360603Y1115039D03*
X1358753Y1118243D03*
X1355053D03*
X1353203Y1115039D03*
X1351353Y1118243D03*
X1349503Y1115039D03*
X1356903Y1127856D03*
X1349503D03*
X1362453Y1131060D03*
X1358753D03*
X1356903Y1140973D03*
X1355053Y1131060D03*
X1351353D03*
X1349503Y1140973D03*
X1373121Y841467D03*
X1365721D03*
X1378671Y851380D03*
X1374971D03*
X1371271D03*
X1367571D03*
X1378671Y864197D03*
X1374971D03*
X1373121Y854584D03*
X1371271Y864197D03*
X1367571D03*
X1365721Y854584D03*
X1373121Y867401D03*
X1365721D03*
X1378671Y877014D03*
X1374971D03*
X1373121Y880219D03*
X1371271Y877014D03*
X1367571D03*
X1365721Y880219D03*
X1378671Y889832D03*
X1374971D03*
X1371271Y896240D03*
Y889832D03*
X1367570Y896240D03*
X1367571Y889832D03*
X1365721Y893036D03*
X1374971Y909057D03*
X1374970Y902649D03*
X1373121Y912262D03*
X1367571Y909057D03*
Y902649D03*
X1371271Y915466D03*
X1367571D03*
X1376820Y925079D03*
X1374971Y928283D03*
X1374970Y921875D03*
X1373120Y918670D03*
X1367571Y928283D03*
Y921875D03*
X1376820Y937896D03*
X1374970Y941100D03*
X1371271Y934691D03*
X1367571Y941100D03*
Y934691D03*
X1374971Y947509D03*
X1367571D03*
X1376820Y957122D03*
X1374970Y960326D03*
X1373120Y957122D03*
X1373121Y950713D03*
X1371271Y953917D03*
X1367571Y960326D03*
Y953917D03*
X1376820Y963530D03*
X1374971Y966735D03*
X1367571D03*
X1376820Y982756D03*
Y969939D03*
X1374970Y979552D03*
X1373120Y976347D03*
X1373121Y969939D03*
X1371271Y973143D03*
X1367571Y979552D03*
Y973143D03*
X1364303Y1006093D03*
X1377253Y1002888D03*
X1373554Y1009297D03*
X1373553Y1002888D03*
X1371704Y1006093D03*
X1368004D03*
Y999684D03*
X1375404Y1012501D03*
X1368003D03*
X1364303Y1025318D03*
X1375403Y1018910D03*
X1373553Y1028523D03*
Y1022114D03*
X1371704Y1025318D03*
X1369853Y1015705D03*
X1368004Y1025318D03*
Y1018910D03*
X1366154Y1015705D03*
X1375404Y1031727D03*
X1368004D03*
X1364303Y1044544D03*
X1375403Y1038136D03*
X1373553Y1041340D03*
X1371704Y1044544D03*
X1368004D03*
Y1038136D03*
X1373553Y1047749D03*
X1375403Y1057361D03*
X1375404Y1050952D03*
X1373553Y1060565D03*
X1368004Y1057361D03*
Y1050952D03*
X1364303Y1063770D03*
X1371704D03*
X1368004D03*
X1377253Y1073383D03*
X1375403Y1076587D03*
X1375404Y1070178D03*
X1373554Y1066974D03*
X1368004Y1076587D03*
Y1070178D03*
X1377253Y1079791D03*
X1373553D03*
X1364303Y1082995D03*
X1377254Y1092608D03*
X1377253Y1086200D03*
X1375404Y1089404D03*
X1373554Y1086200D03*
X1371704Y1082995D03*
X1368004Y1089404D03*
Y1082995D03*
X1379104Y1095813D03*
X1375403D03*
X1368004D03*
X1364304Y1108630D03*
Y1102221D03*
X1377253Y1105426D03*
X1375404Y1102221D03*
X1373554Y1099017D03*
X1371704Y1102221D03*
X1366153Y1105426D03*
X1373553Y1111834D03*
X1366153D03*
X1364303Y1115039D03*
X1377253Y1118243D03*
X1373553D03*
X1371703Y1115039D03*
X1369853Y1118243D03*
X1366153D03*
X1364303Y1127856D03*
X1379103D03*
X1371703D03*
X1364303Y1140973D03*
X1379103D03*
X1377253Y1131060D03*
X1373553D03*
X1371703Y1140973D03*
X1369853Y1131060D03*
X1366153D03*
X1380521Y841467D03*
X1395321D03*
X1387921D03*
X1393471Y851380D03*
X1389771D03*
X1386071D03*
X1382371D03*
X1380521Y854584D03*
X1395321D03*
X1393471Y864197D03*
X1389771D03*
X1387921Y854584D03*
X1386071Y864197D03*
X1382371D03*
X1380521Y867401D03*
X1395321D03*
X1387921D03*
X1380521Y880219D03*
X1395321D03*
X1393471Y877014D03*
X1389771D03*
X1387921Y880219D03*
X1386071Y877014D03*
Y870606D03*
X1382371Y877014D03*
X1395321Y893036D03*
X1393471Y889832D03*
X1389771D03*
X1387921Y893036D03*
X1386071Y889832D03*
X1384221Y893036D03*
X1382371Y889832D03*
X1386071Y902649D03*
X1380520Y912262D03*
Y905853D03*
X1395320Y912262D03*
X1395321Y905853D03*
X1393471Y902649D03*
X1389771D03*
X1386071Y909057D03*
Y915466D03*
X1380520Y918670D03*
X1395187Y926265D03*
X1395320Y918670D03*
X1386071Y921875D03*
X1381189Y930811D03*
Y938045D03*
X1381287Y946239D03*
Y948539D03*
X1381189Y935745D03*
X1390234Y942097D03*
X1381264Y965896D03*
Y963596D03*
X1390506Y971139D03*
X1392896D03*
X1381003Y981269D03*
Y978969D03*
Y986421D03*
X1381243Y992971D03*
Y995271D03*
X1381003Y988721D03*
X1381369Y1007156D03*
X1381373Y1004848D03*
X1393716Y1000059D03*
X1391326D03*
X1381128Y1022427D03*
X1381140Y1026821D03*
X1384466Y1034270D03*
Y1031970D03*
X1393904Y1044544D03*
X1384653Y1041340D03*
X1380953Y1047749D03*
X1388353D03*
X1380953Y1060565D03*
X1393904Y1050952D03*
X1392053Y1060565D03*
Y1054157D03*
X1388353Y1060565D03*
X1386504Y1050952D03*
X1384653Y1054157D03*
X1380953Y1066974D03*
X1395753Y1073383D03*
X1392053Y1066974D03*
X1386504Y1076587D03*
Y1070178D03*
X1382803Y1076587D03*
X1380953Y1079791D03*
X1388353D03*
X1393903Y1089404D03*
Y1082995D03*
X1392053Y1092608D03*
X1392054Y1086200D03*
X1388353Y1092608D03*
X1384653Y1086200D03*
X1386504Y1095813D03*
X1382804D03*
X1380954Y1105426D03*
X1393904Y1102221D03*
X1392054Y1099017D03*
X1390204Y1108630D03*
X1388353Y1099017D03*
X1386504Y1102221D03*
X1382803Y1108630D03*
Y1102221D03*
X1380954Y1111834D03*
X1380953Y1118243D03*
X1386503Y1115039D03*
X1384653Y1118243D03*
X1382803Y1115039D03*
X1386503Y1127856D03*
X1380953Y1131060D03*
X1386503Y1140973D03*
X1384653Y1131060D03*
X1408269Y844971D03*
X1402721Y841467D03*
X1397171Y851380D03*
X1408271D03*
X1404571D03*
X1400871D03*
X1397171Y864197D03*
X1408271D03*
X1404571D03*
X1402721Y854584D03*
X1400871Y864197D03*
X1410121Y854584D03*
Y867401D03*
X1402721D03*
X1397171Y877014D03*
X1410121Y880219D03*
X1408271Y877014D03*
X1404571D03*
X1402721Y880219D03*
X1400871Y877014D03*
X1397171Y889832D03*
X1410121Y893036D03*
X1408271Y889832D03*
X1404571D03*
X1402721Y893036D03*
X1400871Y889832D03*
Y902649D03*
X1397171D03*
X1408271D03*
X1404571Y909057D03*
Y902649D03*
Y915466D03*
X1410121Y925079D03*
Y931488D03*
X1403016Y949498D03*
Y947198D03*
X1406420Y937896D03*
X1404016Y936469D03*
X1410120Y937896D03*
X1403046Y963634D03*
Y965934D03*
Y978035D03*
Y980335D03*
Y992421D03*
Y994721D03*
Y1009174D03*
Y1006874D03*
Y1021962D03*
Y1019662D03*
X1397604Y1063770D03*
Y1082995D03*
Y1095813D03*
X1428620Y848176D03*
X1415669Y844971D03*
X1421220Y848176D03*
X1417520D03*
X1423070Y851380D03*
X1419370D03*
X1415671D03*
X1413822Y860993D03*
X1426771Y864197D03*
X1424921Y854584D03*
X1423071Y864197D03*
X1419371D03*
X1417521Y854584D03*
X1415671Y864197D03*
Y857789D03*
X1424921Y867401D03*
X1417521D03*
X1424921Y880219D03*
X1423071Y877014D03*
X1419371D03*
X1417521Y880219D03*
X1415671Y877014D03*
X1413820Y886627D03*
X1426771Y889832D03*
X1424921Y893036D03*
X1423071Y889832D03*
X1419371D03*
X1417521Y893036D03*
X1415671Y896240D03*
Y889832D03*
X1413821Y899445D03*
Y905853D03*
X1426771Y902649D03*
X1423071Y909057D03*
Y902649D03*
X1419371D03*
X1415670D03*
X1423071Y915466D03*
Y928283D03*
X1417520Y925079D03*
Y931488D03*
X1413820Y918670D03*
X1423071Y921875D03*
X1424920Y937896D03*
X1421220D03*
X1417520D03*
X1413820D03*
X1427203Y1044544D03*
X1425353Y1047749D03*
X1429053Y1060565D03*
X1423503Y1057361D03*
Y1050952D03*
Y1063770D03*
X1425353Y1073383D03*
X1423503Y1076587D03*
Y1070178D03*
X1429053Y1079791D03*
X1425353D03*
X1425354Y1086200D03*
X1423503Y1082995D03*
X1437871Y851380D03*
X1434171D03*
X1430470D03*
X1432321Y841467D03*
X1439721D03*
X1445271Y851380D03*
X1441571D03*
X1439721Y854584D03*
X1432321D03*
X1437871Y864197D03*
X1434171D03*
X1430471D03*
X1445271D03*
X1441571D03*
X1432321Y867401D03*
X1439721D03*
X1437871Y877014D03*
X1434171D03*
X1432321Y880219D03*
X1430471Y877014D03*
X1445271D03*
X1441571D03*
X1439721Y880219D03*
X1437871Y889832D03*
X1434171D03*
X1432321Y893036D03*
X1430471Y889832D03*
X1445271Y896240D03*
X1439721Y893036D03*
X1445271Y889832D03*
X1441571D03*
X1437871Y902649D03*
X1434171D03*
X1432320Y905853D03*
X1430471Y902649D03*
X1441571D03*
Y909057D03*
Y915466D03*
X1430244Y931358D03*
Y933658D03*
X1432320Y918670D03*
X1430575Y1022185D03*
Y1019885D03*
X1443541Y1036914D03*
X1436453Y1041340D03*
X1442003Y1044544D03*
X1432753Y1047749D03*
X1440153D03*
X1432753Y1054157D03*
X1442004Y1057361D03*
X1438304Y1050952D03*
X1434604Y1063770D03*
X1442004D03*
X1432753Y1073383D03*
X1430903Y1076587D03*
X1430904Y1070178D03*
X1443853Y1073383D03*
Y1066974D03*
X1438304Y1070178D03*
X1432754Y1079791D03*
X1443853D03*
X1434603Y1082995D03*
X1432753Y1086200D03*
X1436453Y1092608D03*
X1443854Y1086200D03*
X1440153D03*
X1443854Y1092608D03*
X1442003Y1108630D03*
Y1102221D03*
X1440154Y1099017D03*
X1443853Y1105426D03*
Y1111834D03*
X1454521Y841467D03*
X1447121D03*
X1460071Y851380D03*
X1452671D03*
X1456371D03*
X1448971D03*
X1460071Y864197D03*
X1456371D03*
X1454521Y854584D03*
X1452671Y864197D03*
X1447121Y854584D03*
X1448971Y864197D03*
X1454521Y867401D03*
X1447121D03*
X1460071Y877014D03*
X1456371D03*
X1454521Y880219D03*
X1452671Y877014D03*
X1448971D03*
X1448970Y870606D03*
X1447121Y880219D03*
Y873810D03*
X1456370Y896240D03*
X1456371Y889832D03*
X1454521Y893036D03*
X1447121D03*
X1460071Y889832D03*
X1452671D03*
X1448971D03*
X1458220Y899445D03*
X1460071Y909057D03*
X1458221Y912262D03*
X1450820Y905853D03*
X1460070Y902649D03*
X1452426Y930125D03*
X1460071Y928283D03*
X1458220Y918670D03*
X1456371Y921875D03*
X1460070D03*
X1452670D03*
X1450820Y918670D03*
X1458220Y931488D03*
X1452426Y934725D03*
X1454520Y944304D03*
X1452321Y945354D03*
Y947654D03*
X1460070Y941100D03*
X1458221Y944304D03*
X1458220Y937896D03*
X1456371Y934691D03*
X1460070Y947509D03*
X1452426Y962325D03*
Y960025D03*
Y964625D03*
X1460070Y960326D03*
X1458220Y957122D03*
X1458221Y950713D03*
X1460071Y966735D03*
X1452426Y966925D03*
X1452333Y977669D03*
X1452476Y980736D03*
X1458221Y969939D03*
X1460070Y979552D03*
X1458220Y976347D03*
X1452426Y996825D03*
Y994525D03*
Y989925D03*
Y987625D03*
X1452436Y1010499D03*
X1452426Y1006025D03*
Y1003725D03*
Y1012925D03*
X1460503Y999684D03*
X1458654Y1009297D03*
X1458653Y1002888D03*
X1460504Y1012501D03*
X1452416Y1022635D03*
X1452426Y1017525D03*
X1458653Y1028523D03*
Y1022114D03*
X1460503Y1018910D03*
Y1031727D03*
X1447424Y1036526D03*
X1449649Y1035928D03*
X1458653Y1041340D03*
X1458654Y1034931D03*
X1451253Y1041340D03*
X1460503Y1038136D03*
X1458653Y1047749D03*
X1447553D03*
X1460503Y1057361D03*
X1458653Y1060565D03*
X1456804Y1050952D03*
X1451253Y1060565D03*
X1447553Y1054157D03*
X1460504Y1050952D03*
X1460503Y1076587D03*
X1451253Y1066974D03*
X1449404Y1070178D03*
X1460504D03*
X1458654Y1066974D03*
X1454953Y1073383D03*
X1458653Y1079791D03*
X1454954D03*
X1451253D03*
X1445703Y1089404D03*
X1458654Y1086200D03*
X1456804Y1082995D03*
X1453104Y1089404D03*
X1449404Y1082995D03*
X1460504Y1089404D03*
X1445704Y1095813D03*
X1460504D03*
X1456803D03*
X1445704Y1102221D03*
X1458653Y1105426D03*
X1456804Y1108630D03*
X1454953Y1099017D03*
X1449404Y1108630D03*
X1453104Y1102221D03*
X1451254Y1099017D03*
X1447553D03*
X1458653Y1111834D03*
X1460504Y1108630D03*
X1451253Y1111834D03*
X1447553D03*
X1454953Y1105426D03*
X1445704Y1108630D03*
X1449404Y1102221D03*
X1458653Y1099017D03*
X1454953Y1111834D03*
X1453104Y1108630D03*
X1447553Y1105426D03*
X1451253D03*
X1460504Y1102221D03*
X1458653Y1118243D03*
X1456803Y1115039D03*
X1454953Y1118243D03*
X1453103Y1115039D03*
X1451253Y1118243D03*
X1460503Y1127856D03*
X1453103D03*
X1460504Y1115039D03*
X1449404D03*
X1458653Y1131060D03*
X1454953D03*
X1453103Y1140973D03*
X1451253Y1131060D03*
X1449403Y1134264D03*
X1460503Y1140973D03*
X1469321Y841467D03*
X1461921D03*
X1476721D03*
X1474871Y851380D03*
X1471171D03*
X1467471D03*
X1463771D03*
X1461921Y854584D03*
X1474871Y864197D03*
X1471171D03*
X1469321Y854584D03*
X1467471Y864197D03*
X1463771D03*
X1476721Y854584D03*
X1461921Y867401D03*
X1476721D03*
X1469321D03*
X1461921Y880219D03*
X1471171Y877014D03*
X1476721Y880219D03*
X1474871Y877014D03*
X1469321Y880219D03*
X1467471Y877014D03*
X1463771D03*
X1474871Y889832D03*
X1465621Y893036D03*
X1476721D03*
X1474871Y896240D03*
X1471171Y889832D03*
X1467471D03*
X1463771D03*
X1473021Y899445D03*
X1465620D03*
X1461920Y905853D03*
X1473020Y912262D03*
X1471171Y909057D03*
X1465620Y905853D03*
X1471171Y902649D03*
X1469321Y905853D03*
X1474870Y915466D03*
X1461920Y925079D03*
X1471170Y928283D03*
X1469321Y925079D03*
X1465620D03*
Y918670D03*
X1473021D03*
X1471171Y921875D03*
X1473020Y931488D03*
X1465620D03*
X1461920Y944304D03*
X1474871Y934691D03*
X1473021Y937896D03*
X1471171Y941100D03*
X1469321Y944304D03*
X1465620D03*
Y937896D03*
X1471170Y947509D03*
X1474871Y953917D03*
X1473021Y957122D03*
X1471171Y960326D03*
X1465620Y957122D03*
Y950713D03*
X1473020D03*
X1461920Y963530D03*
X1476721D03*
X1471170Y966735D03*
X1469321Y963530D03*
X1465620D03*
X1473021Y976347D03*
X1473020Y969939D03*
X1465620Y976347D03*
Y969939D03*
X1474870Y973143D03*
X1471171Y979552D03*
X1461920Y982756D03*
X1469321D03*
X1465620D03*
X1475303Y1006093D03*
X1473453Y1009297D03*
X1473454Y1002888D03*
X1471604Y999684D03*
X1466053Y1009297D03*
X1466054Y1002888D03*
X1467903Y1006093D03*
X1464204D03*
X1471603Y1012501D03*
X1462353Y1015705D03*
X1473453Y1028523D03*
X1466053D03*
Y1022114D03*
Y1015705D03*
X1477154D03*
X1475303Y1025318D03*
X1473453Y1022114D03*
X1471604Y1018910D03*
X1469754Y1015705D03*
X1471603Y1031727D03*
X1462353Y1034931D03*
X1473454Y1041340D03*
X1466053D03*
Y1034931D03*
X1475303Y1044544D03*
X1471604Y1038136D03*
X1469754Y1034931D03*
X1466053Y1047749D03*
X1473453D03*
X1462353Y1054157D03*
X1473453Y1060565D03*
X1471604Y1057361D03*
X1466053Y1060565D03*
Y1054157D03*
X1471603Y1050952D03*
X1469753Y1054157D03*
X1475304Y1063770D03*
X1462353Y1073383D03*
X1471604Y1076587D03*
X1469754Y1073383D03*
X1466053Y1066974D03*
X1473453D03*
X1471603Y1070178D03*
X1466053Y1073383D03*
X1473454Y1079791D03*
X1466053D03*
X1462353Y1092608D03*
X1475303Y1082995D03*
X1473453Y1086200D03*
X1469754Y1092608D03*
X1466053D03*
Y1086200D03*
X1471603Y1089404D03*
X1475304Y1095813D03*
X1471604D03*
X1467904D03*
X1462353Y1105426D03*
X1462354Y1099017D03*
X1475303Y1108630D03*
Y1102221D03*
X1473454Y1105426D03*
X1469753D03*
X1467904Y1102221D03*
X1464203D03*
X1473454Y1111834D03*
X1466053D03*
Y1099017D03*
X1471604Y1102221D03*
X1477153Y1099017D03*
X1469753D03*
X1473453D03*
X1466053Y1105426D03*
X1462353Y1111834D03*
X1467904Y1108630D03*
X1464204D03*
X1462353Y1118243D03*
X1477153D03*
X1475303Y1115039D03*
X1473453Y1118243D03*
X1471604Y1121447D03*
X1469754Y1118243D03*
X1466053D03*
X1475303Y1127856D03*
X1467903D03*
X1467904Y1115039D03*
X1471604D03*
X1462353Y1131060D03*
X1477153D03*
X1475303Y1140973D03*
X1473453Y1131060D03*
X1469753D03*
X1466053D03*
X1467903Y1140973D03*
X1491521Y841467D03*
X1484121D03*
X1478571Y851380D03*
X1482271D03*
X1489671D03*
X1485971D03*
X1493371D03*
X1478571Y864197D03*
X1491521Y854584D03*
X1489671Y864197D03*
X1485971D03*
X1482271D03*
X1493371D03*
X1491521Y867401D03*
X1484121D03*
Y854584D03*
X1478571Y877014D03*
X1491521Y880219D03*
X1485971Y877014D03*
X1484121Y880219D03*
X1489671Y877014D03*
X1482271D03*
X1493371D03*
X1478570Y896240D03*
X1478571Y889832D03*
X1491521Y893036D03*
X1482271Y889832D03*
X1489671D03*
X1485971D03*
X1482270Y896240D03*
X1480421Y893036D03*
X1493371Y889832D03*
X1491520Y899445D03*
X1484120D03*
X1478571Y909057D03*
Y902649D03*
X1491520Y912262D03*
X1487820Y905853D03*
X1485971Y909057D03*
X1484121Y912262D03*
X1491520Y905853D03*
X1485970Y902649D03*
X1478571Y915466D03*
X1482271D03*
X1478571Y928283D03*
Y921875D03*
X1491520Y925079D03*
Y918670D03*
X1487820Y925079D03*
X1485971Y928283D03*
X1485970Y921875D03*
X1484120Y918670D03*
X1491520Y931488D03*
X1484121D03*
X1478571Y941100D03*
Y934691D03*
X1491520Y944304D03*
Y937896D03*
X1487820Y944304D03*
X1485970Y941100D03*
X1482271Y934691D03*
X1478571Y947509D03*
Y960326D03*
Y953917D03*
X1491520Y957122D03*
Y950713D03*
X1485970Y960326D03*
X1484120Y957122D03*
X1482271Y953917D03*
X1484121Y950713D03*
X1478570Y966735D03*
X1491520Y963530D03*
X1485971Y966735D03*
X1487820Y963530D03*
X1480420D03*
X1478571Y979552D03*
Y973143D03*
X1491521Y976347D03*
X1491520Y969939D03*
X1484120Y976347D03*
X1484121Y969939D03*
X1489671Y973143D03*
X1485970Y979552D03*
X1482271Y973143D03*
X1493370D03*
X1491520Y982756D03*
X1487820D03*
X1479004Y999684D03*
X1486403D03*
X1484553Y1002888D03*
X1482704Y1006093D03*
X1479003Y1012501D03*
X1486404D03*
X1491953Y1009297D03*
Y1002888D03*
X1484554Y1009297D03*
X1479004Y1025318D03*
Y1018910D03*
X1491953Y1028523D03*
Y1022114D03*
X1484553Y1028523D03*
X1486403Y1018910D03*
X1484553Y1022114D03*
X1482704Y1025318D03*
X1480853Y1015705D03*
X1479004Y1031727D03*
X1486404D03*
X1488253Y1015705D03*
X1491953D03*
X1479004Y1044544D03*
Y1038136D03*
X1491953Y1034931D03*
Y1041340D03*
X1488253Y1034931D03*
X1486403Y1038136D03*
X1484553Y1041340D03*
X1482704Y1044544D03*
X1491953Y1047749D03*
X1484553D03*
X1479004Y1057361D03*
Y1050952D03*
X1491953Y1054157D03*
X1486404Y1057361D03*
X1484553Y1060565D03*
X1488253Y1054157D03*
X1486404Y1050952D03*
X1491953Y1060565D03*
X1479004Y1063770D03*
X1482704D03*
X1479004Y1076587D03*
Y1070178D03*
X1486404Y1076587D03*
Y1070178D03*
X1488253Y1073383D03*
X1484553Y1066974D03*
X1491953Y1073383D03*
Y1066974D03*
X1484553Y1079791D03*
X1491953D03*
X1479004Y1089404D03*
Y1082995D03*
X1488254Y1092608D03*
X1486404Y1089404D03*
X1484554Y1086200D03*
X1482704Y1082995D03*
X1491954Y1092608D03*
X1479004Y1095813D03*
X1490103D03*
X1493804D03*
X1479004Y1102221D03*
X1490104Y1108630D03*
Y1102221D03*
X1488254Y1099017D03*
X1484553D03*
X1482704Y1108630D03*
X1480853Y1099017D03*
X1491953Y1105426D03*
Y1111834D03*
X1493804Y1108630D03*
X1490103Y1115039D03*
X1488253Y1118243D03*
X1484553D03*
X1480853D03*
X1486403Y1115039D03*
X1491953Y1118243D03*
X1490103Y1127856D03*
X1482703D03*
X1493804Y1115039D03*
X1490103Y1140973D03*
X1488253Y1131060D03*
X1484553D03*
X1480853D03*
X1482703Y1140973D03*
X1491953Y1131060D03*
X1504471Y844671D03*
X1498921Y841467D03*
X1508171Y851380D03*
X1504471D03*
X1500771D03*
X1497071D03*
X1504471Y864197D03*
X1500771D03*
X1508170Y857789D03*
X1497071Y864197D03*
X1506321Y860993D03*
Y854584D03*
X1498921D03*
X1510021Y860993D03*
X1506320Y867401D03*
X1498921D03*
X1510021D03*
X1504471Y877014D03*
X1498921Y880219D03*
X1508171Y877014D03*
X1497071D03*
X1506321Y880219D03*
X1500771Y877014D03*
X1510021Y880219D03*
Y873810D03*
X1508170Y883423D03*
X1508171Y889832D03*
X1504471Y896240D03*
Y889832D03*
X1500771D03*
X1508171Y896240D03*
X1502621Y893036D03*
X1500771Y896240D03*
X1497071Y889832D03*
X1510021Y893036D03*
X1498921Y899445D03*
X1510021D03*
X1495221Y905853D03*
X1504471Y902649D03*
X1498920Y912262D03*
X1497070Y909057D03*
X1497071Y902649D03*
X1508171Y915466D03*
X1504471D03*
X1500770D03*
X1504471Y909057D03*
X1510021Y912262D03*
X1495221Y925079D03*
X1504471Y921875D03*
X1497070Y928283D03*
X1498921Y918670D03*
X1497071Y921875D03*
X1498920Y931488D03*
X1504471Y928283D03*
X1510021Y918670D03*
X1510020Y931488D03*
X1495221Y944304D03*
X1504471Y941100D03*
Y934691D03*
X1500770D03*
X1498921Y937896D03*
X1497071Y941100D03*
X1497070Y947509D03*
X1508171Y934691D03*
X1510021Y937896D03*
X1504471Y947509D03*
Y960326D03*
Y953917D03*
X1500771D03*
X1498921Y957122D03*
X1497071Y960326D03*
X1498920Y950713D03*
X1495221Y963530D03*
X1497070Y966735D03*
X1502621Y963530D03*
X1510021Y957122D03*
X1508171Y953917D03*
X1510021Y950713D03*
X1506320Y963530D03*
X1504471Y966735D03*
Y979552D03*
Y973143D03*
X1498921Y976347D03*
X1498920Y969939D03*
X1500770Y973143D03*
X1497071Y979552D03*
X1510021Y976347D03*
X1495221Y982756D03*
X1510043Y980606D03*
X1510021Y969939D03*
X1508171Y973143D03*
X1497503Y1012501D03*
Y999684D03*
X1504904Y1006093D03*
Y999684D03*
X1501203Y1006093D03*
X1499353Y1009297D03*
X1499354Y1002888D03*
X1510453Y1009297D03*
Y1002888D03*
X1508603Y1006093D03*
X1504903Y1012501D03*
X1504904Y1025318D03*
X1499353Y1028523D03*
X1501203Y1025318D03*
X1504904Y1031727D03*
X1497503D03*
X1495654Y1015705D03*
X1497504Y1018910D03*
X1499353Y1022114D03*
X1503054Y1015705D03*
X1504904Y1018910D03*
X1506753Y1015705D03*
X1510453Y1028523D03*
X1510452Y1022114D03*
X1508603Y1025318D03*
X1504904Y1044544D03*
X1501203D03*
X1499354Y1041340D03*
X1497504Y1038136D03*
X1495654Y1034931D03*
X1508604Y1044544D03*
X1499353Y1047749D03*
X1504904Y1038136D03*
X1510453Y1041340D03*
Y1047749D03*
X1504904Y1057361D03*
Y1050952D03*
X1499354Y1060565D03*
X1497504Y1057361D03*
X1497503Y1050952D03*
X1495654Y1054157D03*
X1504904Y1063770D03*
X1501203D03*
X1510453Y1060565D03*
X1508604Y1063770D03*
X1504904Y1076587D03*
Y1070178D03*
X1497504Y1076587D03*
X1497503Y1070178D03*
X1495654Y1073383D03*
X1499353Y1066974D03*
X1499354Y1079791D03*
X1510453Y1066974D03*
Y1079791D03*
X1499353Y1086200D03*
X1497503Y1089404D03*
X1495653Y1092608D03*
X1504904Y1089404D03*
Y1082995D03*
X1501203D03*
X1508604Y1082996D03*
X1510453Y1086200D03*
X1504903Y1095813D03*
X1503053Y1105426D03*
X1497503Y1102221D03*
X1495653Y1105426D03*
X1495654Y1099017D03*
X1508603Y1108630D03*
X1506754Y1111834D03*
X1499353D03*
X1503053Y1099017D03*
X1510453D03*
X1508602Y1102221D03*
X1497504Y1108630D03*
X1501204D03*
X1510453Y1111834D03*
X1499353Y1105426D03*
X1510453D03*
X1504904Y1108630D03*
X1495653Y1111834D03*
X1503053D03*
X1506753Y1124651D03*
Y1118243D03*
X1504904Y1121447D03*
X1499353Y1118243D03*
X1497503Y1115039D03*
X1495653Y1118243D03*
X1508603Y1115039D03*
X1504904Y1127856D03*
X1497503D03*
X1501204Y1115039D03*
X1504904D03*
X1506754Y1137469D03*
X1506753Y1131060D03*
X1503053D03*
X1499353D03*
X1495653D03*
X1504904Y1134264D03*
X1497503Y1140973D03*
X1510453Y1131060D03*
X1511871Y844671D03*
X1513722Y848176D03*
X1511871Y851380D03*
X1521121Y860993D03*
Y854584D03*
X1515570Y864197D03*
X1513721Y854584D03*
Y860993D03*
X1521121Y867401D03*
X1517421D03*
X1513721D03*
X1511871Y870606D03*
X1522971D03*
X1517421Y873810D03*
X1511871Y883423D03*
X1517421Y880219D03*
X1522971Y883423D03*
X1511871Y889832D03*
X1513721Y893036D03*
X1517421Y886627D03*
X1521121D03*
X1513721D03*
X1526671Y889832D03*
X1513721Y899445D03*
X1524821Y912262D03*
X1511871Y909057D03*
Y902649D03*
X1513721Y912262D03*
X1515571Y909057D03*
X1524821Y905853D03*
X1513721D03*
X1519271Y909057D03*
X1511871Y921875D03*
X1513721Y918670D03*
X1524820Y931488D03*
X1513720D03*
X1511871Y941100D03*
X1513721Y937896D03*
X1511871Y947509D03*
X1519271D03*
X1515571D03*
X1511871Y960326D03*
X1513721Y957122D03*
Y950713D03*
X1511871Y966735D03*
X1513721Y963530D03*
X1515571Y979552D03*
X1513721Y982756D03*
X1511871Y973143D03*
X1517421Y969939D03*
X1515571Y973143D03*
X1516004Y1006092D03*
X1516003Y999684D03*
X1512303D03*
Y1006093D03*
X1519705Y1006092D03*
X1525396Y1000648D03*
X1512303Y1012501D03*
Y1025318D03*
X1516003Y1018910D03*
X1517854Y1015705D03*
X1525254D03*
X1521554D03*
X1514154D03*
X1512303Y1018910D03*
Y1031727D03*
X1525254Y1034931D03*
X1521554D03*
X1516004Y1044544D03*
X1516003Y1038136D03*
X1517853Y1034931D03*
X1514153D03*
X1512303Y1038136D03*
X1517853Y1054157D03*
X1514153D03*
X1512303Y1057361D03*
X1521553Y1054157D03*
X1514153Y1060565D03*
X1512303Y1050952D03*
X1525564Y1064850D03*
X1523404Y1070178D03*
X1514153Y1066974D03*
X1517853Y1073383D03*
X1521553Y1066974D03*
X1516003Y1076587D03*
X1512303D03*
X1512304Y1070178D03*
X1514153Y1073383D03*
X1523404Y1082996D03*
X1512304D03*
X1514153Y1092608D03*
X1512303Y1089404D03*
X1521553Y1092608D03*
X1523403Y1095813D03*
X1519703D03*
X1512303D03*
X1521554Y1105426D03*
X1517853D03*
X1516003Y1108630D03*
Y1102221D03*
X1512303D03*
X1517853Y1111834D03*
X1521553D03*
X1514153Y1105426D03*
X1512303Y1108630D03*
X1514153Y1111834D03*
X1519703Y1108630D03*
X1521553Y1124651D03*
Y1118243D03*
X1519704Y1115039D03*
X1516004D03*
X1514153Y1124651D03*
X1512303Y1115039D03*
X1517854Y1131560D03*
X1512304Y1134264D03*
X1527571Y979057D03*
X1526843Y972608D03*
X1527103Y1031726D03*
X1665141Y1051247D03*
X1724541D03*
G54D44*
X333834Y1062790D03*
X329632Y1092168D03*
X335344Y1097289D03*
X549719Y962436D03*
X548146Y965640D03*
X543729Y984866D03*
X1309976Y1062790D03*
X1305774Y1092168D03*
X1311486Y1097289D03*
X1337102Y206675D03*
X1525861Y962436D03*
X1524288Y965640D03*
X1519871Y984866D03*
X1879155Y468898D03*
Y716798D03*
X1889155Y468898D03*
Y716798D03*
X1900275Y840758D03*
X1910275D03*
X1921395Y-19332D03*
X1931395D03*
X1942395Y593048D03*
X1952395D03*
X1963362Y-19190D03*
X1973362D03*
X1984482Y593020D03*
X1994482D03*
X2005452Y-19180D03*
X2015452D03*
X2026452Y593200D03*
X2047419Y-19038D03*
X2036452Y593200D03*
X2057419Y-19038D03*
X2068539Y593172D03*
X2078539D03*
G54D53*
X717313Y-27626D03*
Y-21471D03*
Y-17597D03*
X717298Y-15082D03*
X717313Y-11442D03*
X717298Y-25111D03*
X717313Y-7568D03*
X717298Y-5053D03*
X834273Y2374D03*
X834258Y4889D03*
X834273Y22432D03*
Y8529D03*
Y12403D03*
X834258Y14918D03*
X834273Y18558D03*
X834258Y24947D03*
X1026705Y-27695D03*
Y-38224D03*
X1023437Y-38210D03*
X1026690Y-35709D03*
X1023422Y-35695D03*
X1026705Y-32069D03*
Y-17666D03*
X1026690Y-15151D03*
X1026705Y-11511D03*
X1026690Y-25180D03*
X1026705Y-21540D03*
X1026690Y4907D03*
X1026705Y2392D03*
X1026690Y-5122D03*
X1026705Y-7637D03*
Y-1482D03*
Y22450D03*
Y18576D03*
Y8547D03*
X1026690Y14936D03*
X1026705Y12421D03*
X1026690Y24965D03*
X1336024Y-27695D03*
Y-32069D03*
X1332741Y-35695D03*
X1336009Y-35709D03*
X1332756Y-38210D03*
X1336024Y-38224D03*
Y-11511D03*
X1336009Y-15151D03*
X1336024Y-17666D03*
Y-21540D03*
X1336009Y-25180D03*
X1336024Y2392D03*
X1336009Y4907D03*
X1336024Y-1482D03*
Y-7637D03*
X1336009Y-5122D03*
X1336024Y18576D03*
Y22450D03*
Y12421D03*
X1336009Y14936D03*
X1336024Y8547D03*
X1336009Y24965D03*
G54D63*
X918780Y1684890D03*
Y1694890D03*
Y1714890D03*
X928780Y1684890D03*
X938780D03*
X928780Y1694890D03*
X938780D03*
X928780Y1704890D03*
X938780D03*
X928780Y1714890D03*
X938780D03*
G54D73*
X1879155Y354948D03*
Y458898D03*
Y478898D03*
Y582848D03*
Y602848D03*
Y706798D03*
Y726798D03*
Y830748D03*
X1900275Y-9342D03*
X1889155Y354948D03*
Y458898D03*
Y478898D03*
X1900275Y582858D03*
X1889155Y582848D03*
Y602848D03*
Y706798D03*
X1900275Y726808D03*
X1889155Y726798D03*
X1900275Y830758D03*
X1889155Y830748D03*
X1900275Y850758D03*
Y954708D03*
X1910275Y-9342D03*
Y582858D03*
Y726808D03*
Y830758D03*
Y850758D03*
Y954708D03*
X1921395Y-9332D03*
X1931395D03*
Y582868D03*
X1921395D03*
X1931395Y602868D03*
X1921395D03*
Y1195068D03*
X1931395D03*
X1942395Y-9152D03*
Y583048D03*
Y603048D03*
Y1195248D03*
X1963362Y-9190D03*
X1952395Y-9152D03*
X1963362Y583010D03*
X1952395Y583048D03*
X1963362Y603010D03*
X1952395Y603048D03*
X1963362Y1195210D03*
X1952395Y1195248D03*
X1973362Y-9190D03*
Y583010D03*
Y603010D03*
Y1195210D03*
X1994482Y-9180D03*
X1984482D03*
Y583020D03*
X1994482D03*
X1984482Y603020D03*
X1994482D03*
Y1195220D03*
X1984482D03*
X2005452Y-9180D03*
X2015452D03*
Y583020D03*
X2005452D03*
X2015452Y603020D03*
X2005452D03*
Y1195220D03*
X2015452D03*
X2026452Y-9000D03*
Y583200D03*
Y603200D03*
Y1195400D03*
X2047419Y-9038D03*
X2036452Y-9000D03*
X2047419Y583162D03*
X2036452Y583200D03*
X2047419Y603162D03*
X2036452Y603200D03*
X2047419Y1195362D03*
X2036452Y1195400D03*
X2057419Y-9038D03*
Y583162D03*
Y603162D03*
Y1195362D03*
X2068539Y603172D03*
X2078539D03*
Y1195372D03*
X2068539D03*
G54D74*
X1879155Y468898D03*
Y716798D03*
X1889155Y468898D03*
X1900275Y592858D03*
X1889155Y716798D03*
X1900275Y840758D03*
X1910275Y592858D03*
Y840758D03*
X1921395Y1205068D03*
X1931395D03*
X1942395Y593048D03*
X1952395D03*
X1963362Y1205210D03*
X1984482Y593020D03*
X1973362Y1205210D03*
X1994482Y593020D03*
X2005452Y1205220D03*
X2015452D03*
X2026452Y593200D03*
X2036452D03*
X2047419Y1205362D03*
X2057419D03*
G54D50*
X676508Y224606D03*
G54D24*
X36399Y960892D03*
Y957546D03*
Y967585D03*
Y1054593D03*
X52541Y964239D03*
Y1021129D03*
Y1024475D03*
Y1051247D03*
X66099Y780184D03*
Y773491D03*
Y786877D03*
Y803609D03*
Y796916D03*
Y790223D03*
Y816995D03*
Y810302D03*
Y833727D03*
Y823688D03*
Y827034D03*
Y847113D03*
Y840420D03*
Y853806D03*
Y860499D03*
Y863845D03*
Y883924D03*
Y877231D03*
Y870538D03*
Y890617D03*
Y897310D03*
Y900656D03*
Y914042D03*
Y907349D03*
Y927428D03*
Y920735D03*
Y934121D03*
Y944160D03*
Y937467D03*
Y960892D03*
Y950853D03*
Y957546D03*
Y980971D03*
Y974278D03*
Y967585D03*
Y994357D03*
Y987664D03*
Y1027822D03*
Y1021129D03*
Y1047900D03*
Y1041207D03*
Y1034515D03*
Y1054593D03*
Y1074672D03*
Y1067979D03*
Y1091404D03*
Y1081365D03*
Y1084711D03*
Y1098097D03*
Y1111483D03*
Y1104790D03*
Y1128215D03*
Y1118176D03*
Y1121522D03*
Y1141601D03*
Y1134908D03*
Y1148294D03*
Y1154987D03*
Y1158333D03*
Y1171719D03*
Y1165026D03*
Y1185105D03*
Y1178412D03*
Y1191798D03*
Y1208530D03*
Y1201837D03*
Y1195144D03*
Y1221916D03*
Y1215223D03*
Y1238648D03*
Y1228609D03*
Y1231955D03*
Y1245341D03*
X82241Y770144D03*
Y776837D03*
Y786877D03*
Y783530D03*
Y800263D03*
Y793570D03*
Y813648D03*
Y806955D03*
Y820341D03*
Y830381D03*
Y823688D03*
Y850459D03*
Y843766D03*
Y837074D03*
Y867192D03*
Y860499D03*
Y857152D03*
Y873885D03*
Y880577D03*
Y887270D03*
Y897310D03*
Y893963D03*
Y917389D03*
Y910696D03*
Y904003D03*
Y924081D03*
Y934121D03*
Y930774D03*
Y947507D03*
Y940814D03*
Y964239D03*
Y977625D03*
Y970932D03*
Y991011D03*
Y984318D03*
Y1021129D03*
Y1024475D03*
Y1031168D03*
Y1044554D03*
Y1037861D03*
Y1051247D03*
Y1071326D03*
Y1064633D03*
Y1078018D03*
Y1094751D03*
Y1088058D03*
Y1081365D03*
Y1108137D03*
Y1101444D03*
Y1124869D03*
Y1118176D03*
Y1114829D03*
Y1144948D03*
Y1138255D03*
Y1131562D03*
Y1161680D03*
Y1154987D03*
Y1151641D03*
Y1175066D03*
Y1168373D03*
Y1181759D03*
Y1191798D03*
Y1188452D03*
Y1205184D03*
Y1198491D03*
Y1218570D03*
Y1211877D03*
Y1225263D03*
Y1241995D03*
Y1235302D03*
Y1228609D03*
X95799Y960892D03*
Y957546D03*
Y967585D03*
Y1054593D03*
X125499Y780184D03*
Y773491D03*
Y786877D03*
Y803609D03*
Y796916D03*
Y790223D03*
Y816995D03*
Y810302D03*
Y833727D03*
Y823688D03*
Y827034D03*
Y847113D03*
Y840420D03*
Y853806D03*
Y860499D03*
Y863845D03*
Y883924D03*
Y877231D03*
Y870538D03*
Y890617D03*
Y897310D03*
Y900656D03*
Y914042D03*
Y907349D03*
Y927428D03*
Y920735D03*
Y934121D03*
Y944160D03*
Y937467D03*
Y960892D03*
Y950853D03*
X111941Y964239D03*
X125499Y957546D03*
Y980971D03*
Y974278D03*
Y967585D03*
Y994357D03*
Y987664D03*
X111941Y1021129D03*
Y1024475D03*
X125499Y1027822D03*
Y1021129D03*
Y1047900D03*
Y1041207D03*
Y1034515D03*
X111941Y1051247D03*
X125499Y1054593D03*
Y1074672D03*
Y1067979D03*
Y1091404D03*
Y1081365D03*
Y1084711D03*
Y1098097D03*
Y1111483D03*
Y1104790D03*
Y1128215D03*
Y1118176D03*
Y1121522D03*
Y1141601D03*
Y1134908D03*
Y1148294D03*
Y1154987D03*
Y1158333D03*
Y1171719D03*
Y1165026D03*
Y1185105D03*
Y1178412D03*
Y1191798D03*
Y1208530D03*
Y1201837D03*
Y1195144D03*
Y1221916D03*
Y1215223D03*
Y1238648D03*
Y1228609D03*
Y1231955D03*
Y1245341D03*
X141641Y770144D03*
Y776837D03*
Y786877D03*
Y783530D03*
Y800263D03*
Y793570D03*
Y813648D03*
Y806955D03*
Y820341D03*
Y830381D03*
Y823688D03*
Y850459D03*
Y843766D03*
Y837074D03*
Y867192D03*
Y860499D03*
Y857152D03*
Y873885D03*
Y880577D03*
Y887270D03*
Y897310D03*
Y893963D03*
Y917389D03*
Y910696D03*
Y904003D03*
Y924081D03*
Y934121D03*
Y930774D03*
Y947507D03*
Y940814D03*
Y964239D03*
Y977625D03*
Y970932D03*
Y991011D03*
Y984318D03*
Y1021129D03*
Y1024475D03*
Y1031168D03*
Y1044554D03*
Y1037861D03*
Y1051247D03*
Y1071326D03*
Y1064633D03*
Y1078018D03*
Y1094751D03*
Y1088058D03*
Y1081365D03*
Y1108137D03*
Y1101444D03*
Y1124869D03*
Y1118176D03*
Y1114829D03*
Y1144948D03*
Y1138255D03*
Y1131562D03*
Y1161680D03*
Y1154987D03*
Y1151641D03*
Y1175066D03*
Y1168373D03*
Y1181759D03*
Y1191798D03*
Y1188452D03*
Y1205184D03*
Y1198491D03*
Y1218570D03*
Y1211877D03*
Y1225263D03*
Y1241995D03*
Y1235302D03*
Y1228609D03*
X155199Y960892D03*
Y957546D03*
Y967585D03*
Y1054593D03*
X171341Y964239D03*
Y1021129D03*
Y1024475D03*
Y1051247D03*
X184899Y780184D03*
Y773491D03*
Y786877D03*
Y803609D03*
Y796916D03*
Y790223D03*
Y816995D03*
Y810302D03*
Y833727D03*
Y823688D03*
Y827034D03*
Y847113D03*
Y840420D03*
Y853806D03*
Y860499D03*
Y863845D03*
Y883924D03*
Y877231D03*
Y870538D03*
Y890617D03*
Y897310D03*
Y900656D03*
Y914042D03*
Y907349D03*
Y927428D03*
Y920735D03*
Y934121D03*
Y944160D03*
Y937467D03*
Y960892D03*
Y950853D03*
Y957546D03*
Y980971D03*
Y974278D03*
Y967585D03*
Y994357D03*
Y987664D03*
Y1027822D03*
Y1021129D03*
Y1047900D03*
Y1041207D03*
Y1034515D03*
Y1054593D03*
Y1074672D03*
Y1067979D03*
Y1091404D03*
Y1081365D03*
Y1084711D03*
Y1098097D03*
Y1111483D03*
Y1104790D03*
Y1128215D03*
Y1118176D03*
Y1121522D03*
Y1141601D03*
Y1134908D03*
Y1148294D03*
Y1154987D03*
Y1158333D03*
Y1171719D03*
Y1165026D03*
Y1185105D03*
Y1178412D03*
Y1191798D03*
Y1208530D03*
Y1201837D03*
Y1195144D03*
Y1221916D03*
Y1215223D03*
Y1238648D03*
Y1228609D03*
Y1231955D03*
Y1245341D03*
X201041Y770144D03*
Y776837D03*
Y786877D03*
Y783530D03*
Y800263D03*
Y793570D03*
Y813648D03*
Y806955D03*
Y820341D03*
Y830381D03*
Y823688D03*
Y850459D03*
Y843766D03*
Y837074D03*
Y867192D03*
Y860499D03*
Y857152D03*
Y873885D03*
Y880577D03*
Y887270D03*
Y897310D03*
Y893963D03*
Y917389D03*
Y910696D03*
Y904003D03*
Y924081D03*
Y934121D03*
Y930774D03*
Y947507D03*
Y940814D03*
Y964239D03*
Y977625D03*
Y970932D03*
Y991011D03*
Y984318D03*
X201141Y1021129D03*
Y1024475D03*
Y1031168D03*
Y1044554D03*
Y1037861D03*
Y1051247D03*
Y1071326D03*
Y1064633D03*
Y1078018D03*
Y1094752D03*
Y1088059D03*
Y1081366D03*
Y1108137D03*
Y1101444D03*
X201041Y1124869D03*
X201141Y1118177D03*
Y1114830D03*
Y1144948D03*
Y1138255D03*
X201041Y1131562D03*
X201141Y1161680D03*
Y1154988D03*
Y1151641D03*
Y1175066D03*
Y1168373D03*
Y1181759D03*
Y1191799D03*
Y1188452D03*
Y1205184D03*
Y1198491D03*
Y1218570D03*
Y1211877D03*
Y1225263D03*
Y1241995D03*
Y1235302D03*
Y1228609D03*
X214599Y960892D03*
Y957546D03*
X244299Y883924D03*
Y890617D03*
Y897310D03*
Y900656D03*
Y914042D03*
Y907349D03*
Y960892D03*
Y957546D03*
Y1185105D03*
Y1178412D03*
Y1191798D03*
Y1208530D03*
Y1201837D03*
Y1195144D03*
X260441Y880577D03*
Y887270D03*
Y897310D03*
Y893963D03*
Y910696D03*
Y904003D03*
Y1175066D03*
Y1181759D03*
Y1191798D03*
Y1188452D03*
Y1205184D03*
Y1198491D03*
X337779Y880219D03*
X335928Y883423D03*
X337779Y893036D03*
X335928Y889832D03*
X334079Y886627D03*
X337779D03*
X336361Y1121447D03*
X350727Y851380D03*
X354427Y844971D03*
X348878Y848176D03*
X352578D03*
X350729Y857789D03*
X352578Y860993D03*
X354429Y857789D03*
X341479Y880219D03*
X343329Y883423D03*
X348878Y899445D03*
Y893036D03*
X350729Y889832D03*
X354429D03*
X341478Y893036D03*
X343328Y889832D03*
X347029Y896240D03*
X354429D03*
X341479Y886627D03*
X350729Y896240D03*
X345179Y886627D03*
X348878Y912262D03*
X350729Y909057D03*
X354429D03*
X350729Y902649D03*
X354429D03*
X347029Y915466D03*
X354429D03*
X350729D03*
X348879Y931488D03*
X350729Y928283D03*
X354429D03*
Y921875D03*
X350729D03*
X348878Y918670D03*
X350729Y941100D03*
X348878Y937896D03*
X354429Y941100D03*
X347029Y934691D03*
X354429D03*
X350729D03*
Y947509D03*
X354429D03*
X348878Y950713D03*
X350729Y960326D03*
X348878Y957122D03*
X354429Y960326D03*
X350729Y966735D03*
X354429D03*
X350729Y953917D03*
X354429D03*
X347030D03*
X350729Y979552D03*
X354429D03*
X348878Y976347D03*
X347029Y973143D03*
X348878Y969939D03*
X347461Y1006093D03*
X349311Y1002888D03*
X351161Y999684D03*
X354861D03*
X351161Y1012501D03*
X349311Y1009297D03*
X354861Y1012501D03*
X351162Y1031727D03*
X349311Y1028523D03*
X354861Y1031727D03*
X349311Y1022114D03*
X351161Y1018910D03*
X354861D03*
X347461Y1025318D03*
X354862D03*
X351162D03*
X349311Y1047749D03*
Y1041340D03*
X351161Y1038136D03*
X354861D03*
X347461Y1044544D03*
X354861D03*
X351161D03*
X349311Y1060565D03*
X351161Y1057361D03*
X354861D03*
X347461Y1063770D03*
X351161D03*
X354861D03*
X351161Y1050952D03*
X354861D03*
Y1070178D03*
X351162D03*
X349311Y1066974D03*
Y1079791D03*
X351161Y1076587D03*
X354861D03*
X351161Y1089404D03*
X349311Y1086200D03*
X354861Y1089404D03*
X347461Y1082995D03*
X354861D03*
X351161D03*
X341911Y1105426D03*
X343762Y1108630D03*
X345611Y1111834D03*
X351161Y1102221D03*
X349312Y1111834D03*
X353011Y1105426D03*
X345611D03*
X341912Y1111834D03*
X354861Y1102221D03*
X353012Y1111834D03*
X351162Y1108630D03*
X353011Y1124651D03*
X354861Y1127856D03*
X347461Y1115039D03*
X341912Y1118243D03*
X340061Y1127856D03*
X343761D03*
X347461Y1121447D03*
X340061D03*
X343761D03*
X347461Y1127856D03*
X345611Y1124651D03*
X349312Y1137469D03*
X351161Y1134264D03*
X341911Y1131060D03*
X356279Y841467D03*
X361827Y844971D03*
X363679Y841467D03*
X369227Y844971D03*
X371079Y841467D03*
X358127Y844971D03*
X359978Y848176D03*
X365527Y844971D03*
X367378Y848176D03*
X356278Y854584D03*
X358129Y857789D03*
X363678Y854584D03*
X365529Y857789D03*
X371078Y854584D03*
X359978Y860993D03*
X361829Y857789D03*
X367378Y860993D03*
X369229Y857789D03*
X356278Y899445D03*
Y893036D03*
X358129Y896240D03*
X363678Y899445D03*
X367378D03*
X371078Y893036D03*
X356278Y912262D03*
X358129Y915466D03*
X363678Y912262D03*
X361829Y909057D03*
X367378Y912262D03*
X369229Y909057D03*
X361829Y902649D03*
X369229D03*
X359978Y905853D03*
X367378D03*
X363678D03*
X371078D03*
X356278Y931488D03*
X363678D03*
X356278Y918670D03*
X361829Y928283D03*
X367378Y931488D03*
X369229Y928283D03*
X361829Y921875D03*
X363678Y918670D03*
X369229Y921875D03*
X367378Y918670D03*
X359978Y925079D03*
X367378D03*
X363678D03*
X371078D03*
X356278Y937896D03*
X358129Y934691D03*
X361829Y941100D03*
X363678Y937896D03*
X369229Y941100D03*
X367378Y937896D03*
X361829Y947509D03*
X369229D03*
X367378Y944304D03*
X359978D03*
X371078D03*
X363678D03*
X356278Y950713D03*
Y957122D03*
X358129Y953917D03*
X361829Y966735D03*
X369229D03*
X359978Y963530D03*
X363678Y950713D03*
X367378D03*
X361829Y960326D03*
X363678Y957122D03*
X369229Y960326D03*
X367378Y957122D03*
X371078Y963530D03*
X359978Y982756D03*
X367378D03*
X363678D03*
X371078D03*
X369229Y979552D03*
X367378Y976347D03*
X361829Y979552D03*
X363678Y976347D03*
X356278D03*
Y969939D03*
X358129Y973143D03*
X363678Y969939D03*
X367378D03*
X358562Y1006093D03*
X356711Y1002888D03*
Y1009297D03*
X362262Y1012501D03*
X369662D03*
X364111Y1009297D03*
X367811D03*
X364111Y1002888D03*
X362262Y999684D03*
X371511Y1002888D03*
X369662Y999684D03*
X356711Y1028523D03*
Y1022114D03*
X362262Y1031727D03*
X364111Y1028523D03*
X369662Y1031727D03*
X367811Y1028523D03*
X358562Y1025318D03*
X360411Y1015705D03*
X371511D03*
X364111Y1022114D03*
X362262Y1018910D03*
X367811Y1022114D03*
X369662Y1018910D03*
X356711Y1047749D03*
Y1041340D03*
X364111D03*
X362262Y1038136D03*
X367811Y1041340D03*
X369662Y1038136D03*
X360411Y1034931D03*
X371511D03*
X364111D03*
X358562Y1044544D03*
X367811Y1034931D03*
X364111Y1047749D03*
X367811D03*
X356711Y1060565D03*
X358562Y1063770D03*
X364111Y1060565D03*
X362262Y1057361D03*
X367811Y1060565D03*
X369662Y1057361D03*
X362262Y1050952D03*
X369662D03*
X360411Y1054157D03*
X371511D03*
X364111D03*
X367811D03*
X356711Y1066974D03*
X367811Y1079791D03*
X369662Y1076587D03*
X362262Y1070178D03*
X364111Y1066974D03*
X369662Y1070178D03*
X367811Y1066974D03*
X356711Y1079791D03*
X364111D03*
X362262Y1076587D03*
X360411Y1073383D03*
X371511D03*
X364111D03*
X367811D03*
X356711Y1086200D03*
X358562Y1082995D03*
X362262Y1095813D03*
X369662D03*
X362262Y1089404D03*
X364111Y1086200D03*
X369662Y1089404D03*
X367811Y1086200D03*
X360411Y1092608D03*
X367811D03*
X364111D03*
X371511D03*
X364111Y1099017D03*
X367811D03*
X358561Y1108630D03*
X360412Y1111834D03*
X364112Y1105426D03*
X369661Y1108630D03*
X362261D03*
X365961D03*
X367812Y1111834D03*
X358561Y1121447D03*
X360412Y1124651D03*
X364111D03*
X367811D03*
X371511D03*
X356712D03*
X362262Y1127856D03*
X365962Y1121447D03*
X369662Y1127856D03*
X365961Y1115039D03*
X358561D03*
X369661D03*
X358561Y1134264D03*
X362261Y1140973D03*
X365962Y1134264D03*
X369661Y1140973D03*
X356712Y1137469D03*
X360412D03*
X364112D03*
X367812D03*
X371512D03*
X387727Y844971D03*
X376627D03*
X380327D03*
X384027D03*
X385879Y841467D03*
X372927Y844971D03*
X374778Y848176D03*
X378479Y841467D03*
X382178Y848176D03*
X387729Y857789D03*
X372929D03*
X378478Y854584D03*
X380329Y857789D03*
X384029D03*
X374778Y860993D03*
X376629Y857789D03*
X382178Y860993D03*
X385878Y854584D03*
X374778Y899445D03*
X382178D03*
Y893036D03*
X374778D03*
X385878D03*
X372929Y896240D03*
X380329D03*
X376629D03*
X384029D03*
X376629Y902649D03*
X380329D03*
X374778Y912262D03*
X376629Y909057D03*
X382178Y912262D03*
X380329Y909057D03*
X387729D03*
Y902649D03*
X372929Y915466D03*
X385878Y905853D03*
X380329Y915466D03*
X376629D03*
X384029D03*
X374778Y931488D03*
X376629Y928283D03*
X382178Y931488D03*
X380329Y928283D03*
X387729Y921875D03*
X376629D03*
X374778Y918670D03*
X380329Y921875D03*
X382178Y918670D03*
X387729Y928283D03*
X385878Y925079D03*
X380329Y941100D03*
X382178Y937896D03*
X376629Y947509D03*
X380329D03*
X376629Y941100D03*
X374778Y937896D03*
X372929Y934691D03*
X380329D03*
X376629D03*
X384029D03*
X387729Y947509D03*
Y941100D03*
X385878Y944304D03*
X376629Y960326D03*
X374778Y957122D03*
X380329Y960326D03*
X382178Y957122D03*
X374778Y950713D03*
X382178D03*
X372929Y953917D03*
X380329D03*
X376629D03*
X384029D03*
X387729Y960326D03*
Y966735D03*
X380329D03*
X376629D03*
X385878Y963530D03*
Y982756D03*
X387729Y979552D03*
X376629D03*
X380329D03*
X374778Y976347D03*
X382178D03*
X372929Y973143D03*
X374778Y969939D03*
X382178D03*
X384029Y973143D03*
X373362Y1006093D03*
X380762D03*
X377062D03*
X384462D03*
X375211Y1002888D03*
X377062Y999684D03*
X382611Y1002888D03*
X380762Y999684D03*
X377062Y1012501D03*
X375211Y1009297D03*
X380762Y1012501D03*
X382611Y1009297D03*
X377062Y1031727D03*
X375211Y1028523D03*
X380762Y1031727D03*
X382611Y1028523D03*
X375211Y1022114D03*
X377062Y1018910D03*
X382611Y1022114D03*
X380762Y1018910D03*
X377062Y1025318D03*
X384462D03*
X373360D03*
X380760D03*
X386311Y1015705D03*
X375211Y1047749D03*
X382611D03*
X375211Y1041340D03*
X377062Y1038136D03*
X382611Y1041340D03*
X380762Y1038136D03*
X373362Y1044544D03*
X380762D03*
X377062D03*
X384462D03*
X386311Y1034931D03*
X375211Y1060565D03*
X377062Y1057361D03*
X382611Y1060565D03*
X380762Y1057361D03*
X377062Y1050952D03*
X380762D03*
X373362Y1063770D03*
X384462D03*
X377062D03*
X380762D03*
X386311Y1054157D03*
X380762Y1070178D03*
X382611Y1066974D03*
X377062Y1070178D03*
X375211Y1066974D03*
Y1079791D03*
X377062Y1076587D03*
X382611Y1079791D03*
X380762Y1076587D03*
X386311Y1073383D03*
X377062Y1089404D03*
X375211Y1086200D03*
X380762Y1089404D03*
X382611Y1086200D03*
X373362Y1082995D03*
X386311Y1092608D03*
X384462Y1082995D03*
X377062D03*
X380762D03*
X386311Y1105426D03*
X382611Y1111834D03*
X375211Y1105426D03*
X377062Y1108630D03*
X380762Y1102221D03*
X378911Y1111834D03*
X384462Y1108630D03*
X386311Y1111834D03*
X378912Y1105426D03*
X375211Y1111834D03*
X382611Y1105426D03*
X375211Y1124651D03*
X378911D03*
X382611D03*
X386311D03*
X373362Y1121447D03*
X377062Y1127856D03*
X380762Y1121447D03*
X384462Y1127856D03*
X380762Y1115039D03*
X373362Y1134264D03*
X377061Y1140973D03*
X380762Y1134264D03*
X384461Y1140973D03*
X375212Y1137469D03*
X378912D03*
X382612D03*
X386312D03*
X391427Y844971D03*
X395127D03*
X398827D03*
X400679Y841467D03*
X389578Y848176D03*
X393279Y841467D03*
X396978Y848176D03*
X402527Y844971D03*
X393278Y854584D03*
X395129Y857789D03*
X400678Y854584D03*
X402529Y857789D03*
X389578Y860993D03*
X391429Y857789D03*
X396978Y860993D03*
X398829Y857789D03*
X389578Y899445D03*
X393278D03*
X389578Y912262D03*
X393278D03*
X395129Y909057D03*
Y902649D03*
X393278Y905853D03*
X389578D03*
X396978D03*
X393278Y931488D03*
X395129Y928283D03*
X389578Y918670D03*
X395129Y921875D03*
X393278Y918670D03*
X389578Y931488D03*
X393278Y925079D03*
X389578D03*
X396978D03*
X395129Y947509D03*
X389578Y937896D03*
X395129Y941100D03*
X393278Y937896D03*
Y944304D03*
X389578D03*
X396978D03*
X389578Y957122D03*
X395129Y960326D03*
X393278Y957122D03*
X395129Y966735D03*
X389578Y950713D03*
X393278D03*
X396978Y963530D03*
X393278D03*
X389578D03*
X398829Y973143D03*
X400678Y976347D03*
X402529Y979552D03*
Y973143D03*
X393278Y982756D03*
X389578D03*
X396978D03*
X393278Y976347D03*
X395129Y979552D03*
X389579Y976347D03*
X389578Y969939D03*
X393278D03*
X390011Y1002888D03*
X388162Y999684D03*
X393711Y1002888D03*
X395562Y999684D03*
X388162Y1012501D03*
X395562D03*
X390011Y1009297D03*
X393711D03*
X397411Y1015705D03*
X388162Y1031727D03*
X390011Y1028523D03*
X395562Y1031727D03*
X393711Y1028523D03*
X390011Y1022114D03*
X388162Y1018910D03*
X393711Y1022114D03*
X395562Y1018910D03*
X390011Y1041340D03*
X388162Y1038136D03*
X393711Y1041340D03*
X395562Y1038136D03*
X390011Y1047749D03*
X393711D03*
Y1034931D03*
X390011D03*
X397411D03*
X390011Y1060565D03*
X388162Y1057361D03*
X393711Y1060565D03*
X395562Y1057361D03*
X388162Y1050952D03*
X395562D03*
X393711Y1054157D03*
X390011D03*
X397411D03*
X390011Y1079791D03*
X388162Y1076587D03*
X393711Y1079791D03*
X395562Y1076587D03*
X388162Y1070178D03*
X390011Y1066974D03*
X395562Y1070178D03*
X393711Y1066974D03*
Y1073383D03*
X390011D03*
X397411D03*
X395562Y1095813D03*
X388162Y1089404D03*
X390011Y1086200D03*
X395562Y1089404D03*
X393711Y1086200D03*
X388162Y1095813D03*
X393711Y1092608D03*
X390011D03*
X397411D03*
X402962Y1082995D03*
X402961Y1089404D03*
X393711Y1099017D03*
X390011D03*
X401111D03*
X391862Y1108630D03*
X393711Y1111834D03*
X397411Y1105426D03*
X402962Y1108630D03*
Y1102221D03*
X395562Y1108630D03*
X399262D03*
X401111Y1111834D03*
X390011Y1124651D03*
X395562Y1121447D03*
X397411Y1124651D03*
X401111D03*
X391862Y1127856D03*
X393711Y1124651D03*
X399262Y1127856D03*
X402962Y1121447D03*
X388162D03*
X399262Y1115039D03*
X391862D03*
X402962D03*
X391861Y1140973D03*
X395562Y1134264D03*
X399261Y1140973D03*
X402962Y1134264D03*
X388162D03*
X390012Y1137469D03*
X393712D03*
X397412D03*
X401112D03*
X406227Y844971D03*
X409927D03*
X413627D03*
X417327D03*
X404378Y848176D03*
X408079Y841467D03*
X411778Y848176D03*
X415479Y841467D03*
X419178Y848176D03*
X415478Y867401D03*
X408078Y854584D03*
X409929Y857789D03*
X415478Y854584D03*
X417329Y857789D03*
X404378Y860993D03*
X406229Y857789D03*
X411778Y860993D03*
X413629Y857789D03*
X419178Y860993D03*
Y873810D03*
X417329Y870606D03*
X411778Y873810D03*
X413629Y870606D03*
X417329Y883423D03*
X415478Y880219D03*
X413629Y883423D03*
X419178Y886627D03*
X408511Y1079791D03*
X406662Y1089404D03*
X410362D03*
X404811Y1086200D03*
X419611D03*
X414062Y1082995D03*
X410362D03*
X406662D03*
X408511Y1092608D03*
X414062Y1089404D03*
X419611Y1092608D03*
X412211Y1086200D03*
X404811Y1099017D03*
X408511Y1105426D03*
X412211Y1111834D03*
X415911D03*
X414062Y1102221D03*
X417762Y1108630D03*
X419611Y1105426D03*
X408511Y1099017D03*
X410362Y1108630D03*
X408511Y1111834D03*
X412211Y1105426D03*
X419611Y1111834D03*
X415911Y1105426D03*
X404811Y1124651D03*
X408511D03*
X406662Y1127856D03*
X410362Y1121447D03*
X414062Y1115039D03*
X406661Y1140973D03*
X410362Y1134264D03*
X404812Y1137469D03*
X408512D03*
X421027Y844971D03*
X424727D03*
X428427D03*
X433978Y848176D03*
X435829Y844671D03*
X422879Y841467D03*
X426578Y848176D03*
X430278D03*
Y867401D03*
X422878D03*
Y854584D03*
X424729Y857789D03*
X430278Y854584D03*
X433979Y860993D03*
X421029Y857789D03*
X426578Y860993D03*
X428429Y857789D03*
X432129D03*
X435829D03*
X432129Y870606D03*
X426578Y873810D03*
X424729Y870606D03*
X433979Y873810D03*
X428429Y870606D03*
X421029D03*
X435829D03*
X432129Y883423D03*
X430278Y880219D03*
X424729Y883423D03*
X422878Y880219D03*
X428429Y883423D03*
X421029D03*
X435829D03*
X433978Y886627D03*
X426578D03*
X428861Y1076587D03*
X430711Y1079791D03*
X421462Y1089404D03*
X423311Y1092608D03*
X427011D03*
X430710Y1086200D03*
X425162Y1082995D03*
Y1095813D03*
X430711Y1092608D03*
X423311Y1086200D03*
X428861Y1089404D03*
X427012Y1086200D03*
X450628Y844971D03*
X446927Y844671D03*
X452479Y841467D03*
X448778Y848176D03*
X443227Y844671D03*
X437678Y848176D03*
X452478Y867401D03*
X445078D03*
X437678D03*
X437679Y854584D03*
X452478D03*
X450629Y857789D03*
X445078Y854584D03*
X443229Y857789D03*
X448779Y860993D03*
X446929Y857789D03*
X441378Y860993D03*
X448779Y873810D03*
X446929Y870606D03*
X441378Y873810D03*
X439529Y870606D03*
X450629D03*
X443229D03*
X452479Y880219D03*
X446929Y883423D03*
X445078Y880219D03*
X439529Y883423D03*
X437678Y880219D03*
X450629Y883423D03*
X443229D03*
X448778Y886627D03*
X441378D03*
X467279Y841467D03*
X463578Y848176D03*
X459879Y841467D03*
X458027Y844971D03*
X454327D03*
X469127D03*
X465427D03*
X461727D03*
X456178Y848176D03*
X467278Y867401D03*
X459878D03*
X467278Y854584D03*
X465429Y857789D03*
X459878Y854584D03*
X458029Y857789D03*
X469129D03*
X463578Y860993D03*
X461729Y857789D03*
X456178Y860993D03*
X454329Y857789D03*
X469129Y870606D03*
X463578Y873810D03*
X461729Y870606D03*
X456178Y873810D03*
X454329Y870606D03*
X465429D03*
X458029D03*
X469129Y883423D03*
X467278Y880219D03*
X461729Y883423D03*
X459878Y880219D03*
X454329Y883423D03*
X465429D03*
X458029D03*
X463578Y886627D03*
X456178D03*
X483927Y844971D03*
X480227D03*
X476527D03*
X470978Y848176D03*
X482079Y841467D03*
X478378Y848176D03*
X474679Y841467D03*
X472827Y844971D03*
X482078Y854584D03*
X480229Y857789D03*
X474678Y854584D03*
X472829Y857789D03*
X483929D03*
X478378Y860993D03*
X476529Y857789D03*
X470978Y860993D03*
X482078Y893036D03*
X483929Y896240D03*
X470978Y886627D03*
X483929Y915466D03*
Y934691D03*
Y953917D03*
Y973143D03*
X484362Y1006093D03*
Y1025318D03*
Y1044544D03*
Y1063770D03*
Y1082995D03*
Y1121447D03*
X480662Y1127856D03*
X476962Y1121447D03*
X473262Y1127856D03*
X469562Y1121447D03*
X482511Y1124651D03*
X478811D03*
X475111D03*
X471411D03*
X484362Y1134264D03*
X482512Y1137469D03*
X476962Y1134264D03*
X475112Y1137469D03*
X480661Y1140973D03*
X478812Y1137469D03*
X473261Y1140973D03*
X493178Y848176D03*
X489478Y841467D03*
X487627Y844971D03*
X500578Y848176D03*
X496878Y841467D03*
X495027Y844971D03*
X491327D03*
X485778Y848176D03*
X498727Y844971D03*
X489478Y854584D03*
X487629Y857789D03*
X500578Y860993D03*
X498729Y857789D03*
X495029D03*
X491329D03*
X485778Y860993D03*
X496878Y854584D03*
X493178Y860993D03*
X500578Y899445D03*
X485778D03*
X493178D03*
Y893036D03*
X496878D03*
X485778D03*
X491329Y896240D03*
X487629D03*
X495029D03*
X485778Y912262D03*
X487629Y909057D03*
X493178Y912262D03*
X491329Y909057D03*
X500578Y912262D03*
X498729Y909057D03*
Y902649D03*
X487629D03*
X491329D03*
X487629Y915466D03*
X500578Y905853D03*
X495029Y915466D03*
X496878Y905853D03*
X491329Y915466D03*
X500578Y931488D03*
X498729Y921875D03*
X500578Y918670D03*
X498729Y928283D03*
X496878Y925079D03*
X500578D03*
X491329Y921875D03*
X493178Y918670D03*
X485778Y931488D03*
X491329Y928283D03*
X493178Y931488D03*
X487629Y928283D03*
Y921875D03*
X485778Y918670D03*
X498729Y947509D03*
Y941100D03*
X500578Y937896D03*
X496878Y944304D03*
X500578D03*
X487629Y947509D03*
X491329D03*
X487629Y941100D03*
X485778Y937896D03*
X491329Y941100D03*
X493178Y937896D03*
X487629Y934691D03*
X495029D03*
X491329D03*
X500578Y950713D03*
X487629Y966735D03*
X491329D03*
X498729D03*
X496878Y963530D03*
X485778Y950713D03*
X493178D03*
X491329Y960326D03*
X493178Y957122D03*
X487629Y960326D03*
X485778Y957122D03*
X500578D03*
X498729Y960326D03*
X495029Y953917D03*
X487629D03*
X491329D03*
X487629Y979552D03*
X485778Y976347D03*
X491329Y979552D03*
X493178Y976347D03*
X500578Y982756D03*
X496878D03*
X498729Y979552D03*
X500578Y976347D03*
X495029Y973143D03*
X487629D03*
X491329D03*
X485778Y969939D03*
X493178D03*
X500578D03*
X501011Y1002888D03*
X499162Y999684D03*
Y1012501D03*
X501011Y1009297D03*
X495462Y1006093D03*
X486211Y1002888D03*
X493611D03*
X488062Y999684D03*
X491762D03*
X491761Y1012501D03*
X493611Y1009297D03*
X488062Y1012501D03*
X486211Y1009297D03*
X497311Y1015705D03*
X499162Y1031727D03*
X501011Y1028523D03*
Y1022114D03*
X499162Y1018910D03*
X488062Y1031727D03*
X486211Y1028523D03*
X491762Y1031727D03*
X493611Y1028523D03*
X486211Y1022114D03*
X488062Y1018910D03*
X493611Y1022114D03*
X491762Y1018910D03*
X488062Y1025318D03*
X495462D03*
X491762D03*
X501011Y1041340D03*
X499162Y1038136D03*
X501011Y1047749D03*
Y1034931D03*
X497311D03*
X486211Y1047749D03*
X493611D03*
X486211Y1041340D03*
X488062Y1038136D03*
X493611Y1041340D03*
X491762Y1038136D03*
X488062Y1044544D03*
X495462D03*
X491762D03*
X501011Y1060565D03*
X499162Y1057361D03*
Y1050952D03*
X501011Y1054157D03*
X497311D03*
X486211Y1060565D03*
X488062Y1057361D03*
X493611Y1060565D03*
X491762Y1057361D03*
X488062Y1050952D03*
X491762D03*
X488062Y1063770D03*
X495462D03*
X491762D03*
X499162Y1070178D03*
X501011Y1066974D03*
Y1079791D03*
X499162Y1076587D03*
X497311Y1073383D03*
X501011D03*
X486211Y1079791D03*
X488062Y1076587D03*
X493611Y1079791D03*
X491762Y1076587D03*
X488062Y1070178D03*
X486211Y1066974D03*
X491762Y1070178D03*
X493611Y1066974D03*
X491762Y1089404D03*
X493611Y1086200D03*
X499162Y1089404D03*
X501011Y1086200D03*
X488062Y1089404D03*
X486211Y1086200D03*
X497311Y1092608D03*
X495462Y1082995D03*
X501011Y1092608D03*
X488062Y1082995D03*
X491762D03*
X488062Y1127856D03*
X499162Y1121447D03*
X495462Y1127856D03*
X491762Y1121447D03*
X489911Y1124651D03*
X486211D03*
X501011D03*
X497311D03*
X493611D03*
X493612Y1137469D03*
X488061Y1140973D03*
X501012Y1137469D03*
X495461Y1140973D03*
X491762Y1134264D03*
X489912Y1137469D03*
X486212D03*
X499162Y1134264D03*
X497312Y1137469D03*
X517227Y844971D03*
X511679Y841467D03*
X509827Y844971D03*
X504279Y841467D03*
X515378Y848176D03*
X513527Y844971D03*
X507978Y848176D03*
X506127Y844971D03*
X502427D03*
X517229Y857789D03*
X513529D03*
X509829D03*
X506129D03*
X515378Y860993D03*
X511678Y854584D03*
X507978Y860993D03*
X504278Y854584D03*
X502429Y857789D03*
X511678Y899445D03*
Y893036D03*
X507978D03*
X509829Y896240D03*
X517229D03*
X513529D03*
X504278Y899445D03*
X513529Y902649D03*
X517229D03*
X511678Y912262D03*
X513529Y909057D03*
X517229D03*
X513529Y915466D03*
X509829D03*
X517229D03*
X504278Y912262D03*
X506129Y909057D03*
Y902649D03*
X507978Y905853D03*
X504278D03*
X511678Y931488D03*
X513529Y928283D03*
X517229D03*
X506129D03*
Y921875D03*
X504278Y918670D03*
X513529Y921875D03*
X511678Y918670D03*
X517229Y921875D03*
X504278Y931488D03*
Y925079D03*
X507978D03*
X513529Y941100D03*
X511678Y937896D03*
X517229Y941100D03*
X513529Y934691D03*
X509829D03*
X517229D03*
X513529Y947509D03*
X517229D03*
X506129D03*
Y941100D03*
X504278Y937896D03*
X507978Y944304D03*
X504278D03*
X511678Y950713D03*
X513529Y960326D03*
X511678Y957122D03*
X517229Y960326D03*
Y966735D03*
X513529D03*
X504278Y950713D03*
X513529Y953917D03*
X517229D03*
X509829D03*
X506129Y966735D03*
X504278Y957122D03*
X506129Y960326D03*
X507978Y963530D03*
Y982756D03*
X504278D03*
Y976347D03*
X506129Y979552D03*
X513529D03*
X517229D03*
X511678Y976347D03*
X509829Y973143D03*
X511678Y969939D03*
X504278D03*
X517662Y1006093D03*
X513962D03*
X510262D03*
X517662Y1012501D03*
X504711Y1002888D03*
X506561Y999684D03*
X513962Y1012501D03*
X512111Y1009297D03*
X506562Y1012501D03*
X504711Y1009297D03*
X517661Y999684D03*
X512111Y1002888D03*
X513962Y999684D03*
Y1031727D03*
X512111Y1028523D03*
X517662Y1031727D03*
X512111Y1022114D03*
X513962Y1018910D03*
X517662D03*
X513962Y1025318D03*
X510262D03*
X517662D03*
X508411Y1015705D03*
X506562Y1031727D03*
X504711Y1028523D03*
Y1022114D03*
X506562Y1018910D03*
X504711Y1041340D03*
X506562Y1038136D03*
X512111Y1047749D03*
Y1041340D03*
X513962Y1038136D03*
X517662D03*
X504711Y1047749D03*
X510262Y1044544D03*
X508411Y1034931D03*
X513962Y1044544D03*
X517662D03*
X504711Y1034931D03*
X512111Y1060565D03*
X513962Y1057361D03*
X517662D03*
X510262Y1063770D03*
X513962D03*
X517662D03*
X513962Y1050952D03*
X517662D03*
X504711Y1060565D03*
X506562Y1057361D03*
Y1050952D03*
X508411Y1054157D03*
X504711D03*
X517662Y1070178D03*
X513962D03*
X512111Y1066974D03*
X504711Y1079791D03*
X506562Y1076587D03*
Y1070178D03*
X504711Y1066974D03*
X512111Y1079791D03*
X513962Y1076587D03*
X517662D03*
X508411Y1073383D03*
X504711D03*
X513962Y1089404D03*
X512111Y1086200D03*
X517662Y1089404D03*
X513962Y1082995D03*
X510262D03*
X517662D03*
X510262Y1095813D03*
X506561D03*
X506562Y1089404D03*
X504711Y1086200D03*
X508411Y1092608D03*
X504711D03*
X517662Y1102221D03*
X515811Y1099017D03*
X517662Y1127856D03*
X513962Y1121447D03*
X510262Y1127856D03*
X506562Y1121447D03*
X502862Y1127856D03*
X515811Y1124651D03*
X512111D03*
X508411D03*
X504711D03*
X517661Y1140973D03*
X513962Y1134264D03*
X512112Y1137469D03*
X506562Y1134264D03*
X504712Y1137469D03*
X515812D03*
X510261Y1140973D03*
X508412Y1137469D03*
X502861Y1140973D03*
X532028Y844671D03*
X526478Y848176D03*
X524627Y844971D03*
X519079Y841467D03*
X533878Y848176D03*
X530178D03*
X522778D03*
X520927Y844971D03*
X532029Y864197D03*
X533879Y854584D03*
X528329Y857789D03*
X522778Y860993D03*
X520929Y857789D03*
X526478Y854584D03*
X524629Y857789D03*
X519078Y854584D03*
X526479Y899445D03*
X530178D03*
X519078D03*
Y893036D03*
X522778D03*
X520929Y896240D03*
X530179Y912262D03*
X532029Y909057D03*
X524629Y902649D03*
X532029D03*
X526479Y912262D03*
X524629Y909057D03*
X526479Y905853D03*
X533879D03*
X522778D03*
X530179D03*
X519078Y912262D03*
X520929Y915466D03*
X526479Y931488D03*
X524629Y928283D03*
X530179Y931488D03*
X532029Y928283D03*
X524629Y921875D03*
X526479Y918670D03*
X532029Y921875D03*
X530179Y918670D03*
X526479Y925079D03*
X533879D03*
X522778D03*
X530179D03*
X519078Y931488D03*
Y918670D03*
X524629Y941100D03*
X526479Y937896D03*
X532029Y941100D03*
X530179Y937896D03*
X524629Y947509D03*
X532029D03*
X519078Y937896D03*
X533879Y944304D03*
X520929Y934691D03*
X526479Y944304D03*
X530178D03*
X522778D03*
X524629Y966735D03*
X532029D03*
X522778Y963530D03*
X526479Y950713D03*
X530178D03*
X532029Y960326D03*
X530178Y957122D03*
X524629Y960326D03*
X526479Y957122D03*
X533879Y963530D03*
X519078Y950713D03*
Y957122D03*
X520929Y953917D03*
X526479Y969939D03*
X530179D03*
X519078Y976347D03*
Y969939D03*
X520929Y973143D03*
X521362Y1006093D03*
X525062Y1012501D03*
X532461D03*
X526911Y1009297D03*
X530611D03*
X519511D03*
X519513Y1002888D03*
X530611D03*
X532461Y999684D03*
X526911Y1002888D03*
X525062Y999684D03*
X523211Y1015705D03*
X534311D03*
X525062Y1031727D03*
X526911Y1028523D03*
X532461Y1031727D03*
X530611Y1028523D03*
Y1022114D03*
X532461Y1018910D03*
X526911Y1022114D03*
X525062Y1018910D03*
X519511Y1028523D03*
Y1022114D03*
X521362Y1025318D03*
X526911Y1041340D03*
X525062Y1038136D03*
X530611Y1041340D03*
X532461Y1038136D03*
X526911Y1047749D03*
X530611D03*
X526911Y1034931D03*
X534311D03*
X523211D03*
X530611D03*
X519511Y1047749D03*
Y1041340D03*
X521362Y1044544D03*
X519511Y1060565D03*
X526911D03*
X525062Y1057361D03*
X530611Y1060565D03*
X532462Y1057361D03*
X525061Y1050952D03*
X532462Y1050953D03*
X523211Y1054157D03*
X521362Y1063770D03*
X534311Y1054157D03*
X526911D03*
X530611D03*
Y1079791D03*
X532462Y1076587D03*
X525062Y1070178D03*
X526911Y1066974D03*
X532462Y1070178D03*
X530611Y1066974D03*
X526911Y1079791D03*
X525062Y1076587D03*
X523211Y1073383D03*
X534311D03*
X526911D03*
X530611D03*
X519511Y1066974D03*
Y1079791D03*
X521362Y1095813D03*
X532461D03*
X525062D03*
Y1089404D03*
X526911Y1086200D03*
X532462Y1089404D03*
X530611Y1086200D03*
X526911Y1092608D03*
X534310D03*
X523211D03*
X530611D03*
X519511Y1086200D03*
X521362Y1082995D03*
X530611Y1099017D03*
X526911Y1124651D03*
X521362Y1121447D03*
X525062Y1127856D03*
X523211Y1124651D03*
X519511D03*
X532462Y1134264D03*
X525061Y1140973D03*
X523212Y1137469D03*
X534312D03*
X526912D03*
X521362Y1134264D03*
X519512Y1137469D03*
X543129Y851380D03*
X539429D03*
X535729Y864197D03*
X543128D03*
X546828D03*
X535729Y857789D03*
X543130D03*
X539429D03*
X541279Y860993D03*
Y854584D03*
X539429Y883423D03*
X537578Y880219D03*
X543129Y883423D03*
X544979Y880219D03*
X537578Y873810D03*
X539429Y870606D03*
X544979Y873810D03*
X543129Y870606D03*
X539428Y877014D03*
X546828D03*
X535729D03*
X543129D03*
X620799Y883924D03*
Y890617D03*
Y897310D03*
Y900656D03*
Y914042D03*
Y907349D03*
Y960892D03*
Y957546D03*
Y1185105D03*
Y1178412D03*
Y1191798D03*
Y1208530D03*
Y1201837D03*
Y1195144D03*
X636941Y880577D03*
Y887270D03*
Y897310D03*
Y893963D03*
Y910696D03*
Y904003D03*
Y1175066D03*
Y1181759D03*
Y1191798D03*
Y1188451D03*
Y1205184D03*
Y1198491D03*
X650499Y960892D03*
Y957546D03*
X680299Y780184D03*
Y773491D03*
Y786877D03*
Y803609D03*
Y796916D03*
Y790223D03*
Y816995D03*
Y810302D03*
Y833727D03*
Y823688D03*
Y827034D03*
Y847113D03*
Y840420D03*
Y853806D03*
Y860499D03*
Y863845D03*
Y883924D03*
Y877231D03*
Y870538D03*
Y890617D03*
Y897310D03*
Y900656D03*
Y914042D03*
Y907349D03*
Y927428D03*
Y920735D03*
Y934121D03*
Y944160D03*
Y937467D03*
Y960892D03*
Y950853D03*
Y957546D03*
Y980971D03*
Y974278D03*
Y967585D03*
Y994357D03*
Y987664D03*
X679999Y1027822D03*
X680299Y1021129D03*
X679999Y1047900D03*
Y1041207D03*
Y1034514D03*
Y1054593D03*
X680299Y1074672D03*
Y1067979D03*
Y1091404D03*
Y1081365D03*
Y1084711D03*
Y1098097D03*
Y1111483D03*
Y1104790D03*
Y1128215D03*
Y1118176D03*
Y1121522D03*
Y1141601D03*
Y1134908D03*
Y1148294D03*
Y1154987D03*
Y1158333D03*
Y1171719D03*
Y1165026D03*
Y1185105D03*
Y1178412D03*
Y1191798D03*
Y1208530D03*
Y1201837D03*
Y1195144D03*
Y1221916D03*
Y1215223D03*
Y1238648D03*
Y1228609D03*
Y1231955D03*
Y1245341D03*
X696441Y770144D03*
Y776837D03*
Y786877D03*
Y783530D03*
Y800263D03*
Y793570D03*
Y813648D03*
Y806955D03*
Y820341D03*
Y830381D03*
Y823688D03*
Y850459D03*
Y843766D03*
Y837074D03*
Y867192D03*
Y860499D03*
Y857152D03*
Y873885D03*
Y880577D03*
Y887270D03*
Y897310D03*
Y893963D03*
Y917389D03*
Y910696D03*
Y904003D03*
Y924081D03*
Y934121D03*
Y930774D03*
Y947507D03*
Y940814D03*
Y964239D03*
Y977625D03*
Y970932D03*
Y991011D03*
Y984318D03*
Y1021129D03*
Y1024475D03*
Y1031168D03*
X696141Y1044554D03*
Y1037861D03*
X696441Y1051247D03*
Y1071325D03*
Y1064633D03*
Y1078018D03*
Y1094751D03*
Y1088058D03*
Y1081365D03*
Y1108136D03*
Y1101444D03*
Y1124869D03*
Y1118176D03*
Y1114829D03*
Y1144947D03*
Y1138255D03*
Y1131562D03*
Y1161680D03*
Y1154987D03*
Y1151640D03*
Y1175066D03*
Y1168373D03*
Y1181758D03*
Y1191798D03*
Y1188451D03*
Y1205184D03*
Y1198491D03*
Y1218569D03*
Y1211877D03*
Y1225262D03*
Y1241995D03*
Y1235302D03*
Y1228609D03*
X709899Y960892D03*
Y957546D03*
X709999Y967585D03*
Y1054593D03*
X726141Y964239D03*
Y1021129D03*
Y1024475D03*
Y1051247D03*
X739699Y780184D03*
Y773491D03*
Y786877D03*
Y803609D03*
Y796916D03*
Y790223D03*
Y816995D03*
Y810302D03*
Y833727D03*
Y823688D03*
Y827034D03*
Y847113D03*
Y840420D03*
Y853806D03*
Y860499D03*
Y863845D03*
Y883924D03*
Y877231D03*
Y870538D03*
Y890617D03*
Y897310D03*
Y900656D03*
Y914042D03*
Y907349D03*
Y927428D03*
Y920735D03*
Y934121D03*
Y944160D03*
Y937467D03*
Y960892D03*
Y950853D03*
Y957546D03*
Y980971D03*
Y974278D03*
Y967585D03*
Y994357D03*
Y987664D03*
Y1027822D03*
Y1021129D03*
Y1047900D03*
Y1041207D03*
Y1034514D03*
Y1054593D03*
Y1074672D03*
Y1067979D03*
Y1091404D03*
Y1081365D03*
Y1084711D03*
Y1098097D03*
Y1111483D03*
Y1104790D03*
Y1128215D03*
Y1118176D03*
Y1121522D03*
Y1141601D03*
Y1134908D03*
Y1148294D03*
Y1154987D03*
Y1158333D03*
Y1171719D03*
Y1165026D03*
Y1185105D03*
Y1178412D03*
Y1191798D03*
Y1208530D03*
Y1201837D03*
Y1195144D03*
Y1221916D03*
Y1215223D03*
Y1238648D03*
Y1228609D03*
Y1231955D03*
Y1245341D03*
X755841Y770144D03*
Y776837D03*
Y786877D03*
Y783530D03*
Y800263D03*
Y793570D03*
Y813648D03*
Y806955D03*
Y820341D03*
Y830381D03*
Y823688D03*
Y850459D03*
Y843766D03*
Y837074D03*
Y867192D03*
Y860499D03*
Y857152D03*
Y873885D03*
Y880577D03*
Y887270D03*
Y897310D03*
Y893963D03*
Y917389D03*
Y910696D03*
Y904003D03*
Y924081D03*
Y934121D03*
Y930774D03*
Y947507D03*
Y940814D03*
Y964239D03*
Y977625D03*
X755741Y970932D03*
X755841Y991011D03*
Y984318D03*
Y1021129D03*
Y1024475D03*
Y1031168D03*
X755541Y1044554D03*
Y1037861D03*
X755841Y1051247D03*
X755676Y1071326D03*
X755741Y1064633D03*
X755841Y1078018D03*
Y1094751D03*
Y1088058D03*
Y1081365D03*
X755676Y1108137D03*
X755841Y1101444D03*
Y1124869D03*
Y1118176D03*
Y1114829D03*
Y1144947D03*
Y1138255D03*
Y1131562D03*
Y1161680D03*
Y1154987D03*
Y1151640D03*
Y1175066D03*
Y1168373D03*
X755676Y1181759D03*
X755841Y1191798D03*
X755676Y1188452D03*
X755841Y1205184D03*
Y1198491D03*
Y1218569D03*
Y1211877D03*
Y1225262D03*
Y1241995D03*
Y1235302D03*
Y1228609D03*
X769399Y960892D03*
Y957546D03*
Y967585D03*
Y1054593D03*
X785541Y964239D03*
Y1021129D03*
Y1024475D03*
Y1051247D03*
X799099Y780184D03*
Y773491D03*
Y786877D03*
Y803609D03*
Y796916D03*
Y790223D03*
Y816995D03*
Y810302D03*
Y833727D03*
Y823688D03*
Y827034D03*
Y847113D03*
Y840420D03*
Y853806D03*
Y860499D03*
Y863845D03*
Y883924D03*
Y877231D03*
Y870538D03*
Y890617D03*
Y897310D03*
Y900656D03*
Y914042D03*
Y907349D03*
Y927428D03*
Y920735D03*
Y934121D03*
Y944160D03*
Y937467D03*
Y960892D03*
Y950853D03*
Y957546D03*
Y980971D03*
Y974278D03*
Y967585D03*
Y994357D03*
Y987664D03*
Y1027822D03*
Y1021129D03*
Y1047900D03*
Y1041207D03*
Y1034515D03*
Y1054593D03*
Y1074672D03*
Y1067979D03*
Y1091404D03*
Y1081365D03*
Y1084711D03*
Y1098097D03*
Y1111483D03*
Y1104790D03*
Y1128215D03*
Y1118176D03*
Y1121522D03*
Y1141601D03*
Y1134908D03*
Y1148294D03*
Y1154987D03*
Y1158333D03*
Y1171719D03*
Y1165026D03*
Y1185105D03*
Y1178412D03*
Y1191798D03*
Y1208530D03*
Y1201837D03*
Y1195144D03*
Y1221916D03*
Y1215223D03*
Y1238648D03*
Y1228609D03*
Y1231955D03*
Y1245341D03*
X815241Y770144D03*
Y776837D03*
Y786877D03*
Y783530D03*
Y800263D03*
Y793570D03*
Y813648D03*
Y806955D03*
Y820341D03*
Y830381D03*
Y823688D03*
Y850459D03*
Y843766D03*
Y837074D03*
Y867192D03*
Y860499D03*
Y857152D03*
Y873885D03*
Y880577D03*
Y887270D03*
Y897310D03*
Y893963D03*
Y917389D03*
Y910696D03*
Y904003D03*
Y924081D03*
Y934121D03*
Y930774D03*
Y947507D03*
Y940814D03*
Y964239D03*
Y977625D03*
Y970932D03*
Y991011D03*
Y984318D03*
Y1021129D03*
Y1024475D03*
Y1031168D03*
Y1044554D03*
Y1037861D03*
X814941Y1051247D03*
X815241Y1071325D03*
Y1064633D03*
Y1078018D03*
Y1094751D03*
Y1088058D03*
Y1081365D03*
Y1108136D03*
Y1101444D03*
Y1124869D03*
Y1118176D03*
Y1114829D03*
Y1144947D03*
Y1138255D03*
Y1131562D03*
Y1161680D03*
Y1154987D03*
Y1151640D03*
Y1175066D03*
Y1168373D03*
Y1181758D03*
Y1191798D03*
Y1188451D03*
Y1205184D03*
Y1198491D03*
Y1218570D03*
Y1211877D03*
Y1225263D03*
Y1241995D03*
Y1235302D03*
Y1228609D03*
X828799Y960892D03*
Y957546D03*
Y967585D03*
Y1054593D03*
X844941Y964239D03*
Y1021129D03*
Y1024475D03*
Y1051247D03*
X1012541Y960892D03*
Y957546D03*
Y967585D03*
Y1054593D03*
X1028683Y964239D03*
Y1021129D03*
Y1024475D03*
Y1051247D03*
X1042241Y780184D03*
Y773491D03*
Y786877D03*
Y803609D03*
Y796916D03*
Y790223D03*
Y816995D03*
Y810302D03*
Y833727D03*
Y823688D03*
Y827034D03*
Y847113D03*
Y840420D03*
Y853806D03*
Y860499D03*
Y863845D03*
Y883924D03*
Y877231D03*
Y870538D03*
Y890617D03*
Y897310D03*
Y900656D03*
Y914042D03*
Y907349D03*
Y927428D03*
Y920735D03*
Y934121D03*
Y944160D03*
Y937467D03*
Y960892D03*
Y950853D03*
Y957546D03*
Y980971D03*
Y974278D03*
Y967585D03*
Y994357D03*
Y987664D03*
Y1027822D03*
Y1021129D03*
Y1047900D03*
Y1041207D03*
Y1034515D03*
Y1054593D03*
Y1074672D03*
Y1067979D03*
Y1091404D03*
Y1081365D03*
Y1084711D03*
Y1098097D03*
Y1111483D03*
Y1104790D03*
Y1128215D03*
Y1118176D03*
Y1121522D03*
Y1141601D03*
Y1134908D03*
Y1148294D03*
Y1154987D03*
Y1158333D03*
Y1171719D03*
Y1165026D03*
Y1185105D03*
Y1178412D03*
Y1191798D03*
Y1208530D03*
Y1201837D03*
Y1195144D03*
Y1221916D03*
Y1215223D03*
Y1238648D03*
Y1228609D03*
Y1231955D03*
Y1245341D03*
X1058383Y770144D03*
Y776837D03*
Y786877D03*
Y783530D03*
Y800263D03*
Y793570D03*
Y813648D03*
Y806955D03*
Y820341D03*
Y830381D03*
Y823688D03*
Y850459D03*
Y843766D03*
Y837074D03*
Y867192D03*
Y860499D03*
Y857152D03*
Y873885D03*
Y880577D03*
Y887270D03*
Y897310D03*
Y893963D03*
Y917389D03*
Y910696D03*
Y904003D03*
Y924081D03*
Y934121D03*
Y930774D03*
Y947507D03*
Y940814D03*
Y964239D03*
Y977625D03*
Y970932D03*
Y991011D03*
Y984318D03*
Y1021129D03*
Y1024475D03*
Y1031168D03*
Y1044554D03*
Y1037861D03*
Y1051247D03*
Y1071326D03*
Y1064633D03*
Y1078018D03*
Y1094751D03*
Y1088058D03*
Y1081365D03*
Y1108137D03*
Y1101444D03*
Y1124869D03*
Y1118176D03*
Y1114829D03*
Y1144948D03*
Y1138255D03*
Y1131562D03*
Y1161680D03*
Y1154987D03*
Y1151641D03*
Y1175066D03*
Y1168373D03*
Y1181759D03*
Y1191798D03*
Y1188452D03*
Y1205184D03*
Y1198491D03*
Y1218570D03*
Y1211877D03*
Y1225263D03*
Y1241995D03*
Y1235302D03*
Y1228609D03*
X1071941Y960892D03*
Y957546D03*
Y967585D03*
Y1054593D03*
X1101641Y780184D03*
Y773491D03*
Y786877D03*
Y803609D03*
Y796916D03*
Y790223D03*
Y816995D03*
Y810302D03*
Y833727D03*
Y823688D03*
Y827034D03*
Y847113D03*
Y840420D03*
Y853806D03*
Y860499D03*
Y863845D03*
Y883924D03*
Y877231D03*
Y870538D03*
Y890617D03*
Y897310D03*
Y900656D03*
Y914042D03*
Y907349D03*
Y927428D03*
Y920735D03*
Y934121D03*
Y944160D03*
Y937467D03*
Y960892D03*
Y950853D03*
X1088083Y964239D03*
X1101641Y957546D03*
Y980971D03*
Y974278D03*
Y967585D03*
Y994357D03*
Y987664D03*
X1088083Y1021129D03*
Y1024475D03*
X1101641Y1027822D03*
Y1021129D03*
Y1047900D03*
Y1041207D03*
Y1034515D03*
X1088083Y1051247D03*
X1101641Y1054593D03*
Y1074672D03*
Y1067979D03*
Y1091404D03*
Y1081365D03*
Y1084711D03*
Y1098097D03*
Y1111483D03*
Y1104790D03*
Y1128215D03*
Y1118176D03*
Y1121522D03*
Y1141601D03*
Y1134908D03*
Y1148294D03*
Y1154987D03*
Y1158333D03*
Y1171719D03*
Y1165026D03*
Y1185105D03*
Y1178412D03*
Y1191798D03*
Y1208530D03*
Y1201837D03*
Y1195144D03*
Y1221916D03*
Y1215223D03*
Y1238648D03*
Y1228609D03*
Y1231955D03*
Y1245341D03*
X1117783Y770144D03*
Y776837D03*
Y786877D03*
Y783530D03*
Y800263D03*
Y793570D03*
Y813648D03*
Y806955D03*
Y820341D03*
Y830381D03*
Y823688D03*
Y850459D03*
Y843766D03*
Y837074D03*
Y867192D03*
Y860499D03*
Y857152D03*
Y873885D03*
Y880577D03*
Y887270D03*
Y897310D03*
Y893963D03*
Y917389D03*
Y910696D03*
Y904003D03*
Y924081D03*
Y934121D03*
Y930774D03*
Y947507D03*
Y940814D03*
Y964239D03*
Y977625D03*
Y970932D03*
Y991011D03*
Y984318D03*
Y1021129D03*
Y1024475D03*
Y1031168D03*
Y1044554D03*
Y1037861D03*
Y1051247D03*
Y1071326D03*
Y1064633D03*
Y1078018D03*
Y1094751D03*
Y1088058D03*
Y1081365D03*
Y1108137D03*
Y1101444D03*
Y1124869D03*
Y1118176D03*
Y1114829D03*
Y1144948D03*
Y1138255D03*
Y1131562D03*
Y1161680D03*
Y1154987D03*
Y1151641D03*
Y1175066D03*
Y1168373D03*
Y1181759D03*
Y1191798D03*
Y1188452D03*
Y1205184D03*
Y1198491D03*
Y1218570D03*
Y1211877D03*
Y1225263D03*
Y1241995D03*
Y1235302D03*
Y1228609D03*
X1131341Y960892D03*
Y957546D03*
Y967585D03*
Y1054593D03*
X1147483Y964239D03*
Y1021129D03*
Y1024475D03*
Y1051247D03*
X1161041Y780184D03*
Y773491D03*
Y786877D03*
Y803609D03*
Y796916D03*
Y790223D03*
Y816995D03*
Y810302D03*
Y833727D03*
Y823688D03*
Y827034D03*
Y847113D03*
Y840420D03*
Y853806D03*
Y860499D03*
Y863845D03*
Y883924D03*
Y877231D03*
Y870538D03*
Y890617D03*
Y897310D03*
Y900656D03*
Y914042D03*
Y907349D03*
Y927428D03*
Y920735D03*
Y934121D03*
Y944160D03*
Y937467D03*
Y960892D03*
Y950853D03*
Y957546D03*
Y980971D03*
Y974278D03*
Y967585D03*
Y994357D03*
Y987664D03*
Y1027822D03*
Y1021129D03*
Y1047900D03*
Y1041207D03*
Y1034515D03*
Y1054593D03*
Y1074672D03*
Y1067979D03*
Y1091404D03*
Y1081365D03*
Y1084711D03*
Y1098097D03*
Y1111483D03*
Y1104790D03*
Y1128215D03*
Y1118176D03*
Y1121522D03*
Y1141601D03*
Y1134908D03*
Y1148294D03*
Y1154987D03*
Y1158333D03*
Y1171719D03*
Y1165026D03*
Y1185105D03*
Y1178412D03*
Y1191798D03*
Y1208530D03*
Y1201837D03*
Y1195144D03*
Y1221916D03*
Y1215223D03*
Y1238648D03*
Y1228609D03*
Y1231955D03*
Y1245341D03*
X1177183Y770144D03*
Y776837D03*
Y786877D03*
Y783530D03*
Y800263D03*
Y793570D03*
Y813648D03*
Y806955D03*
Y820341D03*
Y830381D03*
Y823688D03*
Y850459D03*
Y843766D03*
Y837074D03*
Y867192D03*
Y860499D03*
Y857152D03*
Y873885D03*
Y880577D03*
Y887270D03*
Y897310D03*
Y893963D03*
Y917389D03*
Y910696D03*
Y904003D03*
Y924081D03*
Y934121D03*
Y930774D03*
Y947507D03*
Y940814D03*
Y964239D03*
Y977625D03*
Y970932D03*
Y991011D03*
Y984318D03*
X1177283Y1021129D03*
Y1024475D03*
Y1031168D03*
Y1044554D03*
Y1037861D03*
Y1051247D03*
Y1071326D03*
Y1064633D03*
Y1078018D03*
Y1094752D03*
Y1088059D03*
Y1081366D03*
Y1108137D03*
Y1101444D03*
X1177183Y1124869D03*
X1177283Y1118177D03*
Y1114830D03*
Y1144948D03*
Y1138255D03*
X1177183Y1131562D03*
X1177283Y1161680D03*
Y1154988D03*
Y1151641D03*
Y1175066D03*
Y1168373D03*
Y1181759D03*
Y1191799D03*
Y1188452D03*
Y1205184D03*
Y1198491D03*
Y1218570D03*
Y1211877D03*
Y1225263D03*
X1177250Y1241995D03*
X1177283Y1235302D03*
Y1228609D03*
X1190741Y960892D03*
Y957546D03*
X1220441Y883924D03*
Y890617D03*
Y897310D03*
Y900656D03*
Y914042D03*
Y907349D03*
Y960892D03*
Y957546D03*
Y1185105D03*
Y1178412D03*
Y1191798D03*
Y1208530D03*
Y1201837D03*
Y1195144D03*
X1236583Y880577D03*
Y887270D03*
Y897310D03*
Y893963D03*
Y910696D03*
Y904003D03*
Y1175066D03*
Y1181759D03*
Y1191798D03*
Y1188452D03*
Y1205184D03*
Y1198491D03*
X1313921Y880219D03*
X1312070Y883423D03*
X1313921Y893036D03*
X1312070Y889832D03*
X1310221Y886627D03*
X1313921D03*
X1312503Y1121447D03*
X1326869Y851380D03*
X1330569Y844971D03*
X1325020Y848176D03*
X1328720D03*
X1326871Y857789D03*
X1328720Y860993D03*
X1330571Y857789D03*
X1317621Y880219D03*
X1319471Y883423D03*
X1325020Y899445D03*
Y893036D03*
X1326871Y889832D03*
X1330571D03*
X1317620Y893036D03*
X1319470Y889832D03*
X1323171Y896240D03*
X1330571D03*
X1317621Y886627D03*
X1326871Y896240D03*
X1321321Y886627D03*
X1325020Y912262D03*
X1326871Y909057D03*
X1330571D03*
X1326871Y902649D03*
X1330571D03*
X1323171Y915466D03*
X1330571D03*
X1326871D03*
X1325021Y931488D03*
X1326871Y928283D03*
X1330571D03*
Y921875D03*
X1326871D03*
X1325020Y918670D03*
X1326871Y941100D03*
X1325020Y937896D03*
X1330571Y941100D03*
X1323171Y934691D03*
X1330571D03*
X1326871D03*
Y947509D03*
X1330571D03*
X1325020Y950713D03*
X1326871Y960326D03*
X1325020Y957122D03*
X1330571Y960326D03*
X1326871Y966735D03*
X1330571D03*
X1326871Y953917D03*
X1330571D03*
X1323172D03*
X1326871Y979552D03*
X1330571D03*
X1325020Y976347D03*
X1323171Y973143D03*
X1325020Y969939D03*
X1323603Y1006093D03*
X1325453Y1002888D03*
X1327303Y999684D03*
X1331003D03*
X1327303Y1012501D03*
X1325453Y1009297D03*
X1331003Y1012501D03*
X1327304Y1031727D03*
X1325453Y1028523D03*
X1331003Y1031727D03*
X1325453Y1022114D03*
X1327303Y1018910D03*
X1331003D03*
X1323603Y1025318D03*
X1331004D03*
X1327304D03*
X1325453Y1047749D03*
Y1041340D03*
X1327303Y1038136D03*
X1331003D03*
X1323603Y1044544D03*
X1331003D03*
X1327303D03*
X1325453Y1060565D03*
X1327303Y1057361D03*
X1331003D03*
X1323603Y1063770D03*
X1327303D03*
X1331003D03*
X1327303Y1050952D03*
X1331003D03*
Y1070178D03*
X1327304D03*
X1325453Y1066974D03*
Y1079791D03*
X1327303Y1076587D03*
X1331003D03*
X1327303Y1089404D03*
X1325453Y1086200D03*
X1331003Y1089404D03*
X1323603Y1082995D03*
X1331003D03*
X1327303D03*
X1329153Y1105426D03*
X1325454Y1111834D03*
X1327303Y1102221D03*
X1321753Y1111834D03*
X1318054D03*
X1318053Y1105426D03*
X1327304Y1108630D03*
X1329154Y1111834D03*
X1331003Y1102221D03*
X1319904Y1108630D03*
X1321753Y1105426D03*
X1329153Y1124651D03*
X1331003Y1127856D03*
X1323603Y1121447D03*
X1319903Y1127856D03*
X1316203D03*
X1318054Y1118243D03*
X1321753Y1124651D03*
X1323603Y1127856D03*
X1319903Y1121447D03*
X1316203D03*
X1323603Y1115039D03*
X1325452Y1137469D03*
X1327303Y1134264D03*
X1318053Y1131060D03*
X1346137Y179649D03*
X1332421Y841467D03*
X1337969Y844971D03*
X1339821Y841467D03*
X1345369Y844971D03*
X1347221Y841467D03*
X1334269Y844971D03*
X1336120Y848176D03*
X1341669Y844971D03*
X1343520Y848176D03*
X1332420Y854584D03*
X1334271Y857789D03*
X1337971D03*
X1341671D03*
X1345371D03*
X1336120Y860993D03*
X1339820Y854584D03*
X1343520Y860993D03*
X1347220Y854584D03*
X1332420Y899445D03*
Y893036D03*
X1334271Y896240D03*
X1339820Y899445D03*
X1343520D03*
X1347220Y893036D03*
X1332420Y912262D03*
X1334271Y915466D03*
X1339820Y912262D03*
X1337971Y909057D03*
X1343520Y912262D03*
X1345371Y909057D03*
X1337971Y902649D03*
X1345371D03*
X1336120Y905853D03*
X1343520D03*
X1339820D03*
X1347220D03*
X1332420Y931488D03*
X1339820D03*
X1332420Y918670D03*
X1337971Y928283D03*
X1343520Y931488D03*
X1345371Y928283D03*
X1337971Y921875D03*
X1339820Y918670D03*
X1345371Y921875D03*
X1343520Y918670D03*
X1336120Y925079D03*
X1343520D03*
X1339820D03*
X1347220D03*
X1332420Y937896D03*
X1334271Y934691D03*
X1337971Y941100D03*
X1339820Y937896D03*
X1345371Y941100D03*
X1343520Y937896D03*
X1337971Y947509D03*
X1345371D03*
X1343520Y944304D03*
X1336120D03*
X1347220D03*
X1339820D03*
X1332420Y950713D03*
Y957122D03*
X1334271Y953917D03*
X1337971Y966735D03*
X1345371D03*
X1336120Y963530D03*
X1339820Y950713D03*
X1343520D03*
X1337971Y960326D03*
X1339820Y957122D03*
X1345371Y960326D03*
X1343520Y957122D03*
X1347220Y963530D03*
X1336120Y982756D03*
X1343520D03*
X1339820D03*
X1347220D03*
X1345371Y979552D03*
X1343520Y976347D03*
X1337971Y979552D03*
X1339820Y976347D03*
X1332420D03*
Y969939D03*
X1334271Y973143D03*
X1339820Y969939D03*
X1343520D03*
X1334704Y1006093D03*
X1332853Y1002888D03*
Y1009297D03*
X1338404Y1012501D03*
X1345804D03*
X1340253Y1009297D03*
X1343953D03*
X1340253Y1002888D03*
X1338404Y999684D03*
X1347653Y1002888D03*
X1345804Y999684D03*
X1332853Y1028523D03*
Y1022114D03*
X1338404Y1031727D03*
X1340253Y1028523D03*
X1345804Y1031727D03*
X1343953Y1028523D03*
X1334704Y1025318D03*
X1336553Y1015705D03*
X1347653D03*
X1340253Y1022114D03*
X1338404Y1018910D03*
X1343953Y1022114D03*
X1345804Y1018910D03*
X1332853Y1047749D03*
Y1041340D03*
X1340253D03*
X1338404Y1038136D03*
X1343953Y1041340D03*
X1345804Y1038136D03*
X1336553Y1034931D03*
X1347653D03*
X1340253D03*
X1334704Y1044544D03*
X1343953Y1034931D03*
X1340253Y1047749D03*
X1343953D03*
X1332853Y1060565D03*
X1334704Y1063770D03*
X1340253Y1060565D03*
X1338404Y1057361D03*
X1343953Y1060565D03*
X1345804Y1057361D03*
X1338404Y1050952D03*
X1345804D03*
X1336553Y1054157D03*
X1347653D03*
X1340253D03*
X1343953D03*
X1332853Y1066974D03*
X1343953Y1079791D03*
X1345804Y1076587D03*
X1338404Y1070178D03*
X1340253Y1066974D03*
X1345804Y1070178D03*
X1343953Y1066974D03*
X1332853Y1079791D03*
X1340253D03*
X1338404Y1076587D03*
X1336553Y1073383D03*
X1347653D03*
X1340253D03*
X1343953D03*
X1332853Y1086200D03*
X1334704Y1082995D03*
X1338404Y1095813D03*
X1345804D03*
X1338404Y1089404D03*
X1340253Y1086200D03*
X1345804Y1089404D03*
X1343953Y1086200D03*
X1336553Y1092608D03*
X1343953D03*
X1340253D03*
X1347653D03*
X1340253Y1099017D03*
X1343953D03*
X1345803Y1108630D03*
X1340254Y1105426D03*
X1336554Y1111834D03*
X1334703Y1108630D03*
X1343954Y1111834D03*
X1342103Y1108630D03*
X1338403D03*
X1334703Y1121447D03*
X1336554Y1124651D03*
X1340253D03*
X1343953D03*
X1347653D03*
X1332854D03*
X1338404Y1127856D03*
X1342104Y1121447D03*
X1345804Y1127856D03*
X1342103Y1115039D03*
X1345803D03*
X1334703D03*
Y1134264D03*
X1338403Y1140973D03*
X1342104Y1134264D03*
X1345803Y1140973D03*
X1332854Y1137469D03*
X1336554D03*
X1340254D03*
X1343954D03*
X1347654D03*
X1352557Y175948D03*
X1349351Y181498D03*
X1355761Y185198D03*
X1349351D03*
X1355761Y174098D03*
Y181498D03*
X1352557Y183348D03*
X1352561Y198148D03*
X1355771Y196298D03*
X1355765Y199999D03*
Y203699D03*
X1363869Y844971D03*
X1352769D03*
X1356469D03*
X1360169D03*
X1362021Y841467D03*
X1349069Y844971D03*
X1350920Y848176D03*
X1354621Y841467D03*
X1358320Y848176D03*
X1349071Y857789D03*
X1354620Y854584D03*
X1356471Y857789D03*
X1360171D03*
X1363871D03*
X1350920Y860993D03*
X1352771Y857789D03*
X1358320Y860993D03*
X1362020Y854584D03*
X1350920Y899445D03*
X1358320D03*
Y893036D03*
X1350920D03*
X1362020D03*
X1349071Y896240D03*
X1356471D03*
X1352771D03*
X1360171D03*
X1352771Y902649D03*
X1356471D03*
X1350920Y912262D03*
X1352771Y909057D03*
X1358320Y912262D03*
X1356471Y909057D03*
X1363871D03*
Y902649D03*
X1349071Y915466D03*
X1362020Y905853D03*
X1356471Y915466D03*
X1352771D03*
X1360171D03*
X1350920Y931488D03*
X1352771Y928283D03*
X1358320Y931488D03*
X1356471Y928283D03*
X1363871Y921875D03*
X1352771D03*
X1350920Y918670D03*
X1356471Y921875D03*
X1358320Y918670D03*
X1363871Y928283D03*
X1362020Y925079D03*
X1356471Y941100D03*
X1358320Y937896D03*
X1352771Y947509D03*
X1356471D03*
X1352771Y941100D03*
X1350920Y937896D03*
X1349071Y934691D03*
X1356471D03*
X1352771D03*
X1360171D03*
X1363871Y947509D03*
Y941100D03*
X1362020Y944304D03*
X1352771Y960326D03*
X1350920Y957122D03*
X1356471Y960326D03*
X1358320Y957122D03*
X1350920Y950713D03*
X1358320D03*
X1349071Y953917D03*
X1356471D03*
X1352771D03*
X1360171D03*
X1363871Y960326D03*
Y966735D03*
X1356471D03*
X1352771D03*
X1362020Y963530D03*
Y982756D03*
X1363871Y979552D03*
X1352771D03*
X1356471D03*
X1350920Y976347D03*
X1358320D03*
X1349071Y973143D03*
X1350920Y969939D03*
X1358320D03*
X1360171Y973143D03*
X1349504Y1006093D03*
X1356904D03*
X1353204D03*
X1360604D03*
X1351353Y1002888D03*
X1353204Y999684D03*
X1358753Y1002888D03*
X1356904Y999684D03*
X1353204Y1012501D03*
X1351353Y1009297D03*
X1356904Y1012501D03*
X1358753Y1009297D03*
X1353204Y1031727D03*
X1351353Y1028523D03*
X1356904Y1031727D03*
X1358753Y1028523D03*
X1351353Y1022114D03*
X1353204Y1018910D03*
X1358753Y1022114D03*
X1356904Y1018910D03*
X1353204Y1025318D03*
X1360604D03*
X1349502D03*
X1356902D03*
X1362453Y1015705D03*
X1351353Y1047749D03*
X1358753D03*
X1351353Y1041340D03*
X1353204Y1038136D03*
X1358753Y1041340D03*
X1356904Y1038136D03*
X1349504Y1044544D03*
X1356904D03*
X1353204D03*
X1360604D03*
X1362453Y1034931D03*
X1351353Y1060565D03*
X1353204Y1057361D03*
X1358753Y1060565D03*
X1356904Y1057361D03*
X1353204Y1050952D03*
X1356904D03*
X1349504Y1063770D03*
X1360604D03*
X1353204D03*
X1356904D03*
X1362453Y1054157D03*
X1356904Y1070178D03*
X1358753Y1066974D03*
X1353204Y1070178D03*
X1351353Y1066974D03*
Y1079791D03*
X1353204Y1076587D03*
X1358753Y1079791D03*
X1356904Y1076587D03*
X1362453Y1073383D03*
X1353204Y1089404D03*
X1351353Y1086200D03*
X1356904Y1089404D03*
X1358753Y1086200D03*
X1349504Y1082995D03*
X1362453Y1092608D03*
X1360604Y1082995D03*
X1353204D03*
X1356904D03*
X1362453Y1111834D03*
Y1105426D03*
X1358753D03*
X1351353Y1111834D03*
Y1105426D03*
X1358753Y1111834D03*
X1360604Y1108630D03*
X1355053Y1111834D03*
X1356904Y1102221D03*
X1353204Y1108630D03*
X1355054Y1105426D03*
X1351353Y1124651D03*
X1355053D03*
X1358753D03*
X1362453D03*
X1349504Y1121447D03*
X1353204Y1127856D03*
X1356904Y1121447D03*
X1360604Y1127856D03*
X1356904Y1115039D03*
X1349504Y1134264D03*
X1353203Y1140973D03*
X1356904Y1134264D03*
X1360603Y1140973D03*
X1351354Y1137469D03*
X1355054D03*
X1358754D03*
X1362454D03*
X1367569Y844971D03*
X1369421Y841467D03*
X1373120Y848176D03*
X1376821Y841467D03*
X1365720Y848176D03*
X1371269Y844971D03*
X1374969D03*
X1378669D03*
X1365720Y860993D03*
X1367571Y857789D03*
X1373120Y860993D03*
X1374971Y857789D03*
X1369420Y854584D03*
X1371271Y857789D03*
X1376820Y854584D03*
X1378671Y857789D03*
X1365720Y899445D03*
X1369420D03*
X1365720Y912262D03*
X1369420D03*
X1371271Y909057D03*
Y902649D03*
X1369420Y905853D03*
X1365720D03*
X1373120D03*
X1369420Y931488D03*
X1371271Y928283D03*
X1365720Y918670D03*
X1371271Y921875D03*
X1369420Y918670D03*
X1365720Y931488D03*
X1369420Y925079D03*
X1365720D03*
X1373120D03*
X1371271Y947509D03*
X1365720Y937896D03*
X1371271Y941100D03*
X1369420Y937896D03*
Y944304D03*
X1365720D03*
X1373120D03*
X1365720Y957122D03*
X1371271Y960326D03*
X1369420Y957122D03*
X1371271Y966735D03*
X1365720Y950713D03*
X1369420D03*
X1373120Y963530D03*
X1369420D03*
X1365720D03*
X1374971Y973143D03*
X1376820Y976347D03*
X1378671Y979552D03*
Y973143D03*
X1369420Y982756D03*
X1365720D03*
X1373120D03*
X1369420Y976347D03*
X1371271Y979552D03*
X1365721Y976347D03*
X1365720Y969939D03*
X1369420D03*
X1366153Y1002888D03*
X1364304Y999684D03*
X1369853Y1002888D03*
X1371704Y999684D03*
X1364304Y1012501D03*
X1371704D03*
X1366153Y1009297D03*
X1369853D03*
X1373553Y1015705D03*
X1364304Y1031727D03*
X1366153Y1028523D03*
X1371704Y1031727D03*
X1369853Y1028523D03*
X1366153Y1022114D03*
X1364304Y1018910D03*
X1369853Y1022114D03*
X1371704Y1018910D03*
X1366153Y1041340D03*
X1364304Y1038136D03*
X1369853Y1041340D03*
X1371704Y1038136D03*
X1366153Y1047749D03*
X1369853D03*
Y1034931D03*
X1366153D03*
X1373553D03*
X1366153Y1060565D03*
X1364304Y1057361D03*
X1369853Y1060565D03*
X1371704Y1057361D03*
X1364304Y1050952D03*
X1371704D03*
X1369853Y1054157D03*
X1366153D03*
X1373553D03*
X1366153Y1079791D03*
X1364304Y1076587D03*
X1369853Y1079791D03*
X1371704Y1076587D03*
X1364304Y1070178D03*
X1366153Y1066974D03*
X1371704Y1070178D03*
X1369853Y1066974D03*
Y1073383D03*
X1366153D03*
X1373553D03*
X1371704Y1095813D03*
X1364304Y1089404D03*
X1366153Y1086200D03*
X1371704Y1089404D03*
X1369853Y1086200D03*
X1364304Y1095813D03*
X1369853Y1092608D03*
X1366153D03*
X1373553D03*
X1379104Y1082995D03*
X1379103Y1089404D03*
X1369853Y1099017D03*
X1366153D03*
X1369853Y1111834D03*
X1368004Y1108630D03*
X1377253Y1099017D03*
X1379104Y1108630D03*
X1373553Y1105426D03*
X1371704Y1108630D03*
X1379104Y1102221D03*
X1377253Y1111834D03*
X1375404Y1108630D03*
X1366153Y1124651D03*
X1371704Y1121447D03*
X1373553Y1124651D03*
X1377253D03*
X1368004Y1127856D03*
X1369853Y1124651D03*
X1375404Y1127856D03*
X1379104Y1121447D03*
X1364304D03*
X1375404Y1115039D03*
X1368004D03*
X1379104D03*
X1368003Y1140973D03*
X1371704Y1134264D03*
X1375403Y1140973D03*
X1379104Y1134264D03*
X1364304D03*
X1366154Y1137469D03*
X1369854D03*
X1373554D03*
X1377254D03*
X1380520Y848176D03*
X1386069Y844971D03*
X1389769D03*
X1393469D03*
X1382369D03*
X1384221Y841467D03*
X1387920Y848176D03*
X1391621Y841467D03*
X1395320Y848176D03*
X1391620Y867401D03*
X1380520Y860993D03*
X1382371Y857789D03*
X1387920Y860993D03*
X1389771Y857789D03*
X1395320Y860993D03*
X1384220Y854584D03*
X1386071Y857789D03*
X1391620Y854584D03*
X1393471Y857789D03*
X1395320Y873810D03*
X1393471Y870606D03*
X1387920Y873810D03*
X1389771Y870606D03*
X1393471Y883423D03*
X1391620Y880219D03*
X1389771Y883423D03*
X1386071Y896240D03*
X1389771D03*
X1393471D03*
X1387920Y899445D03*
X1391620Y893036D03*
X1395320Y899445D03*
Y886627D03*
X1384653Y1079791D03*
X1388353Y1086200D03*
X1386504Y1082995D03*
X1390204Y1089404D03*
X1382804D03*
X1390204Y1082995D03*
X1382804D03*
X1395753Y1086200D03*
Y1092608D03*
X1380953Y1086200D03*
X1386504Y1089404D03*
X1384653Y1092608D03*
X1380953Y1099017D03*
X1395753Y1105426D03*
X1393904Y1108630D03*
X1390204Y1102221D03*
X1392053Y1111834D03*
X1388353D03*
X1384653Y1105426D03*
Y1099017D03*
X1392053Y1105426D03*
X1395753Y1111834D03*
X1388353Y1105426D03*
X1384653Y1111834D03*
X1386504Y1108630D03*
X1380953Y1124651D03*
X1384653D03*
X1382804Y1127856D03*
X1386504Y1121447D03*
X1390204Y1115039D03*
X1382803Y1140973D03*
X1386504Y1134264D03*
X1380954Y1137469D03*
X1384654D03*
X1397169Y844971D03*
X1399021Y841467D03*
X1402720Y848176D03*
X1406420D03*
X1411969Y844971D03*
X1400869D03*
X1404569D03*
X1410120Y848176D03*
X1406420Y867401D03*
X1399020D03*
X1397171Y857789D03*
X1402720Y860993D03*
X1404571Y857789D03*
X1410121Y860993D03*
X1411971Y857789D03*
X1399020Y854584D03*
X1400871Y857789D03*
X1406420Y854584D03*
X1408271Y857789D03*
Y870606D03*
X1402720Y873810D03*
X1400871Y870606D03*
X1410121Y873810D03*
X1404571Y870606D03*
X1397171D03*
X1411971D03*
X1408271Y883423D03*
X1406420Y880219D03*
X1400871Y883423D03*
X1399020Y880219D03*
X1404571Y883423D03*
X1397171D03*
X1411971D03*
X1397171Y896240D03*
X1402720Y899445D03*
X1404571Y896240D03*
X1410120Y899445D03*
X1399020Y893036D03*
X1400871Y896240D03*
X1406420Y893036D03*
X1408271Y896240D03*
X1411971D03*
X1410120Y886627D03*
X1402720D03*
X1405003Y1076587D03*
X1406853Y1079791D03*
X1401304Y1082995D03*
X1405003Y1089404D03*
X1399453Y1086200D03*
X1406853Y1092608D03*
X1399453D03*
X1397604Y1089404D03*
X1403154Y1086200D03*
X1406852D03*
X1403153Y1092608D03*
X1401304Y1095813D03*
X1413820Y848176D03*
X1428620Y867401D03*
X1421220D03*
X1413820D03*
X1424921Y860993D03*
X1421220Y854584D03*
X1417520Y860993D03*
X1428620Y854584D03*
X1426771Y857789D03*
X1423071D03*
X1419371D03*
X1413821Y854584D03*
X1424921Y873810D03*
X1423071Y870606D03*
X1417520Y873810D03*
X1415671Y870606D03*
X1426771D03*
X1419371D03*
X1428621Y880219D03*
X1423071Y883423D03*
X1421220Y880219D03*
X1415671Y883423D03*
X1413820Y880219D03*
X1426771Y883423D03*
X1419371D03*
X1413820Y893036D03*
X1421220Y899445D03*
X1419371Y896240D03*
X1424920Y899445D03*
X1426772Y896240D03*
X1417520Y899445D03*
X1421220Y893036D03*
X1423071Y896240D03*
X1428621Y893036D03*
X1424920Y886627D03*
X1417520D03*
X1443420Y867401D03*
X1436020D03*
X1445271Y857789D03*
X1439720Y860993D03*
X1437871Y857789D03*
X1432320Y860993D03*
X1430471Y857789D03*
X1443420Y854584D03*
X1441571Y857789D03*
X1436020Y854584D03*
X1434171Y857789D03*
X1445271Y870606D03*
X1439720Y873810D03*
X1437871Y870606D03*
X1432320Y873810D03*
X1430471Y870606D03*
X1441571D03*
X1434171D03*
X1445271Y883423D03*
X1443420Y880219D03*
X1437871Y883423D03*
X1436020Y880219D03*
X1430471Y883423D03*
X1441571D03*
X1434171D03*
X1430471Y896240D03*
X1436020Y893036D03*
X1437871Y896240D03*
X1441571D03*
X1432320Y899445D03*
X1434171Y896240D03*
X1439720Y899445D03*
X1443420Y893036D03*
X1439720Y886627D03*
X1432320D03*
X1460071Y857789D03*
X1454520Y860993D03*
X1452671Y857789D03*
X1447120Y860993D03*
X1458220Y854584D03*
X1456371Y857789D03*
X1450820Y854584D03*
X1448971Y857789D03*
X1458220Y893036D03*
X1460071Y896240D03*
X1447120Y886627D03*
X1460071Y915466D03*
Y934691D03*
Y953917D03*
Y973143D03*
X1460504Y1006093D03*
Y1025318D03*
Y1044544D03*
Y1063770D03*
Y1082995D03*
Y1121447D03*
X1456804Y1127856D03*
X1453104Y1121447D03*
X1449404Y1127856D03*
X1445704Y1121447D03*
X1458653Y1124651D03*
X1454953D03*
X1451253D03*
X1447553D03*
X1460504Y1134264D03*
X1458654Y1137469D03*
X1453104Y1134264D03*
X1451254Y1137469D03*
X1456803Y1140973D03*
X1454954Y1137469D03*
X1449403Y1140973D03*
X1467471Y857789D03*
X1461920Y860993D03*
X1476720D03*
X1474871Y857789D03*
X1471171D03*
X1465620Y854584D03*
X1463771Y857789D03*
X1473020Y854584D03*
X1469320Y860993D03*
X1476720Y899445D03*
X1461920D03*
X1469320D03*
Y893036D03*
X1473020D03*
X1461920D03*
X1467471Y896240D03*
X1463771D03*
X1471171D03*
X1461920Y912262D03*
X1463771Y909057D03*
X1469320Y912262D03*
X1467471Y909057D03*
X1476720Y912262D03*
X1474871Y909057D03*
Y902649D03*
X1463771D03*
X1467471D03*
X1463771Y915466D03*
X1476720Y905853D03*
X1471171Y915466D03*
X1473020Y905853D03*
X1467471Y915466D03*
X1476720Y931488D03*
X1474871Y921875D03*
X1476720Y918670D03*
X1474871Y928283D03*
X1473020Y925079D03*
X1476720D03*
X1467471Y921875D03*
X1469320Y918670D03*
X1461920Y931488D03*
X1467471Y928283D03*
X1469320Y931488D03*
X1463771Y928283D03*
Y921875D03*
X1461920Y918670D03*
X1474871Y947509D03*
Y941100D03*
X1476720Y937896D03*
X1473020Y944304D03*
X1476720D03*
X1463771Y947509D03*
X1467471D03*
X1463771Y941100D03*
X1461920Y937896D03*
X1467471Y941100D03*
X1469320Y937896D03*
X1463771Y934691D03*
X1471171D03*
X1467471D03*
X1476720Y950713D03*
X1463771Y966735D03*
X1467471D03*
X1474871D03*
X1473020Y963530D03*
X1461920Y950713D03*
X1469320D03*
X1467471Y960326D03*
X1469320Y957122D03*
X1463771Y960326D03*
X1461920Y957122D03*
X1476720D03*
X1474871Y960326D03*
X1471171Y953917D03*
X1463771D03*
X1467471D03*
X1463771Y979552D03*
X1461920Y976347D03*
X1467471Y979552D03*
X1469320Y976347D03*
X1476720Y982756D03*
X1473020D03*
X1474871Y979552D03*
X1476720Y976347D03*
X1471171Y973143D03*
X1463771D03*
X1467471D03*
X1461920Y969939D03*
X1469320D03*
X1476720D03*
X1477153Y1002888D03*
X1475304Y999684D03*
Y1012501D03*
X1477153Y1009297D03*
X1471604Y1006093D03*
X1462353Y1002888D03*
X1469753D03*
X1464204Y999684D03*
X1467904D03*
X1467903Y1012501D03*
X1469753Y1009297D03*
X1464204Y1012501D03*
X1462353Y1009297D03*
X1473453Y1015705D03*
X1475304Y1031727D03*
X1477153Y1028523D03*
Y1022114D03*
X1475304Y1018910D03*
X1464204Y1031727D03*
X1462353Y1028523D03*
X1467904Y1031727D03*
X1469753Y1028523D03*
X1462353Y1022114D03*
X1464204Y1018910D03*
X1469753Y1022114D03*
X1467904Y1018910D03*
X1464204Y1025318D03*
X1471604D03*
X1467904D03*
X1477153Y1041340D03*
X1475304Y1038136D03*
X1477153Y1047749D03*
Y1034931D03*
X1473453D03*
X1462353Y1047749D03*
X1469753D03*
X1462353Y1041340D03*
X1464204Y1038136D03*
X1469753Y1041340D03*
X1467904Y1038136D03*
X1464204Y1044544D03*
X1471604D03*
X1467904D03*
X1477153Y1060565D03*
X1475304Y1057361D03*
Y1050952D03*
X1477153Y1054157D03*
X1473453D03*
X1462353Y1060565D03*
X1464204Y1057361D03*
X1469753Y1060565D03*
X1467904Y1057361D03*
X1464204Y1050952D03*
X1467904D03*
X1464204Y1063770D03*
X1471604D03*
X1467904D03*
X1475304Y1070178D03*
X1477153Y1066974D03*
Y1079791D03*
X1475304Y1076587D03*
X1473453Y1073383D03*
X1477153D03*
X1462353Y1079791D03*
X1464204Y1076587D03*
X1469753Y1079791D03*
X1467904Y1076587D03*
X1464204Y1070178D03*
X1462353Y1066974D03*
X1467904Y1070178D03*
X1469753Y1066974D03*
X1467904Y1089404D03*
X1469753Y1086200D03*
X1475304Y1089404D03*
X1477153Y1086200D03*
X1464204Y1089404D03*
X1462353Y1086200D03*
X1473453Y1092608D03*
X1471604Y1082995D03*
X1477153Y1092608D03*
X1464204Y1082995D03*
X1467904D03*
X1464204Y1127856D03*
X1475304Y1121447D03*
X1471604Y1127856D03*
X1467904Y1121447D03*
X1466053Y1124651D03*
X1462353D03*
X1477153D03*
X1473453D03*
X1469753D03*
X1469754Y1137469D03*
X1464203Y1140973D03*
X1477154Y1137469D03*
X1471603Y1140973D03*
X1467904Y1134264D03*
X1466054Y1137469D03*
X1462354D03*
X1475304Y1134264D03*
X1473454Y1137469D03*
X1491520Y860993D03*
X1489671Y857789D03*
X1484120Y860993D03*
X1482271Y857789D03*
X1493371D03*
X1487820Y854584D03*
X1485971Y857789D03*
X1480420Y854584D03*
X1478571Y857789D03*
X1487820Y899445D03*
Y893036D03*
X1484120D03*
X1485971Y896240D03*
X1493371D03*
X1489671D03*
X1480420Y899445D03*
X1489671Y902649D03*
X1493371D03*
X1487820Y912262D03*
X1489671Y909057D03*
X1493371D03*
X1489671Y915466D03*
X1485971D03*
X1493371D03*
X1480420Y912262D03*
X1482271Y909057D03*
Y902649D03*
X1484120Y905853D03*
X1480420D03*
X1487820Y931488D03*
X1489671Y928283D03*
X1493371D03*
X1482271D03*
Y921875D03*
X1480420Y918670D03*
X1489671Y921875D03*
X1487820Y918670D03*
X1493371Y921875D03*
X1480420Y931488D03*
Y925079D03*
X1484120D03*
X1489671Y941100D03*
X1487820Y937896D03*
X1493371Y941100D03*
X1489671Y934691D03*
X1485971D03*
X1493371D03*
X1489671Y947509D03*
X1493371D03*
X1482271D03*
Y941100D03*
X1480420Y937896D03*
X1484120Y944304D03*
X1480420D03*
X1487820Y950713D03*
X1489671Y960326D03*
X1487820Y957122D03*
X1493371Y960326D03*
Y966735D03*
X1489671D03*
X1480420Y950713D03*
X1489671Y953917D03*
X1493371D03*
X1485971D03*
X1482271Y966735D03*
X1480420Y957122D03*
X1482271Y960326D03*
X1484120Y963530D03*
Y982756D03*
X1480420D03*
Y976347D03*
X1482271Y979552D03*
X1489671D03*
X1493371D03*
X1487820Y976347D03*
X1485971Y973143D03*
X1487820Y969939D03*
X1480420D03*
X1493804Y1006093D03*
X1490104D03*
X1486404D03*
X1493804Y1012501D03*
X1480853Y1002888D03*
X1482703Y999684D03*
X1490104Y1012501D03*
X1488253Y1009297D03*
X1482704Y1012501D03*
X1480853Y1009297D03*
X1493803Y999684D03*
X1488253Y1002888D03*
X1490104Y999684D03*
Y1031727D03*
X1488253Y1028523D03*
X1493804Y1031727D03*
X1488253Y1022114D03*
X1490104Y1018910D03*
X1493804D03*
X1490104Y1025318D03*
X1486404D03*
X1493804D03*
X1484553Y1015705D03*
X1482704Y1031727D03*
X1480853Y1028523D03*
Y1022114D03*
X1482704Y1018910D03*
X1480853Y1041340D03*
X1482704Y1038136D03*
X1488253Y1047749D03*
Y1041340D03*
X1490104Y1038136D03*
X1493804D03*
X1480853Y1047749D03*
X1486404Y1044544D03*
X1484553Y1034931D03*
X1490104Y1044544D03*
X1493804D03*
X1480853Y1034931D03*
X1488253Y1060565D03*
X1490104Y1057361D03*
X1493804D03*
X1486404Y1063770D03*
X1490104D03*
X1493804D03*
X1490104Y1050952D03*
X1493804D03*
X1480853Y1060565D03*
X1482704Y1057361D03*
Y1050952D03*
X1484553Y1054157D03*
X1480853D03*
X1493804Y1070178D03*
X1490104D03*
X1488253Y1066974D03*
X1480853Y1079791D03*
X1482704Y1076587D03*
Y1070178D03*
X1480853Y1066974D03*
X1488253Y1079791D03*
X1490104Y1076587D03*
X1493804D03*
X1484553Y1073383D03*
X1480853D03*
X1490104Y1089404D03*
X1488253Y1086200D03*
X1493804Y1089404D03*
X1490104Y1082995D03*
X1486404D03*
X1493804D03*
X1486404Y1095813D03*
X1482703D03*
X1482704Y1089404D03*
X1480853Y1086200D03*
X1484553Y1092608D03*
X1480853D03*
X1493804Y1102221D03*
X1491953Y1099017D03*
X1493804Y1127856D03*
X1490104Y1121447D03*
X1486404Y1127856D03*
X1482704Y1121447D03*
X1479004Y1127856D03*
X1491953Y1124651D03*
X1488253D03*
X1484553D03*
X1480853D03*
X1493803Y1140973D03*
X1490104Y1134264D03*
X1488254Y1137469D03*
X1482704Y1134264D03*
X1480854Y1137469D03*
X1491954D03*
X1486403Y1140973D03*
X1484554Y1137469D03*
X1479003Y1140973D03*
X1508171Y864197D03*
X1510021Y854584D03*
X1504471Y857789D03*
X1498920Y860993D03*
X1497071Y857789D03*
X1502620Y854584D03*
X1500771Y857789D03*
X1495220Y854584D03*
X1502621Y899445D03*
X1506320D03*
X1495220D03*
Y893036D03*
X1498920D03*
X1497071Y896240D03*
X1506321Y912262D03*
X1508171Y909057D03*
X1500771Y902649D03*
X1508171D03*
X1502621Y912262D03*
X1500771Y909057D03*
X1502621Y905853D03*
X1510021D03*
X1498920D03*
X1506321D03*
X1495220Y912262D03*
X1497071Y915466D03*
X1502621Y931488D03*
X1500771Y928283D03*
X1506321Y931488D03*
X1508171Y928283D03*
X1500771Y921875D03*
X1502621Y918670D03*
X1508171Y921875D03*
X1506321Y918670D03*
X1502621Y925079D03*
X1510021D03*
X1498920D03*
X1506321D03*
X1495220Y931488D03*
Y918670D03*
X1500771Y941100D03*
X1502621Y937896D03*
X1508171Y941100D03*
X1506321Y937896D03*
X1500771Y947509D03*
X1508171D03*
X1495220Y937896D03*
X1510021Y944304D03*
X1497071Y934691D03*
X1502621Y944304D03*
X1506320D03*
X1498920D03*
X1500771Y966735D03*
X1508171D03*
X1498920Y963530D03*
X1502621Y950713D03*
X1506320D03*
X1508171Y960326D03*
X1506320Y957122D03*
X1500771Y960326D03*
X1502621Y957122D03*
X1510021Y963530D03*
X1495220Y950713D03*
Y957122D03*
X1497071Y953917D03*
X1502621Y969939D03*
X1506321D03*
X1495220Y976347D03*
Y969939D03*
X1497071Y973143D03*
X1497504Y1006093D03*
X1501204Y1012501D03*
X1508603D03*
X1503053Y1009297D03*
X1506753D03*
X1495653D03*
X1495655Y1002888D03*
X1506753D03*
X1508603Y999684D03*
X1503053Y1002888D03*
X1501204Y999684D03*
X1499353Y1015705D03*
X1510453D03*
X1501204Y1031727D03*
X1503053Y1028523D03*
X1508603Y1031727D03*
X1506753Y1028523D03*
Y1022114D03*
X1508603Y1018910D03*
X1503053Y1022114D03*
X1501204Y1018910D03*
X1495653Y1028523D03*
Y1022114D03*
X1497504Y1025318D03*
X1503053Y1041340D03*
X1501204Y1038136D03*
X1506753Y1041340D03*
X1508603Y1038136D03*
X1503053Y1047749D03*
X1506753D03*
X1503053Y1034931D03*
X1510453D03*
X1499353D03*
X1506753D03*
X1495653Y1047749D03*
Y1041340D03*
X1497504Y1044544D03*
X1495653Y1060565D03*
X1503053D03*
X1501204Y1057361D03*
X1506753Y1060565D03*
X1508604Y1057361D03*
X1501203Y1050952D03*
X1508604Y1050953D03*
X1499353Y1054157D03*
X1497504Y1063770D03*
X1510453Y1054157D03*
X1503053D03*
X1506753D03*
Y1079791D03*
X1508604Y1076587D03*
X1501204Y1070178D03*
X1503053Y1066974D03*
X1508604Y1070178D03*
X1506753Y1066974D03*
X1503053Y1079791D03*
X1501204Y1076587D03*
X1499353Y1073383D03*
X1510453D03*
X1503053D03*
X1506753D03*
X1495653Y1066974D03*
Y1079791D03*
X1497504Y1095813D03*
X1508603D03*
X1501204D03*
Y1089404D03*
X1503053Y1086200D03*
X1508604Y1089404D03*
X1506753Y1086200D03*
X1503053Y1092608D03*
X1510452D03*
X1499353D03*
X1506753D03*
X1495653Y1086200D03*
X1497504Y1082995D03*
X1506753Y1099017D03*
X1503053Y1124651D03*
X1497504Y1121447D03*
X1501204Y1127856D03*
X1499353Y1124651D03*
X1495653D03*
X1508604Y1134264D03*
X1501203Y1140973D03*
X1499354Y1137469D03*
X1510454D03*
X1503054D03*
X1497504Y1134264D03*
X1495654Y1137469D03*
X1519271Y851380D03*
X1515571D03*
X1511871Y864197D03*
X1519270D03*
X1522970D03*
X1511871Y857789D03*
X1519271D03*
X1515571D03*
X1517421Y860993D03*
Y854584D03*
X1515571Y883423D03*
X1513720Y880219D03*
X1519271Y883423D03*
X1521121Y880219D03*
X1513720Y873810D03*
X1515571Y870606D03*
X1521121Y873810D03*
X1519271Y870606D03*
X1515570Y877014D03*
X1522970D03*
X1511871D03*
X1519271D03*
X1596941Y883924D03*
Y890617D03*
Y897310D03*
Y900656D03*
Y914042D03*
Y907349D03*
Y960892D03*
Y957546D03*
Y1185105D03*
Y1178412D03*
Y1191798D03*
Y1208530D03*
Y1201837D03*
Y1195144D03*
X1613083Y880577D03*
Y887270D03*
Y897310D03*
Y893963D03*
Y910696D03*
Y904003D03*
Y1175066D03*
Y1181759D03*
Y1191798D03*
Y1188451D03*
Y1205184D03*
Y1198491D03*
X1626641Y960892D03*
Y957546D03*
X1656441Y780184D03*
Y773491D03*
Y786877D03*
Y803609D03*
Y796916D03*
Y790223D03*
Y816995D03*
Y810302D03*
Y833727D03*
Y823688D03*
Y827034D03*
Y847113D03*
Y840420D03*
Y853806D03*
Y860499D03*
Y863845D03*
Y883924D03*
Y877231D03*
Y870538D03*
Y890617D03*
Y897310D03*
Y900656D03*
Y914042D03*
Y907349D03*
Y927428D03*
Y920735D03*
Y934121D03*
Y944160D03*
Y937467D03*
Y960892D03*
Y950853D03*
Y957546D03*
Y980971D03*
Y974278D03*
Y967585D03*
Y994357D03*
Y987664D03*
X1656141Y1027822D03*
X1656441Y1021129D03*
X1656141Y1047900D03*
Y1041207D03*
Y1034514D03*
Y1054593D03*
X1656441Y1074672D03*
Y1067979D03*
Y1091404D03*
Y1081365D03*
Y1084711D03*
Y1098097D03*
Y1111483D03*
Y1104790D03*
Y1128215D03*
Y1118176D03*
Y1121522D03*
Y1141601D03*
Y1134908D03*
Y1148294D03*
Y1154987D03*
Y1158333D03*
Y1171719D03*
Y1165026D03*
Y1185105D03*
Y1178412D03*
Y1191798D03*
Y1208530D03*
Y1201837D03*
Y1195144D03*
Y1221916D03*
Y1215223D03*
Y1238648D03*
Y1228609D03*
Y1231955D03*
Y1245341D03*
X1672583Y770144D03*
Y776837D03*
Y786877D03*
Y783530D03*
Y800263D03*
Y793570D03*
Y813648D03*
Y806955D03*
Y820341D03*
Y830381D03*
Y823688D03*
Y850459D03*
Y843766D03*
Y837074D03*
Y867192D03*
Y860499D03*
Y857152D03*
Y873885D03*
Y880577D03*
Y887270D03*
Y897310D03*
Y893963D03*
Y917389D03*
Y910696D03*
Y904003D03*
Y924081D03*
Y934121D03*
Y930774D03*
Y947507D03*
Y940814D03*
Y964239D03*
Y977625D03*
Y970932D03*
Y991011D03*
Y984318D03*
Y1021129D03*
Y1024475D03*
Y1031168D03*
X1672283Y1044554D03*
Y1037861D03*
X1672583Y1051247D03*
Y1071325D03*
Y1064633D03*
Y1078018D03*
Y1094751D03*
Y1088058D03*
Y1081365D03*
Y1108136D03*
Y1101444D03*
Y1124869D03*
Y1118176D03*
Y1114829D03*
Y1144947D03*
Y1138255D03*
Y1131562D03*
Y1161680D03*
Y1154987D03*
Y1151640D03*
Y1175066D03*
Y1168373D03*
Y1181758D03*
Y1191798D03*
Y1188451D03*
Y1205184D03*
Y1198491D03*
Y1218569D03*
Y1211877D03*
Y1225262D03*
Y1241995D03*
Y1235302D03*
Y1228609D03*
X1686041Y960892D03*
Y957546D03*
X1686141Y967585D03*
Y1054593D03*
X1702283Y964239D03*
Y1021129D03*
Y1024475D03*
Y1051247D03*
X1715841Y780184D03*
Y773491D03*
Y786877D03*
Y803609D03*
Y796916D03*
Y790223D03*
Y816995D03*
Y810302D03*
Y833727D03*
Y823688D03*
Y827034D03*
Y847113D03*
Y840420D03*
Y853806D03*
Y860499D03*
Y863845D03*
Y883924D03*
Y877231D03*
Y870538D03*
Y890617D03*
Y897310D03*
Y900656D03*
Y914042D03*
Y907349D03*
Y927428D03*
Y920735D03*
Y934121D03*
Y944160D03*
Y937467D03*
Y960892D03*
Y950853D03*
Y957546D03*
Y980971D03*
Y974278D03*
Y967585D03*
Y994357D03*
Y987664D03*
Y1027822D03*
Y1021129D03*
Y1047900D03*
Y1041207D03*
Y1034514D03*
Y1054593D03*
Y1074672D03*
Y1067979D03*
Y1091404D03*
Y1081365D03*
Y1084711D03*
Y1098097D03*
Y1111483D03*
Y1104790D03*
Y1128215D03*
Y1118176D03*
Y1121522D03*
Y1141601D03*
Y1134908D03*
Y1148294D03*
Y1154987D03*
Y1158333D03*
Y1171719D03*
Y1165026D03*
Y1185105D03*
Y1178412D03*
Y1191798D03*
Y1208530D03*
Y1201837D03*
Y1195144D03*
Y1221916D03*
Y1215223D03*
Y1238648D03*
Y1228609D03*
Y1231955D03*
Y1245341D03*
X1731983Y770144D03*
Y776837D03*
Y786877D03*
Y783530D03*
Y800263D03*
Y793570D03*
Y813648D03*
Y806955D03*
Y820341D03*
Y830381D03*
Y823688D03*
Y850459D03*
Y843766D03*
Y837074D03*
Y867192D03*
Y860499D03*
Y857152D03*
Y873885D03*
Y880577D03*
Y887270D03*
Y897310D03*
Y893963D03*
Y917389D03*
Y910696D03*
Y904003D03*
Y924081D03*
Y934121D03*
Y930774D03*
Y947507D03*
Y940814D03*
Y964239D03*
Y977625D03*
X1731883Y970932D03*
X1731983Y991011D03*
Y984318D03*
Y1021129D03*
Y1024475D03*
Y1031168D03*
X1731683Y1044554D03*
Y1037861D03*
X1731983Y1051247D03*
X1731818Y1071326D03*
X1731883Y1064633D03*
X1731983Y1078018D03*
Y1094751D03*
Y1088058D03*
Y1081365D03*
X1731818Y1108137D03*
X1731983Y1101444D03*
Y1124869D03*
Y1118176D03*
Y1114829D03*
Y1144947D03*
Y1138255D03*
Y1131562D03*
Y1161680D03*
Y1154987D03*
Y1151640D03*
Y1175066D03*
Y1168373D03*
X1731818Y1181759D03*
X1731983Y1191798D03*
X1731818Y1188452D03*
X1731983Y1205184D03*
Y1198491D03*
Y1218569D03*
Y1211877D03*
Y1225262D03*
Y1241995D03*
Y1235302D03*
Y1228609D03*
X1745541Y960892D03*
Y957546D03*
Y967585D03*
Y1054593D03*
X1761683Y964239D03*
Y1021129D03*
Y1024475D03*
Y1051247D03*
X1775241Y780184D03*
Y773491D03*
Y786877D03*
Y803609D03*
Y796916D03*
Y790223D03*
Y816995D03*
Y810302D03*
Y833727D03*
Y823688D03*
Y827034D03*
Y847113D03*
Y840420D03*
Y853806D03*
Y860499D03*
Y863845D03*
Y883924D03*
Y877231D03*
Y870538D03*
Y890617D03*
Y897310D03*
Y900656D03*
Y914042D03*
Y907349D03*
Y927428D03*
Y920735D03*
Y934121D03*
Y944160D03*
Y937467D03*
Y960892D03*
Y950853D03*
Y957546D03*
Y980971D03*
Y974278D03*
Y967585D03*
Y994357D03*
Y987664D03*
Y1027822D03*
Y1021129D03*
Y1047900D03*
Y1041207D03*
Y1034515D03*
Y1054593D03*
Y1074672D03*
Y1067979D03*
Y1091404D03*
Y1081365D03*
Y1084711D03*
Y1098097D03*
Y1111483D03*
Y1104790D03*
Y1128215D03*
Y1118176D03*
Y1121522D03*
Y1141601D03*
Y1134908D03*
Y1148294D03*
Y1154987D03*
Y1158333D03*
Y1171719D03*
Y1165026D03*
Y1185105D03*
Y1178412D03*
Y1191798D03*
Y1208530D03*
Y1201837D03*
Y1195144D03*
Y1221916D03*
Y1215223D03*
Y1238648D03*
Y1228609D03*
Y1231955D03*
Y1245341D03*
X1791383Y770144D03*
Y776837D03*
Y786877D03*
Y783530D03*
Y800263D03*
Y793570D03*
Y813648D03*
Y806955D03*
Y820341D03*
Y830381D03*
Y823688D03*
Y850459D03*
Y843766D03*
Y837074D03*
Y867192D03*
Y860499D03*
Y857152D03*
Y873885D03*
Y880577D03*
Y887270D03*
Y897310D03*
Y893963D03*
Y917389D03*
Y910696D03*
Y904003D03*
Y924081D03*
Y934121D03*
Y930774D03*
Y947507D03*
Y940814D03*
Y964239D03*
Y977625D03*
Y970932D03*
Y991011D03*
Y984318D03*
Y1021129D03*
Y1024475D03*
Y1031168D03*
Y1044554D03*
Y1037861D03*
X1791083Y1051247D03*
X1791383Y1071325D03*
Y1064633D03*
Y1078018D03*
Y1094751D03*
Y1088058D03*
Y1081365D03*
Y1108136D03*
Y1101444D03*
Y1124869D03*
Y1118176D03*
Y1114829D03*
Y1144947D03*
Y1138255D03*
Y1131562D03*
Y1161680D03*
Y1154987D03*
Y1151640D03*
Y1175066D03*
Y1168373D03*
Y1181758D03*
Y1191798D03*
Y1188451D03*
Y1205184D03*
Y1198491D03*
Y1218570D03*
Y1211877D03*
Y1225263D03*
Y1241995D03*
Y1235302D03*
Y1228609D03*
X1804941Y960892D03*
Y957546D03*
Y967585D03*
Y1054593D03*
X1821083Y964239D03*
Y1021129D03*
Y1024475D03*
Y1051247D03*
G54D49*
X676508Y145866D03*
G54D35*
X238780Y1643661D03*
X230906Y1649173D03*
X238780Y1653110D03*
Y1657834D03*
X230906Y1653897D03*
Y1663346D03*
X238780Y1667283D03*
Y1672007D03*
X230906Y1668070D03*
X238780Y1723976D03*
Y1728700D03*
X230906Y1720039D03*
Y1724763D03*
Y1734212D03*
X254528Y1643661D03*
X246654Y1649173D03*
X254528Y1653110D03*
Y1657834D03*
X246654Y1653897D03*
Y1663346D03*
X254528Y1667283D03*
Y1672007D03*
X246654Y1668070D03*
X254528Y1723976D03*
Y1728700D03*
X246654Y1720039D03*
Y1724763D03*
Y1734212D03*
X270276Y1643661D03*
X262402Y1649173D03*
X270276Y1653110D03*
Y1657834D03*
X262402Y1653897D03*
Y1663346D03*
X270276Y1667283D03*
Y1672007D03*
X262402Y1668070D03*
X270276Y1723976D03*
Y1728700D03*
X262402Y1720039D03*
Y1724763D03*
Y1734212D03*
X286024Y1643661D03*
X278150Y1649173D03*
X286024Y1653110D03*
Y1657834D03*
X278150Y1653897D03*
Y1663346D03*
X286024Y1667283D03*
Y1672007D03*
X278150Y1668070D03*
X286024Y1723976D03*
Y1728700D03*
X278150Y1720039D03*
Y1724763D03*
Y1734212D03*
X305709Y1672007D03*
X297835Y1720039D03*
Y1724763D03*
X305709Y1723976D03*
Y1728700D03*
X297835Y1734212D03*
X321457Y1672007D03*
X313583Y1720039D03*
Y1724763D03*
X321457Y1723976D03*
Y1728700D03*
X313583Y1734212D03*
X337205Y1672007D03*
X329331Y1720039D03*
Y1724763D03*
X337205Y1723976D03*
Y1728700D03*
X329331Y1734212D03*
X352953Y1672007D03*
X345079Y1720039D03*
Y1724763D03*
X352953Y1723976D03*
Y1728700D03*
X345079Y1734212D03*
X495079Y1705866D03*
Y1710590D03*
Y1734212D03*
X502953Y1672007D03*
X510827Y1705866D03*
X502953Y1709803D03*
X510827Y1710590D03*
X502953Y1714527D03*
X510827Y1734212D03*
X518701Y1672007D03*
X534449D03*
X526575Y1705866D03*
X518701Y1709803D03*
X526575Y1710590D03*
X534449Y1709803D03*
X518701Y1714527D03*
X534449D03*
X526575Y1734212D03*
X550197Y1672007D03*
X542323Y1705866D03*
Y1710590D03*
X550197Y1709803D03*
Y1714527D03*
X542323Y1734212D03*
X562008Y1705866D03*
Y1710590D03*
Y1734212D03*
X569882Y1672007D03*
X577756Y1705866D03*
X569882Y1709803D03*
X577756Y1710590D03*
X569882Y1714527D03*
X577756Y1734212D03*
X585630Y1672007D03*
X593504Y1705866D03*
X585630Y1709803D03*
X593504Y1710590D03*
X585630Y1714527D03*
X593504Y1734212D03*
X601378Y1672007D03*
X609252Y1705866D03*
X601378Y1709803D03*
X609252Y1710590D03*
X601378Y1714527D03*
X609252Y1734212D03*
X617126Y1672007D03*
Y1709803D03*
Y1714527D03*
X1246654Y1672007D03*
X1238780Y1720039D03*
Y1724763D03*
X1246654Y1723976D03*
Y1728700D03*
X1238780Y1734212D03*
X1262402Y1672007D03*
X1254528Y1720039D03*
Y1724763D03*
X1262402Y1723976D03*
Y1728700D03*
X1254528Y1734212D03*
X1278150Y1672007D03*
X1270276Y1720039D03*
Y1724763D03*
X1278150Y1723976D03*
Y1728700D03*
X1270276Y1734212D03*
X1293898Y1672007D03*
X1286024Y1720039D03*
Y1724763D03*
X1293898Y1723976D03*
Y1728700D03*
X1286024Y1734212D03*
X1313583Y1672007D03*
X1305709Y1720039D03*
Y1724763D03*
X1313583Y1723976D03*
Y1728700D03*
X1305709Y1734212D03*
X1329331Y1672007D03*
X1321457Y1720039D03*
Y1724763D03*
X1329331Y1723976D03*
Y1728700D03*
X1321457Y1734212D03*
X1345079Y1672007D03*
X1337205Y1720039D03*
Y1724763D03*
X1345079Y1723976D03*
Y1728700D03*
X1337205Y1734212D03*
X1360827Y1672007D03*
X1352953Y1720039D03*
Y1724763D03*
X1360827Y1723976D03*
Y1728700D03*
X1352953Y1734212D03*
X1510827Y1672007D03*
X1502953Y1705866D03*
Y1710590D03*
X1510827Y1709803D03*
Y1714527D03*
X1502953Y1734212D03*
X1526575Y1672007D03*
X1518701Y1705866D03*
Y1710590D03*
X1526575Y1709803D03*
Y1714527D03*
X1518701Y1734212D03*
X1542323Y1672007D03*
X1534449Y1705866D03*
Y1710590D03*
X1542323Y1709803D03*
Y1714527D03*
X1534449Y1734212D03*
X1558071Y1672007D03*
X1550197Y1705866D03*
Y1710590D03*
X1558071Y1709803D03*
Y1714527D03*
X1550197Y1734212D03*
X1569882Y1705866D03*
Y1710590D03*
Y1734212D03*
X1577756Y1672007D03*
X1585630Y1705866D03*
X1577756Y1709803D03*
X1585630Y1710590D03*
X1577756Y1714527D03*
X1585630Y1734212D03*
X1593504Y1672007D03*
X1601378Y1705866D03*
X1593504Y1709803D03*
X1601378Y1710590D03*
X1593504Y1714527D03*
X1601378Y1734212D03*
X1609252Y1672007D03*
X1617126Y1705866D03*
X1609252Y1709803D03*
X1617126Y1710590D03*
X1609252Y1714527D03*
X1617126Y1734212D03*
X1625000Y1672007D03*
Y1709803D03*
Y1714527D03*
G54D76*
X1886720Y1001463D03*
X1876720D03*
X1875836Y1303980D03*
X1885836D03*
X1886211Y1364167D03*
X1876211D03*
X1876165Y1669023D03*
X1886165D03*
X1897608Y1001506D03*
X1898086Y1305044D03*
X1897682Y1364479D03*
X1897402Y1670072D03*
X1907608Y1001506D03*
X1908086Y1305044D03*
X1907682Y1364479D03*
X1907402Y1670072D03*
X1935200Y1362732D03*
X1925200D03*
X1924695Y1670036D03*
X1934695D03*
X1946178Y1362781D03*
X1945484Y1670313D03*
X1967697Y1362790D03*
X1956178Y1362781D03*
X1966555Y1669946D03*
X1955484Y1670313D03*
X1977697Y1362790D03*
X1976555Y1669946D03*
X1988618Y1363081D03*
X1998618D03*
X1998147Y1669691D03*
X1988147D03*
G54D22*
X45812Y451602D03*
X61157Y69340D03*
X61470Y84622D03*
X62812Y412708D03*
X62813Y415750D03*
X49212Y451602D03*
X78269Y26474D03*
X74869D03*
X64557Y69340D03*
X72157Y75340D03*
X75557D03*
X64870Y84622D03*
X78120Y1515436D03*
Y1518836D03*
X77618Y1572504D03*
X74218D03*
X64410Y1599102D03*
Y1602502D03*
X85374Y19538D03*
X81974D03*
X92442Y26474D03*
X89042D03*
X86557Y69340D03*
X83157D03*
X94157Y75340D03*
X90998Y1518937D03*
Y1515537D03*
X99547Y19538D03*
X110320D03*
X96147D03*
X106615Y26474D03*
X103215D03*
X108557Y69340D03*
X105157D03*
X97557Y75340D03*
X113720Y19538D03*
X127894D03*
X124494D03*
X120789Y26474D03*
X117389D03*
X127157Y69340D03*
X116157Y75340D03*
X119557D03*
X130557Y69340D03*
X138157Y75340D03*
X141557D03*
X160360Y19538D03*
X156655Y26474D03*
X153255D03*
X152557Y69340D03*
X149157D03*
X163760Y19538D03*
X174533D03*
X170828Y26474D03*
X167428D03*
X175761Y69340D03*
X172361D03*
X161361Y75340D03*
X164761D03*
X167266Y1569968D03*
X170666D03*
X177933Y19538D03*
X183361Y75340D03*
X186761D03*
X188897Y1590094D03*
X192297D03*
X207894Y19538D03*
X204494D03*
X200789Y26474D03*
X197389D03*
X197761Y69340D03*
X194361D03*
X205495Y75340D03*
X208895D03*
X200957Y1590094D03*
X204357D03*
X194197Y1614292D03*
X197597D03*
X206257D03*
X194197Y1602380D03*
X197597D03*
X206257D03*
X222067Y19538D03*
X218667D03*
X214962Y26474D03*
X211562D03*
X219895Y69340D03*
X216495D03*
X225077Y1590094D03*
X213017D03*
X216417D03*
X209657Y1614292D03*
X218317D03*
X221717D03*
X209657Y1602380D03*
X218317D03*
X221717D03*
X227495Y75340D03*
X230895D03*
X237137Y1590094D03*
X240537D03*
X228477D03*
X230377Y1614292D03*
X233777D03*
X230377Y1602380D03*
X233777D03*
X249197Y1590094D03*
X252597D03*
X242437Y1614292D03*
X254497D03*
X245837D03*
X242437Y1602380D03*
X254497D03*
X245837D03*
X273317Y1590094D03*
X261257D03*
X264657D03*
X266557Y1614292D03*
X257897D03*
X269957D03*
X266557Y1602380D03*
X257897D03*
X269957D03*
X285377Y1590094D03*
X288777D03*
X276717D03*
X278617Y1614292D03*
X282017D03*
X278617Y1602380D03*
X282017D03*
X297437Y1590094D03*
X300837D03*
X290677Y1614292D03*
X302737D03*
X294077D03*
X306137D03*
X290677Y1602380D03*
X302737D03*
X294077D03*
X306137D03*
X321557Y1590094D03*
X309497D03*
X312897D03*
X314797Y1614292D03*
X318197D03*
X314797Y1602380D03*
X318197D03*
X333617Y1590094D03*
X337017D03*
X324957D03*
X330257Y1614292D03*
X338917D03*
X326857D03*
X330257Y1602380D03*
X338917D03*
X326857D03*
X345677Y1590094D03*
X349077D03*
X350977Y1614292D03*
X342317D03*
X354377D03*
X350977Y1602380D03*
X342317D03*
X354377D03*
X369797Y1590094D03*
X357737D03*
X361137D03*
X363037Y1614292D03*
X366437D03*
X363037Y1602380D03*
X366437D03*
X373197Y1590094D03*
X375097Y1614292D03*
X378497D03*
X375097Y1602380D03*
X378497D03*
X476451Y1590094D03*
X485111D03*
X473051D03*
X478351Y1614292D03*
X481751D03*
X478351Y1602380D03*
X481751D03*
X500571Y1590094D03*
X488511D03*
X497171D03*
X490411Y1614292D03*
X493811D03*
X490411Y1602380D03*
X493811D03*
X512631Y1590094D03*
X509231D03*
X514531Y1614292D03*
X502471D03*
X517931D03*
X505871D03*
X514531Y1602380D03*
X502471D03*
X517931D03*
X505871D03*
X519764Y40328D03*
X523164D03*
X519742Y71436D03*
X523142D03*
X524691Y1590094D03*
X533351D03*
X521291D03*
X526591Y1614292D03*
X529991D03*
X526591Y1602380D03*
X529991D03*
X536751Y1590094D03*
X548811D03*
X545411D03*
X538651Y1614292D03*
X542051D03*
X538651Y1602380D03*
X542051D03*
X555175Y71436D03*
X558575D03*
X560871Y1590094D03*
X557471D03*
X562771Y1614292D03*
X550711D03*
X566171D03*
X554111D03*
X562771Y1602380D03*
X550711D03*
X566171D03*
X554111D03*
X572931Y1590094D03*
X581591D03*
X569531D03*
X574831Y1614292D03*
X578231D03*
X574831Y1602380D03*
X578231D03*
X597051Y1590094D03*
X584991D03*
X593651D03*
X598951Y1614292D03*
X586891D03*
X590291D03*
X598951Y1602380D03*
X586891D03*
X590291D03*
X613970Y188752D03*
X609111Y1590094D03*
X605711D03*
X611011Y1614292D03*
X614411D03*
X602351D03*
X611011Y1602380D03*
X614411D03*
X602351D03*
X617370Y188752D03*
X630040D03*
X626640D03*
X621171Y1590094D03*
X629831D03*
X617771D03*
X623071Y1614292D03*
X626471D03*
X623071Y1602380D03*
X626471D03*
X645291Y1590094D03*
X633231D03*
X641891D03*
X647191Y1614292D03*
X635131D03*
X638531D03*
X647191Y1602380D03*
X635131D03*
X638531D03*
X656439Y47264D03*
X659839D03*
X657351Y1590094D03*
X653951D03*
X662651Y1614292D03*
X659251D03*
X650591D03*
X662651Y1602380D03*
X659251D03*
X650591D03*
X723041Y-13200D03*
Y-9800D03*
X840001Y20200D03*
Y16800D03*
X902350Y208294D03*
X907470Y211980D03*
X902350Y204894D03*
X907470Y215380D03*
X902350Y219068D03*
X907470Y226154D03*
X902350Y222468D03*
X907470Y229554D03*
X953970Y208275D03*
X947496Y215397D03*
X953970Y204875D03*
X947496Y211997D03*
X957156Y227163D03*
X947496Y226135D03*
X957156Y230563D03*
X947496Y229535D03*
X980899Y-13200D03*
Y-9800D03*
Y20200D03*
Y16800D03*
X1032433Y-29811D03*
Y-33211D03*
Y-23211D03*
Y-19811D03*
Y-13211D03*
Y-9811D03*
Y-3211D03*
Y189D03*
X1156770Y638192D03*
X1153370D03*
X1161860Y642112D03*
X1165260D03*
X1173220Y636052D03*
X1169820D03*
X1183360Y642062D03*
X1186760D03*
X1196772Y1578182D03*
X1200172D03*
X1196772Y1590094D03*
X1200172D03*
X1212232Y1578182D03*
X1208832D03*
X1212232Y1590094D03*
X1208832D03*
X1214132Y1614292D03*
X1202072D03*
X1217532D03*
X1205472D03*
X1220892Y1578182D03*
X1232952D03*
X1224292D03*
X1220892Y1590094D03*
X1232952D03*
X1224292D03*
X1226192Y1614292D03*
X1229592D03*
X1245012Y1578182D03*
X1236352D03*
X1248412D03*
X1245012Y1590094D03*
X1236352D03*
X1248412D03*
X1238252Y1614292D03*
X1241652D03*
X1257072Y1578182D03*
X1260472D03*
X1257072Y1590094D03*
X1260472D03*
X1262372Y1614292D03*
X1250312D03*
X1265772D03*
X1253712D03*
X1269132Y1578182D03*
X1281192D03*
X1272532D03*
X1269132Y1590094D03*
X1281192D03*
X1272532D03*
X1274432Y1614292D03*
X1277832D03*
X1290291Y-29811D03*
Y-33211D03*
Y-23211D03*
Y-19811D03*
Y-13211D03*
Y-9811D03*
Y-3211D03*
Y189D03*
X1293252Y1578182D03*
X1284592D03*
X1296652D03*
X1293252Y1590094D03*
X1284592D03*
X1296652D03*
X1298552Y1614292D03*
X1286492D03*
X1289892D03*
X1305312Y1578182D03*
X1308712D03*
X1305312Y1590094D03*
X1308712D03*
X1310612Y1614292D03*
X1314012D03*
X1301952D03*
X1317372Y1578182D03*
X1320772D03*
X1329432D03*
X1317372Y1590094D03*
X1320772D03*
X1329432D03*
X1322672Y1614292D03*
X1326072D03*
X1341752Y-29811D03*
Y-33211D03*
Y-19811D03*
Y-23211D03*
Y-9811D03*
Y-13211D03*
Y189D03*
Y-3211D03*
X1344684Y280259D03*
X1332832Y1578182D03*
X1341492D03*
X1344892D03*
X1332832Y1590094D03*
X1341492D03*
X1344892D03*
X1346792Y1614292D03*
X1334732D03*
X1338132D03*
X1348084Y280259D03*
X1358624Y284644D03*
X1355224D03*
X1353552Y1578182D03*
X1356952D03*
X1353552Y1590094D03*
X1356952D03*
X1358852Y1614292D03*
X1362252D03*
X1350192D03*
X1380522Y260236D03*
Y263636D03*
X1368524Y282744D03*
X1365124D03*
X1378306Y657608D03*
X1374668Y659708D03*
X1378306Y669608D03*
X1374668Y671708D03*
Y683708D03*
X1378306Y681608D03*
X1374668Y695708D03*
X1378306Y693608D03*
Y705608D03*
X1374668Y707708D03*
Y719708D03*
X1378306Y717608D03*
X1365612Y1578182D03*
X1377672D03*
X1369012D03*
X1365612Y1590094D03*
X1377672D03*
X1369012D03*
X1370912Y1614292D03*
X1374312D03*
X1384002Y197668D03*
X1389256D03*
X1380602D03*
X1392656D03*
X1380638Y245694D03*
X1386630Y238651D03*
X1380638Y249094D03*
X1386630Y242051D03*
X1388754Y253803D03*
Y257203D03*
X1386273Y268670D03*
Y272070D03*
X1393206Y664708D03*
X1389568Y662608D03*
X1393206Y679208D03*
X1389568Y677108D03*
X1393206Y693708D03*
X1389568Y691608D03*
Y706108D03*
X1393206Y708208D03*
X1393199Y722708D03*
X1389561Y720608D03*
X1385338Y735098D03*
X1388976Y737198D03*
X1381072Y1578182D03*
Y1590094D03*
X1382972Y1614292D03*
X1386372D03*
X1412284Y171696D03*
X1398006Y197668D03*
X1406786D03*
X1401406D03*
X1410186D03*
X1407420Y220018D03*
X1410820D03*
X1404385Y240929D03*
X1400985D03*
X1415684Y171696D03*
X1436060Y220018D03*
X1432660D03*
X1457176Y656992D03*
X1460814Y654892D03*
Y666892D03*
X1457176Y668992D03*
X1460814Y678892D03*
X1457176Y680992D03*
X1460814Y690892D03*
X1457176Y704992D03*
Y692992D03*
X1460814Y702892D03*
X1457176Y716992D03*
X1460814Y714892D03*
X1472076Y657392D03*
Y671892D03*
X1475714Y659492D03*
Y673992D03*
X1472076Y686392D03*
X1475714Y688492D03*
X1472076Y700892D03*
X1475714Y702992D03*
X1472076Y715392D03*
X1475714Y717492D03*
X1468876Y728392D03*
X1472514Y730492D03*
X1477755Y1590094D03*
X1462295D03*
X1474355D03*
X1465695D03*
X1467595Y1614292D03*
X1470995D03*
X1467595Y1602380D03*
X1470995D03*
X1482650Y-29811D03*
Y-33211D03*
Y-19811D03*
Y-23211D03*
Y-9811D03*
Y-13211D03*
Y189D03*
Y-3211D03*
X1489815Y1590094D03*
X1486415D03*
X1491715Y1614292D03*
X1479655D03*
X1483055D03*
X1491715Y1602380D03*
X1479655D03*
X1483055D03*
X1501875Y1590094D03*
X1498475D03*
X1503775Y1614292D03*
X1507175D03*
X1495115D03*
X1503775Y1602380D03*
X1507175D03*
X1495115D03*
X1525995Y1590094D03*
X1513935D03*
X1522595D03*
X1510535D03*
X1515835Y1614292D03*
X1519235D03*
X1515835Y1602380D03*
X1519235D03*
X1538996Y69297D03*
X1535596D03*
X1538055Y1590094D03*
X1534655D03*
X1527895Y1614292D03*
X1539955D03*
X1531295D03*
X1527895Y1602380D03*
X1539955D03*
X1531295D03*
X1556413Y19495D03*
X1549308Y26431D03*
X1552708D03*
X1557596Y69297D03*
X1546596Y75297D03*
X1549996D03*
X1550115Y1590094D03*
X1558775D03*
X1546715D03*
X1552015Y1614292D03*
X1555415D03*
X1543355D03*
X1552015Y1602380D03*
X1555415D03*
X1543355D03*
X1570586Y19495D03*
X1573986D03*
X1559813D03*
X1563481Y26431D03*
X1566881D03*
X1560996Y69297D03*
X1568596Y75297D03*
X1571996D03*
X1574235Y1590094D03*
X1562175D03*
X1570835D03*
X1564075Y1614292D03*
X1567475D03*
X1564075Y1602380D03*
X1567475D03*
X1584759Y19495D03*
X1588159D03*
X1577654Y26431D03*
X1591828D03*
X1581054D03*
X1582996Y69297D03*
X1579596D03*
X1590596Y75297D03*
X1586295Y1590094D03*
X1582895D03*
X1588195Y1614292D03*
X1576135D03*
X1591595D03*
X1579535D03*
X1588195Y1602380D03*
X1576135D03*
X1591595D03*
X1579535D03*
X1598933Y19495D03*
X1602333D03*
X1595228Y26431D03*
X1604996Y69297D03*
X1601596D03*
X1593996Y75297D03*
X1598355Y1590094D03*
X1607015D03*
X1594955D03*
X1600255Y1614292D03*
X1603655D03*
X1600255Y1602380D03*
X1603655D03*
X1623596Y69297D03*
X1612596Y75297D03*
X1615996D03*
X1622475Y1590094D03*
X1610415D03*
X1619075D03*
X1612315Y1614292D03*
X1615715D03*
X1612315Y1602380D03*
X1615715D03*
X1634799Y19495D03*
X1638199D03*
X1627694Y26431D03*
X1631094D03*
X1626996Y69297D03*
X1635800Y75297D03*
X1639200D03*
X1634535Y1590094D03*
X1631135D03*
X1636435Y1614292D03*
X1624375D03*
X1639835D03*
X1627775D03*
X1636435Y1602380D03*
X1624375D03*
X1639835D03*
X1627775D03*
X1648972Y19495D03*
X1652372D03*
X1641867Y26431D03*
X1645267D03*
X1650200Y69297D03*
X1646800D03*
X1646595Y1590094D03*
X1643195D03*
X1651895Y1614292D03*
X1648495D03*
X1651895Y1602380D03*
X1648495D03*
X1671828Y26431D03*
X1672200Y69297D03*
X1668800D03*
X1657800Y75297D03*
X1661200D03*
X1678933Y19495D03*
X1682333D03*
X1686001Y26431D03*
X1689401D03*
X1675228D03*
X1679934Y75297D03*
X1683334D03*
X1696506Y19495D03*
X1693106D03*
X1694334Y69297D03*
X1690934D03*
X1705334Y75297D03*
X1701934D03*
G54D41*
X338042Y849978D03*
X331284Y978814D03*
X338211Y1118243D03*
Y1131060D03*
X345178Y854584D03*
X348879Y860993D03*
X350729Y870606D03*
X354429D03*
X352578Y873810D03*
X354429Y883423D03*
X348879Y873810D03*
X347029Y877014D03*
X348878Y880219D03*
X343761Y999684D03*
X349311Y1105426D03*
X351162Y1127856D03*
X353011Y1118243D03*
X354861Y1121447D03*
X347461Y1134264D03*
X354861D03*
X356278Y848176D03*
X371078D03*
X363678D03*
X371078Y867401D03*
X356278D03*
X363678D03*
X356278Y860993D03*
X371078D03*
X363678D03*
X358129Y870606D03*
X361829D03*
X365529D03*
X359978Y873810D03*
X367378D03*
X369229Y870606D03*
X356278Y880219D03*
X358129Y883423D03*
X363678Y880219D03*
X365529Y883423D03*
X371078Y880219D03*
X361829Y883423D03*
X369229D03*
X371078Y873810D03*
X356278D03*
X363678D03*
X363679Y893036D03*
X367379D03*
X359978Y886627D03*
X367378D03*
X363678D03*
X371078D03*
X367811Y1002888D03*
Y1105426D03*
X369661Y1102221D03*
X358562D03*
X360412Y1105426D03*
X369662Y1121447D03*
X362261D03*
X369662Y1134264D03*
X362262D03*
X385878Y848176D03*
X378478D03*
Y867401D03*
X385878D03*
X378478Y860993D03*
X385878D03*
X387729Y870606D03*
X372929D03*
X380329D03*
X374778Y873810D03*
X376629Y870606D03*
X382178Y873810D03*
X384029Y870606D03*
X372929Y883423D03*
X378478Y880219D03*
X380329Y883423D03*
X385878Y880219D03*
X387729Y883423D03*
X376629D03*
X384029D03*
X378478Y873810D03*
X385878D03*
X374778Y886627D03*
X382178D03*
X378478D03*
X385878D03*
X375211Y1099017D03*
X380762Y1095813D03*
X382611Y1099017D03*
X384462Y1121447D03*
X377062D03*
X384462Y1134264D03*
X377062D03*
X400678Y848176D03*
X393278D03*
X400678Y867401D03*
X393278D03*
X400678Y860993D03*
X393278D03*
X391429Y870606D03*
X395129D03*
X402529D03*
X389578Y873810D03*
X396978D03*
X398829Y870606D03*
X393278Y880219D03*
X395129Y883423D03*
X400678Y880219D03*
X402529Y883423D03*
X391429D03*
X398829D03*
X393278Y873810D03*
X400678D03*
X402529Y896240D03*
X400678Y899445D03*
X393279Y893036D03*
X396979D03*
X396978Y886627D03*
X389578D03*
X398829Y896240D03*
X400678Y893036D03*
X393278Y886627D03*
X400678D03*
X404378Y899445D03*
X400678Y905853D03*
X402529Y915466D03*
Y909057D03*
X406229Y915466D03*
X400678Y912262D03*
X402529Y902649D03*
X400678Y931488D03*
X402529Y928283D03*
Y921875D03*
X398829Y934691D03*
X402529D03*
Y941100D03*
X400679Y944304D03*
X402529Y947509D03*
Y966735D03*
Y960326D03*
X398829Y953917D03*
X402529D03*
X400680Y950713D03*
X399262Y1006093D03*
X402962D03*
X399262Y999684D03*
X402962D03*
X401111Y1009297D03*
X402962Y1012501D03*
Y1031727D03*
X401111Y1028523D03*
Y1022114D03*
X402960Y1018910D03*
X402962Y1025318D03*
X399262D03*
X401111Y1015705D03*
Y1047749D03*
X399262Y1044544D03*
X402962D03*
X401111Y1041340D03*
X402962Y1038136D03*
X406662Y1057361D03*
X402962D03*
Y1063770D03*
X401113Y1060565D03*
X399262Y1063770D03*
X401111Y1054157D03*
X402962Y1050952D03*
Y1076587D03*
Y1070178D03*
X401112Y1066974D03*
X399262Y1082995D03*
X391862Y1102221D03*
X393711Y1105426D03*
X391862Y1121447D03*
X399262D03*
X391862Y1134264D03*
X399262D03*
X408078Y848176D03*
X415478D03*
X408078Y867401D03*
X415478Y860993D03*
X408078D03*
X404378Y873810D03*
X406229Y870606D03*
X408078Y880219D03*
X409929Y883423D03*
X406229D03*
X415478Y873810D03*
X408078D03*
X404378Y886627D03*
X411778D03*
X404378Y893036D03*
X415478Y886627D03*
X408078D03*
X406229Y896240D03*
X408078Y899445D03*
X415478D03*
X409929Y896240D03*
X415478Y893036D03*
X417329Y896240D03*
X422878Y893036D03*
X411778Y899445D03*
X413629Y896240D03*
X419178Y899445D03*
X422878Y912262D03*
X417329Y909057D03*
X406229D03*
X413629D03*
Y915466D03*
X411778Y905853D03*
X408078D03*
Y912262D03*
X406229Y902649D03*
X415478Y905853D03*
X411778Y912262D03*
X415478D03*
X417329Y915466D03*
X411779Y918670D03*
X406229Y921875D03*
X408078Y918670D03*
X408569Y929108D03*
X406308Y928626D03*
X417329Y921875D03*
X411872Y925264D03*
X415479Y918670D03*
X407589Y942164D03*
X405289D03*
X409889D03*
X415185Y956620D03*
X411685D03*
X409385D03*
X417685D03*
X404785Y971100D03*
X407085D03*
X409385D03*
X411685D03*
X420205D03*
X412365Y985610D03*
X410065D03*
X420145Y985550D03*
X409385Y1014540D03*
X407085D03*
X411685D03*
X412385Y1000080D03*
X410085D03*
X420215Y1000040D03*
X420405Y1014470D03*
X414461Y1028855D03*
X411961D03*
X416961D03*
X419461D03*
X415911Y1047749D03*
X419611D03*
X406662Y1044544D03*
X410362D03*
X408511Y1047749D03*
X414062Y1044544D03*
X404811Y1041340D03*
X412211D03*
X415911D03*
X419611D03*
X406662Y1050952D03*
X414060D03*
X417762Y1057361D03*
X421462Y1050952D03*
X419611Y1054157D03*
X406662Y1063770D03*
X408511Y1060565D03*
X410362Y1063770D03*
X412211Y1054157D03*
X404811D03*
X414062Y1057361D03*
X410362D03*
X417762Y1063770D03*
X414062D03*
X419611Y1060565D03*
Y1079791D03*
X408511Y1073383D03*
X406662Y1070178D03*
X404811Y1073383D03*
X417762Y1076587D03*
X408511Y1066974D03*
X415911Y1079791D03*
X412211Y1073383D03*
X415911D03*
X414062Y1070178D03*
X417762D03*
X412211Y1066974D03*
X419611D03*
X419612Y1099017D03*
X404811Y1092608D03*
X417762Y1095813D03*
X414061D03*
X415912Y1124651D03*
X419612D03*
Y1118243D03*
X417761Y1121447D03*
Y1127856D03*
X406661Y1121447D03*
X414062Y1127856D03*
X406662Y1134264D03*
X415912Y1137469D03*
Y1131060D03*
X414061Y1140973D03*
X419612Y1137469D03*
Y1131060D03*
X417761Y1134264D03*
Y1140973D03*
X412212Y1137469D03*
X422878Y848176D03*
X430278Y860993D03*
X422878D03*
Y873810D03*
X430278D03*
X422878Y886627D03*
X430278D03*
Y899445D03*
X422878D03*
X424729Y896240D03*
X430278Y893036D03*
X432129Y896240D03*
X437678Y893036D03*
X421029Y896240D03*
X426578Y899445D03*
X428429Y896240D03*
X433978Y899445D03*
X435829Y896240D03*
X424729Y915466D03*
X426578Y912262D03*
X430278D03*
X432129Y915466D03*
X421029Y909057D03*
X435829D03*
Y915466D03*
X432128Y909057D03*
X433978Y905853D03*
X424728Y909057D03*
X422878Y905853D03*
X430278D03*
X426578D03*
X421029Y915466D03*
X433979Y912262D03*
X430278Y918670D03*
X432129Y921875D03*
X433979Y918670D03*
X435829Y921875D03*
X424927Y927255D03*
X423176Y929465D03*
X422427Y927255D03*
X425676Y929465D03*
X424729Y921875D03*
X422878Y918670D03*
X421029Y921875D03*
X426578Y918670D03*
X430279Y925079D03*
X432130Y928283D03*
X430279Y931487D03*
X432130Y934692D03*
X435830Y928283D03*
X427875Y941930D03*
Y944230D03*
X430280Y944305D03*
X432130Y941101D03*
X435830D03*
X432129Y947510D03*
X435830D03*
Y934692D03*
X427875Y956373D03*
Y954073D03*
X422685Y956620D03*
X425185D03*
X430280Y957123D03*
X432129Y960327D03*
Y953918D03*
X430280Y950714D03*
X435830Y960327D03*
Y953918D03*
X432129Y966736D03*
X430280Y963531D03*
X435830Y966736D03*
X430268Y976348D03*
X432129Y973144D03*
X430280Y969940D03*
X427875Y971267D03*
X422685Y971100D03*
X427875Y968967D03*
X435830Y973144D03*
X430280Y982757D03*
X432129Y979553D03*
X427875Y983111D03*
X435830Y979553D03*
X422685Y985580D03*
X427875Y985411D03*
Y997521D03*
X430712Y1009298D03*
X427875Y1012152D03*
X430712Y1002889D03*
X427875Y999821D03*
X422685Y1000060D03*
X436263Y1006094D03*
Y999685D03*
X432562Y1006094D03*
Y999685D03*
X427875Y1014452D03*
X423015Y1014470D03*
X436263Y1012502D03*
X432562D03*
X421961Y1028855D03*
X430712Y1022115D03*
Y1015706D03*
X427875Y1026704D03*
X430712Y1028524D03*
X436263Y1018911D03*
X432562D03*
Y1025319D03*
X436263D03*
X427875Y1029004D03*
Y1031304D03*
X436263Y1031728D03*
X432562D03*
X427011Y1047749D03*
X427012Y1041340D03*
X423312D03*
X425162Y1044544D03*
X423285Y1036884D03*
X430711Y1041340D03*
X430712Y1034932D03*
X427875Y1033604D03*
X423285Y1032284D03*
Y1034584D03*
X436262Y1038137D03*
X436261Y1044544D03*
X432562Y1038137D03*
X434412Y1041340D03*
X432561Y1044544D03*
X434412Y1047749D03*
X421462Y1044544D03*
X427011Y1054157D03*
X430711D03*
X428861Y1057361D03*
X432561D03*
X421462D03*
X425162Y1050952D03*
X423311Y1054157D03*
X428862Y1050952D03*
X436262Y1057361D03*
Y1050952D03*
Y1063770D03*
X425162D03*
X423311Y1060565D03*
X427011D03*
X428861Y1063770D03*
X430711Y1060565D03*
X423311Y1073383D03*
X432560Y1070178D03*
X421462Y1076587D03*
X423311Y1079791D03*
X436262Y1070178D03*
Y1076587D03*
X421462Y1070178D03*
X425162D03*
X428862D03*
X430711Y1066974D03*
X436262Y1082995D03*
Y1089404D03*
X436261Y1095813D03*
X421462Y1102221D03*
X423311Y1099017D03*
X428861Y1108630D03*
X427012Y1105426D03*
X425162Y1108630D03*
X430711Y1105426D03*
Y1099017D03*
X428861Y1102221D03*
X436262Y1108630D03*
Y1102221D03*
X432561Y1108630D03*
Y1102221D03*
X434412Y1099017D03*
X430711Y1111834D03*
X427012D03*
X430711Y1124651D03*
X428861Y1121447D03*
X427012Y1124651D03*
X425162Y1121447D03*
X421461D03*
X430711Y1118243D03*
X428861Y1115039D03*
X427012Y1118243D03*
X425162Y1115039D03*
X436262Y1121447D03*
Y1115039D03*
X432561Y1121447D03*
Y1115039D03*
X428861Y1127856D03*
X425162D03*
X421461D03*
X436262D03*
X432561D03*
X430711Y1137769D03*
X427012Y1137569D03*
X430711Y1131060D03*
X428861Y1134264D03*
X427012Y1131060D03*
X425162Y1134264D03*
X421461D03*
X428861Y1140973D03*
X425161D03*
X421461D03*
X436261Y1134264D03*
X432561D03*
X445078Y860993D03*
X452479D03*
X437679Y873810D03*
X452479D03*
X445078D03*
X452478Y886627D03*
X445078D03*
X452478Y899445D03*
X441378D03*
X445078Y893036D03*
X446929Y896240D03*
X452479Y893036D03*
X445078Y899445D03*
X443229Y896240D03*
X448778Y899445D03*
X450630Y896240D03*
X443229Y909057D03*
X439529Y915466D03*
X445079Y905853D03*
X441379D03*
X450630Y909057D03*
X452479Y905853D03*
X448779D03*
X448780Y912262D03*
X441380D03*
X439529Y909057D03*
X445080Y912262D03*
X443229Y915466D03*
X450629D03*
X452478Y912262D03*
X448779Y918670D03*
X454329Y915466D03*
X439529Y921875D03*
X441378Y918670D03*
X450629Y921875D03*
X445078Y918670D03*
X443229Y921875D03*
X452478Y918670D03*
X446930Y934692D03*
X443230Y928283D03*
X448780Y931487D03*
X437679D03*
X450630Y928283D03*
X448780Y925079D03*
X445079Y931487D03*
X439530Y934692D03*
X445079Y925079D03*
X439530Y928283D03*
X437679Y925079D03*
X437680Y944305D03*
X441380D03*
X443230Y941101D03*
X445079Y944305D03*
X439530Y941101D03*
X450630D03*
X448780Y944305D03*
X443229Y947510D03*
X439529D03*
X450630D03*
X443230Y934692D03*
X445079Y957123D03*
X437680D03*
X441380D03*
X439529Y960327D03*
X443229D03*
Y953918D03*
X439529D03*
X437680Y950714D03*
X441380D03*
X445079D03*
X448780Y957123D03*
X450630Y953918D03*
Y960327D03*
X448780Y950714D03*
X445079Y963531D03*
X437680D03*
X441380D03*
X439529Y966736D03*
X443229D03*
X448780Y963531D03*
X450630Y966736D03*
X445079Y976348D03*
Y969940D03*
X439529Y973144D03*
X443229D03*
X437680Y976348D03*
X441380D03*
X437680Y969940D03*
X441380D03*
X450630Y973144D03*
X448780Y976348D03*
Y969940D03*
X445079Y982757D03*
X437680D03*
X441380D03*
X439529Y979553D03*
X443229D03*
X448780Y982757D03*
X450630Y979553D03*
X439962Y1006094D03*
X443662D03*
X445511Y1009298D03*
X438113D03*
X441813D03*
X445512Y1002889D03*
X438113D03*
X441813D03*
X439962Y999685D03*
X443662D03*
X451062Y1006094D03*
X449213Y1009298D03*
Y1002889D03*
X451062Y999685D03*
X439962Y1012502D03*
X443662D03*
X451062D03*
X445511Y1022115D03*
X438113D03*
X441813D03*
X445512Y1015706D03*
X438113D03*
X439962Y1018911D03*
X441813Y1015706D03*
X443662Y1018911D03*
Y1025319D03*
X439962D03*
X445511Y1028524D03*
X441813D03*
X438113D03*
X449213Y1022115D03*
X451062Y1018911D03*
X449213Y1015706D03*
X451062Y1025319D03*
X449213Y1028524D03*
X439962Y1031728D03*
X443662D03*
X451062D03*
X452911Y1047749D03*
X439962Y1038137D03*
X443662D03*
X438112Y1041340D03*
X439961Y1044544D03*
X441812Y1041340D03*
X443661Y1044544D03*
X447361D03*
X445511Y1041340D03*
X445512Y1034932D03*
X438113D03*
X441813D03*
X451062Y1038137D03*
X449211Y1041340D03*
X449213Y1034932D03*
X445510Y1047749D03*
X441812D03*
X438112D03*
X449211Y1054157D03*
X449213Y1060565D03*
X438112D03*
Y1054157D03*
X439961Y1057361D03*
X441812Y1054157D03*
Y1060565D03*
X443661Y1057361D03*
X445511Y1060565D03*
Y1054157D03*
X439961Y1050952D03*
X443661D03*
X439961Y1063770D03*
X443661D03*
X451061D03*
X452911Y1054157D03*
X451062Y1050952D03*
X454762D03*
Y1057361D03*
X451062D03*
X451061Y1076587D03*
X452911Y1073383D03*
X439961Y1076587D03*
Y1070178D03*
X441812Y1073383D03*
X438112D03*
X443661Y1070178D03*
Y1076587D03*
X445511Y1073383D03*
X441812Y1066974D03*
X438112D03*
X445511D03*
X441812Y1079791D03*
X438112D03*
X445511D03*
X452911Y1066974D03*
X449211D03*
X451062Y1070178D03*
X452911Y1086200D03*
X443661Y1082995D03*
X439961D03*
X441812Y1086200D03*
X445511D03*
X439961Y1089404D03*
X441812Y1092608D03*
X438112D03*
X443661Y1089404D03*
X445511Y1092608D03*
X447361Y1089404D03*
X438112Y1086200D03*
X449211Y1092608D03*
X439961Y1095813D03*
X443661D03*
X447361D03*
X451060Y1082995D03*
X441812Y1105426D03*
X438112D03*
X439961Y1108630D03*
X443661D03*
X445511Y1105426D03*
X439961Y1102221D03*
X441812Y1099017D03*
X438112D03*
X443661Y1102221D03*
X445511Y1099017D03*
X452912Y1105426D03*
X451061Y1108630D03*
X449212Y1105426D03*
X451061Y1102221D03*
X449212Y1099017D03*
X441812Y1111834D03*
X438112D03*
X445511D03*
X452912D03*
X449212D03*
X438112Y1124651D03*
X439961Y1121447D03*
X441812Y1124651D03*
X445511D03*
X443661Y1121447D03*
X438112Y1118243D03*
X441812D03*
X439961Y1115039D03*
X445511Y1118243D03*
X443661Y1115039D03*
X452912Y1124651D03*
Y1118243D03*
X451061Y1121447D03*
X449212Y1124651D03*
Y1118243D03*
X451061Y1115039D03*
X439961Y1127856D03*
X443661D03*
X451061D03*
X441812Y1137769D03*
X438112D03*
X445511D03*
X443661Y1134264D03*
X441812Y1131060D03*
X439961Y1134264D03*
X438112Y1131060D03*
X445511D03*
X452912Y1137769D03*
Y1131060D03*
X449212Y1137769D03*
Y1131060D03*
X451061Y1134264D03*
X459878Y848176D03*
X467278D03*
X459878Y860993D03*
X467278D03*
Y873810D03*
X459878D03*
Y886627D03*
X467278D03*
X459878Y899445D03*
X467278D03*
X454329Y896240D03*
X459878Y893036D03*
X461729Y896240D03*
X467278Y893036D03*
X456178Y899445D03*
X458029Y896240D03*
X463578Y899445D03*
X465429Y896240D03*
X470978Y899445D03*
X463578Y905853D03*
X470980Y912262D03*
X469129Y902649D03*
X454329Y909057D03*
X470978Y918670D03*
X467278Y912262D03*
X469129Y915466D03*
X458029Y909057D03*
X459878Y905853D03*
X461729Y915466D03*
X467278Y905853D03*
X461729Y909057D03*
X458029Y915466D03*
X459878Y918670D03*
X463578Y912262D03*
X459878D03*
X469129Y909057D03*
X467278Y918670D03*
X454329Y921875D03*
X468236Y928349D03*
X465936D03*
X463636D03*
X461336D03*
X459036D03*
X469129Y921875D03*
X463578Y918670D03*
X465429Y921875D03*
X458029D03*
X469251Y942246D03*
X453585Y942238D03*
Y939938D03*
Y944538D03*
X453403Y956999D03*
X461424Y956620D03*
X458404D03*
X453403Y959299D03*
X468904Y956620D03*
Y971100D03*
X458404D03*
X461424Y971140D03*
X453403Y973099D03*
Y970799D03*
Y986899D03*
X461424Y985580D03*
X458404D03*
X453403Y984599D03*
X468904Y985580D03*
X453403Y998399D03*
Y1012199D03*
X458404Y1000080D03*
X461424D03*
X453403Y1000699D03*
X468904Y1000080D03*
X458404Y1014540D03*
X461295Y1014510D03*
X453403Y1014499D03*
X465680Y1028855D03*
X463180D03*
X460680D03*
X458180D03*
X457942Y1031909D03*
X467711Y1047750D03*
X460311D03*
X471411Y1041340D03*
X467711D03*
X454762Y1044544D03*
Y1038136D03*
X460971Y1037069D03*
X463271D03*
X458671D03*
X457942Y1034409D03*
X456611Y1041340D03*
X464011D03*
X462162Y1044544D03*
X458462D03*
X464011Y1054157D03*
X465860Y1050952D03*
X456611Y1060565D03*
X462161Y1057361D03*
Y1063770D03*
X460312Y1054157D03*
X458462Y1057361D03*
X467712Y1054157D03*
Y1060565D03*
X454761Y1063770D03*
X464012Y1060565D03*
X458460Y1050952D03*
X460311Y1060565D03*
Y1073383D03*
X458460Y1070178D03*
X460311Y1066974D03*
X464011D03*
X465860Y1070178D03*
X469560D03*
X464012Y1079791D03*
X460312D03*
X462162Y1076587D03*
X456611Y1066974D03*
X465862Y1076587D03*
X464011Y1073383D03*
X458462Y1076587D03*
X465862Y1082995D03*
X462162D03*
X462161Y1095812D03*
X458461D03*
X465861Y1089403D03*
X456612Y1092607D03*
X454761Y1089403D03*
X460311Y1086200D03*
X454760Y1082995D03*
X465861Y1095812D03*
X464012Y1092607D03*
X454761Y1095812D03*
X458461Y1089403D03*
X462161D03*
X467711Y1099017D03*
X462162Y1102221D03*
X458461Y1108630D03*
X456612Y1105426D03*
X454761Y1108630D03*
Y1102221D03*
X460312Y1111834D03*
X456611D03*
X460312Y1099016D03*
X464012Y1124651D03*
X462161Y1121447D03*
X460312Y1124651D03*
X456611D03*
X454761Y1121447D03*
X464011Y1118243D03*
X462161Y1115039D03*
X460312Y1118243D03*
X456611D03*
X454761Y1115039D03*
X462161Y1127856D03*
X454761D03*
X465861D03*
X464012Y1137469D03*
X460312D03*
X456612D03*
X464012Y1131060D03*
X462161Y1134264D03*
X460312Y1131060D03*
X456611D03*
X454761Y1134264D03*
X462161Y1140973D03*
X458461D03*
X454761D03*
X467712Y1137469D03*
X465861Y1134264D03*
X467712Y1131060D03*
X465861Y1140973D03*
X474678Y848176D03*
X482078D03*
X474678Y867401D03*
X482078D03*
X474678Y860993D03*
X482078D03*
X480229Y870606D03*
X476529D03*
X478378Y873810D03*
X483929Y870606D03*
X474678Y880219D03*
X476529Y883423D03*
X482078Y880219D03*
X483929Y883423D03*
X472829D03*
X480229D03*
X474678Y873810D03*
X482078D03*
X474678Y893036D03*
X472829Y896240D03*
X478378Y886627D03*
Y899445D03*
X474678Y886627D03*
X482078D03*
X476529Y896240D03*
Y915466D03*
X478380Y912262D03*
X478379Y918670D03*
X480229Y902649D03*
Y915466D03*
X472828D03*
X472829Y902649D03*
X480228Y909057D03*
X482078Y905853D03*
X476529Y902649D03*
X470978Y905853D03*
X478378D03*
X472829Y909057D03*
X476529D03*
X480229Y928283D03*
X478378Y931488D03*
Y925079D03*
X482078D03*
X472829Y921875D03*
X470536Y928349D03*
X478378Y937896D03*
X480229Y941100D03*
Y947509D03*
X471550Y942152D03*
X473851Y942246D03*
X478378Y963530D03*
X480228Y960326D03*
X478378Y950713D03*
X480229Y953917D03*
X478378Y957122D03*
X471404Y956620D03*
X480229Y966735D03*
X482078Y963529D03*
Y982756D03*
X478379Y969939D03*
X476285Y973826D03*
Y971526D03*
X471404Y971100D03*
X473904D03*
X480229Y979552D03*
X478378Y982756D03*
X480229Y973143D03*
X478378Y976347D03*
X471404Y985580D03*
X480662Y999684D03*
X478811Y1002888D03*
Y1009297D03*
X480662Y1012501D03*
X471404Y1000080D03*
X480662Y1031727D03*
X482511Y1015705D03*
X480661Y1018910D03*
X478811Y1022114D03*
Y1028523D03*
Y1015705D03*
X476325Y1031795D03*
Y1027195D03*
Y1029495D03*
X470724Y1028827D03*
X480662Y1025318D03*
X475111Y1047749D03*
X469562Y1044544D03*
X478811Y1034931D03*
X480662Y1038136D03*
X478811Y1041340D03*
X480662Y1044544D03*
X473262D03*
X476962D03*
X478811Y1047749D03*
X473261Y1057361D03*
X471412Y1060565D03*
X475112Y1054157D03*
X469562Y1063770D03*
X469561Y1057361D03*
X473262Y1063770D03*
X469561Y1050952D03*
X473262D03*
X482511Y1054157D03*
X480662Y1063770D03*
X480661Y1057361D03*
X478812Y1060565D03*
X476962Y1063770D03*
Y1057361D03*
X478812Y1054157D03*
X476961Y1050952D03*
X478811Y1066974D03*
X471411D03*
X476962Y1076587D03*
X480662D03*
Y1070178D03*
X476962D03*
X473262Y1076587D03*
X469562D03*
X471411Y1073383D03*
Y1079791D03*
X475111Y1073383D03*
X482511D03*
X473262Y1095813D03*
X469562Y1082995D03*
X480662Y1089404D03*
X478812Y1092607D03*
X475112D03*
X473261Y1089403D03*
X471412Y1086199D03*
X476961Y1082994D03*
X482512Y1092607D03*
X476961Y1095812D03*
X471412Y1092607D03*
X475112Y1086199D03*
X478812D03*
X480662Y1102221D03*
X473262Y1121447D03*
X480662D03*
Y1134264D03*
X469561D03*
X489478Y848176D03*
X496878D03*
X489478Y867401D03*
X496878D03*
X489478Y860993D03*
X496878D03*
X487629Y870606D03*
X495029D03*
X485778Y873810D03*
X491329Y870606D03*
X493178Y873810D03*
X498729Y870606D03*
X500578Y873810D03*
X489478Y880219D03*
X491329Y883423D03*
X496878Y880219D03*
X498729Y883423D03*
X487629D03*
X495029D03*
X496878Y873810D03*
X489478D03*
X485778Y886627D03*
X493178D03*
X500578D03*
X489478D03*
X496878D03*
X488062Y1095813D03*
X501012Y1105426D03*
Y1111833D03*
X488062Y1115039D03*
Y1121447D03*
X495462Y1134264D03*
X488062D03*
X511678Y848176D03*
X504278D03*
X511678Y867401D03*
X504278D03*
X511678Y860993D03*
X504278D03*
X517229Y870606D03*
X502429D03*
X509829D03*
X513529D03*
X515378Y873810D03*
X506129Y870606D03*
X507978Y873810D03*
X511678Y880219D03*
X513529Y883423D03*
X504278Y880219D03*
X506129Y883423D03*
X509829D03*
X517229D03*
X502429D03*
X511678Y873810D03*
X504278D03*
X515378Y886627D03*
X507978D03*
X511678D03*
X504278D03*
X502862Y1006093D03*
X510262Y1102221D03*
X502861Y1108629D03*
X512112Y1105426D03*
X508412Y1111833D03*
X506561Y1102220D03*
X504712Y1111833D03*
Y1105426D03*
X510261Y1108630D03*
X512112Y1111833D03*
X508412Y1105426D03*
X502862Y1115039D03*
X510262Y1121447D03*
X502862D03*
X517662D03*
X506561Y1115038D03*
X510262Y1134264D03*
X502862D03*
X517662D03*
X519078Y848176D03*
Y867401D03*
X526479D03*
Y860993D03*
X519078D03*
X524629Y870606D03*
X532029D03*
X520929D03*
X522778Y873810D03*
X528329Y870606D03*
X530178Y873810D03*
X519078Y880219D03*
X520929Y883423D03*
X526479Y880219D03*
X528329Y883423D03*
X524629D03*
X526479Y873810D03*
X519078D03*
X530178Y893036D03*
X522778Y886627D03*
X530179D03*
X526479D03*
X519078D03*
X533879D03*
X528762Y1102221D03*
X525062D03*
X523212Y1099017D03*
X530611Y1105426D03*
X526911Y1118243D03*
X525062Y1121447D03*
X534311Y1118243D03*
X532461Y1121446D03*
X534311Y1124650D03*
X532461Y1127855D03*
X525062Y1134264D03*
X528761Y1140973D03*
X532461D03*
X541711Y1118243D03*
X538010Y1118242D03*
X543561Y1121446D03*
X539861Y1127855D03*
X536161D03*
Y1121446D03*
X539861D03*
X541711Y1124650D03*
X543561Y1127855D03*
X538012Y1131059D03*
X650599Y766798D03*
X918264Y506011D03*
X1030780Y1266532D03*
X1074480Y1263742D03*
X1181941Y766798D03*
X1297012Y157449D03*
X1293802Y159299D03*
Y166699D03*
X1293511Y179048D03*
X1296999Y183349D03*
X1297007Y172249D03*
X1296999Y175949D03*
X1293802Y170399D03*
X1294163Y175865D03*
X1296999Y179649D03*
Y194449D03*
Y198149D03*
Y190749D03*
Y187049D03*
Y201849D03*
X1293805Y211099D03*
X1293798Y205833D03*
X1296999Y216649D03*
X1293807Y218499D03*
Y214799D03*
X1296999Y212949D03*
Y205549D03*
X1294357Y224688D03*
X1296999Y224049D03*
X1293807Y222199D03*
X1300393Y235762D03*
X1303417Y164849D03*
X1300213Y162999D03*
X1300212Y166699D03*
X1306622D03*
X1309832Y157449D03*
X1306626Y162999D03*
Y159299D03*
X1313037Y162999D03*
X1309832Y164849D03*
X1313037Y159299D03*
X1303417Y157449D03*
X1300217Y159299D03*
X1313033Y166699D03*
X1300212Y170399D03*
X1306626D03*
X1303407Y183349D03*
X1309817Y175949D03*
X1300212Y174099D03*
X1313037Y170399D03*
X1306617Y185199D03*
X1309832Y172249D03*
X1313027Y181499D03*
Y185199D03*
X1303407Y175949D03*
Y179649D03*
X1306617Y177799D03*
X1309817Y179649D03*
X1300204Y181499D03*
X1309817Y194449D03*
X1306617Y188899D03*
X1303407Y194449D03*
X1306617Y196299D03*
X1300207D03*
X1303407Y190749D03*
Y187049D03*
X1300204Y188899D03*
X1313027Y192599D03*
X1309817Y190749D03*
X1313025Y188899D03*
X1309817Y198149D03*
X1303407D03*
X1300207Y203699D03*
Y207399D03*
X1309832Y209249D03*
X1313027Y203699D03*
X1300220Y218499D03*
X1309833Y220349D03*
X1303416Y205549D03*
X1306614Y203699D03*
X1306627Y214799D03*
X1316242Y209249D03*
X1300207Y211099D03*
X1303422Y220349D03*
X1300220Y222199D03*
X1313033D03*
X1303425Y224049D03*
X1300493Y238062D03*
X1314184Y849978D03*
X1307426Y978814D03*
X1314353Y1118243D03*
Y1131060D03*
X1319452Y162999D03*
X1316242Y168549D03*
X1319442Y159299D03*
X1316241Y157449D03*
X1316242Y164849D03*
X1322652D03*
X1329062D03*
X1326918Y161161D03*
X1329062Y157449D03*
X1322652D03*
X1325853Y174099D03*
X1331102Y179724D03*
Y182874D03*
Y186024D03*
X1325085Y176402D03*
X1324802Y179724D03*
Y186024D03*
Y182874D03*
X1315352Y186024D03*
Y179724D03*
X1319442Y174099D03*
X1332268D03*
X1324802Y195474D03*
X1327952D03*
X1318502D03*
X1321652D03*
X1327952Y201774D03*
X1321652D03*
X1331102Y189174D03*
X1315405Y189227D03*
X1329062Y212949D03*
X1325852Y211099D03*
X1319442D03*
X1324802Y204924D03*
X1327952D03*
X1318502D03*
X1315352D03*
X1322652Y209249D03*
X1325857Y218499D03*
X1322652Y216649D03*
X1329062Y220349D03*
X1325856Y222199D03*
X1322652Y224049D03*
Y220349D03*
X1321320Y854584D03*
X1325021Y860993D03*
X1326871Y870606D03*
X1330571D03*
X1328720Y873810D03*
X1330571Y883423D03*
X1325020Y873810D03*
X1323171Y877014D03*
X1325020Y880219D03*
X1319903Y999684D03*
X1325453Y1105426D03*
X1327304Y1127856D03*
X1329153Y1118243D03*
X1331003Y1121447D03*
Y1134264D03*
X1323603D03*
X1339727Y161149D03*
X1341992Y156897D03*
X1332268Y162999D03*
X1342903Y170399D03*
X1339727Y168549D03*
X1335472Y164849D03*
X1346140Y161149D03*
X1342937Y162999D03*
X1335472Y157449D03*
X1346140D03*
X1339727D03*
X1332268Y170399D03*
X1334252Y176574D03*
X1339727Y183349D03*
X1346137Y175949D03*
X1342937Y177799D03*
X1346137Y183349D03*
X1337901Y196035D03*
X1339727Y187049D03*
X1337345Y201831D03*
X1339727Y201849D03*
X1337402Y198624D03*
X1342937Y192599D03*
X1346137Y187049D03*
X1346147Y201849D03*
Y198149D03*
X1336527Y214799D03*
X1339727Y216649D03*
X1346147Y212949D03*
Y216649D03*
X1336527Y218499D03*
X1342937D03*
Y214799D03*
X1332262Y211099D03*
X1339686Y205478D03*
X1332262Y207399D03*
X1339727Y209249D03*
Y220349D03*
X1336527Y222199D03*
X1346147Y220349D03*
X1347220Y848176D03*
X1339820D03*
X1332420D03*
X1347220Y867401D03*
X1332420D03*
X1339820D03*
Y860993D03*
X1347220D03*
X1332420D03*
X1334271Y870606D03*
X1337971D03*
X1341671D03*
X1336120Y873810D03*
X1343520D03*
X1345371Y870606D03*
X1332420Y880219D03*
X1334271Y883423D03*
X1339820Y880219D03*
X1341671Y883423D03*
X1347220Y880219D03*
X1337971Y883423D03*
X1345371D03*
X1339820Y873810D03*
X1332420D03*
X1347220D03*
X1339821Y893036D03*
X1343521D03*
X1336120Y886627D03*
X1343520D03*
X1347220D03*
X1339820D03*
X1343953Y1002888D03*
X1334704Y1102221D03*
X1345803D03*
X1343953Y1105426D03*
X1336554D03*
X1345804Y1121447D03*
X1338403D03*
X1338404Y1134264D03*
X1345804D03*
X1352550Y157449D03*
X1355961Y155458D03*
X1352557Y168548D03*
X1355762Y166698D03*
X1349344Y162999D03*
X1348386Y156646D03*
X1352551Y161148D03*
X1352557Y172248D03*
X1349351Y177798D03*
Y170398D03*
Y174098D03*
Y192598D03*
X1352551Y187048D03*
X1355761Y188898D03*
X1349361Y199998D03*
X1352561Y201848D03*
X1355766Y214798D03*
X1349351Y218498D03*
X1352561Y216648D03*
X1355766Y218498D03*
X1352561Y220348D03*
X1355766Y222198D03*
X1360186Y226264D03*
X1362020Y848176D03*
X1354620D03*
Y867401D03*
X1362020D03*
Y860993D03*
X1354620D03*
X1363871Y870606D03*
X1349071D03*
X1356471D03*
X1350920Y873810D03*
X1352771Y870606D03*
X1358320Y873810D03*
X1360171Y870606D03*
X1349071Y883423D03*
X1354620Y880219D03*
X1356471Y883423D03*
X1362020Y880219D03*
X1363871Y883423D03*
X1352771D03*
X1360171D03*
X1354620Y873810D03*
X1362020D03*
X1350920Y886627D03*
X1358320D03*
X1354620D03*
X1362020D03*
X1351354Y1099017D03*
X1356904Y1095813D03*
X1358753Y1099017D03*
X1360604Y1121447D03*
X1353204D03*
Y1134264D03*
X1360604D03*
X1376820Y848176D03*
X1369420D03*
X1376820Y867401D03*
X1369420D03*
X1376820Y860993D03*
X1369420D03*
X1367571Y870606D03*
X1371271D03*
X1378671D03*
X1365720Y873810D03*
X1373120D03*
X1374971Y870606D03*
X1369420Y880219D03*
X1371271Y883423D03*
X1376820Y880219D03*
X1378671Y883423D03*
X1367571D03*
X1374971D03*
X1369420Y873810D03*
X1376820D03*
X1378671Y896240D03*
X1376820Y899445D03*
X1369421Y893036D03*
X1373121D03*
X1373120Y886627D03*
X1365720D03*
X1374971Y896240D03*
X1376820Y893036D03*
X1369420Y886627D03*
X1376820D03*
X1380520Y899445D03*
X1376820Y905853D03*
X1378671Y915466D03*
Y909057D03*
X1376820Y912262D03*
X1378671Y902649D03*
X1376820Y931488D03*
X1378671Y928283D03*
Y921875D03*
X1374971Y934691D03*
X1378671D03*
Y947509D03*
Y966735D03*
Y960326D03*
Y953917D03*
X1374971D03*
X1376822Y950713D03*
X1375404Y1006093D03*
X1379104D03*
X1375404Y999684D03*
X1379104D03*
X1377253Y1009297D03*
X1379104Y1012501D03*
Y1031727D03*
X1377253Y1028523D03*
X1375404Y1025318D03*
X1377253Y1022114D03*
X1379102Y1018910D03*
X1379104Y1025318D03*
X1377253Y1015705D03*
X1375404Y1044544D03*
X1377253Y1041340D03*
X1379104Y1044544D03*
Y1038136D03*
X1377253Y1047749D03*
X1379104Y1057361D03*
Y1063770D03*
X1377255Y1060565D03*
X1375404Y1063770D03*
X1377253Y1054157D03*
X1379104Y1050952D03*
X1380953Y1054157D03*
X1379104Y1076587D03*
Y1070178D03*
X1377254Y1066974D03*
X1375404Y1082995D03*
X1368004Y1102221D03*
X1369853Y1105426D03*
X1368004Y1121447D03*
X1375404D03*
X1368004Y1134264D03*
X1375404D03*
X1374847Y1153069D03*
X1391620Y848176D03*
X1384220D03*
Y867401D03*
Y860993D03*
X1391620D03*
X1380520Y873810D03*
X1382371Y870606D03*
X1384220Y880219D03*
X1386071Y883423D03*
X1382371D03*
X1391620Y873810D03*
X1384220D03*
X1380520Y886627D03*
X1387920D03*
X1380520Y893036D03*
X1382371Y896240D03*
X1384220Y886627D03*
X1391620D03*
Y899445D03*
X1384221Y899446D03*
X1393471Y909057D03*
X1382371D03*
X1389771D03*
Y915466D03*
X1399020Y905853D03*
X1382371Y915466D03*
X1384220Y918670D03*
X1387920Y905853D03*
X1384220D03*
Y912262D03*
X1382371Y902649D03*
X1391620Y905853D03*
X1387920Y912262D03*
X1391620D03*
X1393471Y915466D03*
X1391621Y918670D03*
X1382371Y921875D03*
X1382809Y927986D03*
X1385070Y928468D03*
X1393471Y921875D03*
X1391550Y925219D03*
X1387921Y918670D03*
X1386030Y942163D03*
X1383730D03*
X1381430D03*
X1392534Y942097D03*
X1394834D03*
X1393826Y956619D03*
X1387826D03*
X1391326D03*
X1385526D03*
X1380926Y971099D03*
X1383226D03*
X1387826D03*
X1385526D03*
X1396346D03*
X1396286Y985549D03*
X1388506Y985609D03*
X1386206D03*
X1385526Y1014539D03*
X1387826D03*
X1383226D03*
X1386226Y1000079D03*
X1396356Y1000039D03*
X1388526Y1000079D03*
X1396546Y1014469D03*
X1388102Y1028854D03*
X1390602D03*
X1393102D03*
X1395602D03*
X1380953Y1041340D03*
X1388353D03*
X1392053D03*
X1395753D03*
Y1047749D03*
X1392053D03*
X1382804Y1044544D03*
X1386504D03*
X1384653Y1047749D03*
X1390204Y1044544D03*
X1382804Y1050952D03*
Y1057361D03*
X1386504D03*
X1390204Y1050952D03*
X1393904Y1057361D03*
X1395753Y1054157D03*
X1382804Y1063770D03*
X1384653Y1060565D03*
X1386504Y1063770D03*
X1388353Y1054157D03*
X1390204Y1057361D03*
X1393904Y1063770D03*
X1390204D03*
X1395753Y1060565D03*
Y1079791D03*
X1384653Y1073383D03*
X1382804Y1070178D03*
X1380953Y1073383D03*
X1393904Y1076587D03*
X1392053Y1079791D03*
X1384653Y1066974D03*
X1388353Y1073383D03*
X1392053D03*
X1390204Y1070178D03*
X1393904D03*
X1388353Y1066974D03*
X1395753D03*
X1395754Y1099017D03*
X1380953Y1092608D03*
X1393904Y1095813D03*
X1390203D03*
X1392054Y1124651D03*
X1393903Y1121447D03*
Y1127856D03*
X1395754Y1118243D03*
Y1124651D03*
X1382803Y1121447D03*
X1390204Y1127856D03*
X1382804Y1134264D03*
X1390203Y1140973D03*
X1392054Y1131060D03*
Y1137469D03*
X1393903Y1134264D03*
Y1140973D03*
X1395754Y1131060D03*
Y1137469D03*
X1388354D03*
X1399020Y848176D03*
X1406420Y860993D03*
X1399020D03*
Y873810D03*
X1406420D03*
Y886627D03*
X1399020D03*
X1406420Y899445D03*
X1399020D03*
Y912262D03*
X1400871Y915466D03*
X1402720Y912262D03*
X1406420D03*
X1408271Y915466D03*
X1397171Y909057D03*
X1411971D03*
Y915466D03*
X1408270Y909057D03*
X1410120Y905853D03*
X1400870Y909057D03*
X1406420Y905853D03*
X1402720D03*
X1397171Y915466D03*
X1410121Y912262D03*
X1406420Y918670D03*
X1408271Y921875D03*
X1410121Y918670D03*
X1411971Y921875D03*
X1401528Y927155D03*
X1399028D03*
X1401817Y929464D03*
X1399317D03*
X1400871Y921875D03*
X1399020Y918670D03*
X1397171Y921875D03*
X1402720Y918670D03*
X1411971Y934691D03*
X1406420Y925079D03*
X1408271Y928283D03*
X1406420Y931488D03*
X1411971Y928283D03*
X1406421Y944304D03*
X1408271Y941100D03*
X1411971D03*
X1404016Y944229D03*
Y941929D03*
X1408270Y947509D03*
X1411971D03*
X1408271Y934691D03*
X1406421Y950713D03*
Y957122D03*
X1408270Y953917D03*
Y960326D03*
X1411971Y953917D03*
Y960326D03*
X1404016Y954072D03*
Y956372D03*
X1401326Y956619D03*
X1398826D03*
X1406421Y963530D03*
X1408270Y966735D03*
X1411971D03*
X1406421Y969939D03*
X1406409Y976347D03*
X1408270Y973143D03*
X1411971D03*
X1404016Y971266D03*
Y968966D03*
X1398826Y971099D03*
X1406421Y982756D03*
X1408270Y979552D03*
X1411971D03*
X1404016Y983110D03*
Y985410D03*
X1398826Y985579D03*
X1404016Y997520D03*
X1412404Y999684D03*
Y1006093D03*
Y1012501D03*
X1406853Y1002888D03*
Y1009297D03*
X1408703Y999684D03*
Y1006093D03*
Y1012501D03*
X1404016Y1012151D03*
Y999820D03*
X1398826Y1000059D03*
X1404016Y1014451D03*
X1399156Y1014469D03*
X1398102Y1028854D03*
X1406853Y1028523D03*
X1412404Y1018910D03*
X1406853Y1015705D03*
Y1022114D03*
X1408703Y1018910D03*
X1412404Y1025318D03*
X1408703D03*
X1404016Y1026703D03*
X1412404Y1031727D03*
X1408703D03*
X1404016Y1029003D03*
Y1031303D03*
X1403153Y1047749D03*
X1403154Y1041340D03*
X1399454D03*
X1401304Y1044544D03*
X1412403Y1038136D03*
Y1044544D03*
X1406853Y1034931D03*
Y1041340D03*
X1408703Y1038136D03*
Y1044544D03*
X1410554Y1041340D03*
X1404016Y1033603D03*
X1399426Y1036883D03*
Y1034583D03*
Y1032283D03*
X1410554Y1047749D03*
X1397604Y1044544D03*
X1403153Y1054157D03*
X1406853D03*
X1405003Y1057361D03*
X1408703D03*
Y1063770D03*
X1412404Y1050952D03*
Y1057361D03*
Y1063770D03*
X1397604Y1057361D03*
X1401304Y1050952D03*
X1399453Y1054157D03*
X1405004Y1050952D03*
X1397604D03*
X1401304Y1063770D03*
X1399453Y1060565D03*
X1403153D03*
X1405003Y1063770D03*
X1406853Y1060565D03*
X1397604Y1076587D03*
X1408702Y1070178D03*
X1399453Y1073383D03*
Y1079791D03*
X1412404Y1070178D03*
Y1076587D03*
X1397604Y1070178D03*
X1401304D03*
X1405004D03*
X1406853Y1066974D03*
X1412404Y1082995D03*
Y1089404D03*
X1412403Y1095813D03*
X1397604Y1102221D03*
X1399453Y1099017D03*
X1412404Y1102221D03*
Y1108630D03*
X1401304D03*
X1403154Y1105426D03*
Y1111834D03*
X1405003Y1102221D03*
Y1108630D03*
X1406853Y1099017D03*
Y1105426D03*
Y1111834D03*
X1408703Y1102221D03*
Y1108630D03*
X1410554Y1099017D03*
X1412404Y1115039D03*
Y1121447D03*
Y1127856D03*
X1397603Y1121447D03*
Y1127856D03*
X1401304Y1115039D03*
Y1121447D03*
Y1127856D03*
X1403154Y1118243D03*
Y1124651D03*
X1405003Y1115039D03*
Y1121447D03*
Y1127856D03*
X1406853Y1118243D03*
Y1124651D03*
X1408703Y1115039D03*
Y1121447D03*
Y1127856D03*
X1412403Y1134264D03*
X1397603D03*
Y1140973D03*
X1401304Y1134264D03*
X1401303Y1140973D03*
X1403154Y1131060D03*
Y1137569D03*
X1405003Y1134264D03*
Y1140973D03*
X1406853Y1131060D03*
Y1137769D03*
X1408703Y1134264D03*
X1421220Y860993D03*
X1428621D03*
X1413821Y873810D03*
X1428621D03*
X1421220D03*
X1428620Y899445D03*
Y886627D03*
X1421220D03*
X1419371Y909057D03*
X1415671Y915466D03*
X1421221Y905853D03*
X1417521D03*
X1430471Y909057D03*
X1426772D03*
X1428621Y905853D03*
X1424921D03*
X1424922Y912262D03*
X1417522D03*
X1415671Y909057D03*
X1421222Y912262D03*
X1419371Y915466D03*
X1426771D03*
X1428620Y912262D03*
X1424921Y918670D03*
X1430471Y915466D03*
X1415671Y921875D03*
X1417520Y918670D03*
X1426771Y921875D03*
X1421220Y918670D03*
X1419371Y921875D03*
X1428620Y918670D03*
X1424921Y931488D03*
X1419371Y928283D03*
X1413820Y931488D03*
X1424921Y925079D03*
X1419371Y934691D03*
X1421220Y931488D03*
Y925079D03*
X1415671Y928283D03*
X1413820Y925079D03*
X1426771Y928283D03*
X1413821Y944304D03*
X1415671Y941100D03*
X1417521Y944304D03*
X1419371Y941100D03*
X1421220Y944304D03*
X1424921D03*
X1426771Y941100D03*
X1415670Y947509D03*
X1419370D03*
X1426771D03*
X1423071Y934691D03*
X1415671D03*
X1413821Y950713D03*
Y957122D03*
X1415670Y953917D03*
Y960326D03*
X1417521Y950713D03*
Y957122D03*
X1419370Y953917D03*
Y960326D03*
X1421220Y950713D03*
Y957122D03*
X1424921Y950713D03*
Y957122D03*
X1426771Y953917D03*
Y960326D03*
X1413821Y963530D03*
X1415670Y966735D03*
X1417521Y963530D03*
X1419370Y966735D03*
X1421220Y963530D03*
X1424921D03*
X1426771Y966735D03*
X1413821Y969939D03*
Y976347D03*
X1415670Y973143D03*
X1417521Y969939D03*
Y976347D03*
X1419370Y973143D03*
X1421220Y969939D03*
Y976347D03*
X1424921Y969939D03*
Y976347D03*
X1426771Y973143D03*
X1413821Y982756D03*
X1415670Y979552D03*
X1417521Y982756D03*
X1419370Y979552D03*
X1421220Y982756D03*
X1424921D03*
X1426771Y979552D03*
X1414254Y1002888D03*
Y1009297D03*
X1416103Y999684D03*
Y1006093D03*
Y1012501D03*
X1417954Y1002888D03*
Y1009297D03*
X1419803Y999684D03*
Y1006093D03*
Y1012501D03*
X1421653Y1002888D03*
Y1009297D03*
X1425354Y1002888D03*
Y1009297D03*
X1427203Y999684D03*
Y1006093D03*
Y1012501D03*
X1421653Y1028523D03*
X1414254D03*
X1417954D03*
X1425354D03*
X1414254Y1015705D03*
Y1022114D03*
X1416103Y1018910D03*
X1417954Y1015705D03*
Y1022114D03*
X1419803Y1018910D03*
X1421653Y1015705D03*
Y1022114D03*
X1425354Y1015705D03*
Y1022114D03*
X1427203Y1018910D03*
X1416103Y1025318D03*
X1419803D03*
X1427203D03*
X1416103Y1031727D03*
X1419803D03*
X1427203D03*
X1429053Y1047749D03*
X1414254Y1034931D03*
Y1041340D03*
X1416103Y1038136D03*
Y1044544D03*
X1417954Y1034931D03*
Y1041340D03*
X1419803Y1038136D03*
Y1044544D03*
X1421653Y1034931D03*
Y1041340D03*
X1423503Y1044544D03*
X1425354Y1034931D03*
X1425353Y1041340D03*
X1427203Y1038136D03*
X1421653Y1047749D03*
X1414254D03*
X1417954D03*
X1425353Y1054157D03*
X1425355Y1060565D03*
X1414254Y1054157D03*
X1416103Y1050952D03*
X1417954Y1054157D03*
X1419803Y1050952D03*
X1421653Y1054157D03*
X1414254Y1060565D03*
X1416103Y1057361D03*
X1417954Y1060565D03*
X1419803Y1057361D03*
X1421653Y1060565D03*
X1416103Y1063770D03*
X1419803D03*
X1427203D03*
X1429053Y1054157D03*
X1427203Y1050952D03*
X1430903D03*
X1430904Y1057361D03*
X1427204D03*
X1429053Y1073383D03*
X1427203Y1076587D03*
X1414254Y1066974D03*
Y1073383D03*
X1416103Y1070178D03*
Y1076587D03*
X1417954Y1066974D03*
Y1073383D03*
X1419803Y1070178D03*
Y1076587D03*
X1421653Y1066974D03*
Y1073383D03*
X1414254Y1079791D03*
X1417954D03*
X1421653D03*
X1429053Y1066974D03*
X1425353D03*
X1427204Y1070178D03*
X1429053Y1086200D03*
X1416103Y1082995D03*
X1419803D03*
X1414254Y1086200D03*
Y1092608D03*
X1416103Y1089404D03*
Y1095813D03*
X1417954Y1086200D03*
Y1092608D03*
X1419803Y1089404D03*
Y1095813D03*
X1421653Y1086200D03*
Y1092608D03*
X1423503Y1089404D03*
Y1095813D03*
X1425353Y1092608D03*
X1427202Y1082995D03*
X1414254Y1099017D03*
Y1105426D03*
Y1111834D03*
X1416103Y1102221D03*
Y1108630D03*
X1417954Y1099017D03*
Y1105426D03*
Y1111834D03*
X1419803Y1102221D03*
Y1108630D03*
X1421653Y1099017D03*
Y1105426D03*
Y1111834D03*
X1425354Y1099017D03*
Y1105426D03*
Y1111834D03*
X1427203Y1102221D03*
Y1108630D03*
X1429054Y1105426D03*
Y1111834D03*
X1414254Y1118243D03*
Y1124651D03*
X1416103Y1115039D03*
Y1121447D03*
Y1127856D03*
X1417954Y1118243D03*
Y1124651D03*
X1419803Y1115039D03*
Y1121447D03*
Y1127856D03*
X1421653Y1118243D03*
Y1124651D03*
X1425354Y1118243D03*
Y1124651D03*
X1427203Y1115039D03*
Y1121447D03*
Y1127856D03*
X1429054Y1118243D03*
Y1124651D03*
X1414254Y1131060D03*
Y1137769D03*
X1416103Y1134264D03*
X1417954Y1131060D03*
Y1137769D03*
X1419803Y1134264D03*
X1421653Y1131060D03*
Y1137769D03*
X1425354Y1131060D03*
Y1137769D03*
X1427203Y1134264D03*
X1429054Y1131060D03*
Y1137769D03*
X1443420Y848176D03*
X1436020D03*
X1443420Y860993D03*
X1436020D03*
Y873810D03*
X1443420D03*
X1436020Y899445D03*
X1443420D03*
X1436020Y886627D03*
X1443420D03*
X1447120Y899445D03*
X1445271Y902649D03*
X1434171Y909057D03*
X1437871Y915466D03*
X1443420Y912262D03*
X1445271Y915466D03*
X1437871Y909057D03*
X1434171Y915466D03*
X1436020Y918670D03*
X1439720Y912262D03*
X1436020D03*
Y905853D03*
X1439720D03*
X1443420D03*
X1445271Y909057D03*
X1430471Y921875D03*
X1443420Y918670D03*
X1439777Y928348D03*
X1437477D03*
X1435177D03*
X1444377D03*
X1442077D03*
X1445271Y921875D03*
X1439720Y918670D03*
X1441571Y921875D03*
X1434171D03*
X1445392Y942195D03*
X1429726Y944537D03*
Y939937D03*
Y942237D03*
X1429544Y959298D03*
Y956998D03*
X1437565Y956619D03*
X1434545D03*
X1445045D03*
X1429544Y970798D03*
Y973098D03*
X1437565Y971139D03*
X1434545Y971099D03*
X1429544Y986898D03*
Y984598D03*
X1437565Y985579D03*
X1434545D03*
X1445045D03*
X1429544Y998398D03*
Y1012198D03*
Y1000698D03*
X1437565Y1000079D03*
X1434545D03*
X1445045D03*
X1429544Y1014498D03*
X1437436Y1014509D03*
X1434545Y1014539D03*
X1445036Y1014549D03*
X1439321Y1028854D03*
X1436821D03*
X1434321D03*
X1441821D03*
X1434083Y1031908D03*
X1447553Y1041340D03*
X1443853D03*
X1436453Y1047750D03*
X1443853D03*
X1430904Y1044544D03*
Y1038136D03*
X1434083Y1034408D03*
X1434813Y1037069D03*
X1439413D03*
X1437113D03*
X1432753Y1041340D03*
X1440153D03*
X1438304Y1044544D03*
X1434604D03*
X1432753Y1060565D03*
X1438303Y1057361D03*
Y1063770D03*
X1442002Y1050952D03*
X1440153Y1054157D03*
X1436454D03*
X1434604Y1057361D03*
X1443854Y1054157D03*
Y1060565D03*
X1430903Y1063770D03*
X1440154Y1060565D03*
X1434603Y1050952D03*
X1436453Y1060565D03*
Y1073383D03*
X1434602Y1070178D03*
X1436453Y1066974D03*
X1440153D03*
X1442002Y1070178D03*
X1447553Y1066974D03*
X1440154Y1079791D03*
X1436454D03*
X1438304Y1076587D03*
X1432753Y1066974D03*
X1442004Y1076587D03*
X1440153Y1073383D03*
X1434604Y1076587D03*
X1438304Y1082995D03*
X1442004D03*
X1438303Y1095812D03*
X1434603D03*
X1442003Y1089403D03*
X1432754Y1092607D03*
X1430903Y1089403D03*
X1436454Y1086199D03*
X1430902Y1082995D03*
X1442003Y1095812D03*
X1440154Y1092607D03*
X1430903Y1095812D03*
X1434603Y1089403D03*
X1438303D03*
X1438304Y1102221D03*
X1443853Y1099017D03*
X1430903Y1102221D03*
Y1108630D03*
X1432754Y1105426D03*
X1432753Y1111834D03*
X1434603Y1108630D03*
X1436454Y1111834D03*
Y1099016D03*
X1430903Y1115039D03*
Y1121447D03*
Y1127856D03*
X1432753Y1118243D03*
Y1124651D03*
X1436454Y1118243D03*
Y1124651D03*
X1438303Y1115039D03*
Y1121447D03*
Y1127856D03*
X1440153Y1118243D03*
X1440154Y1124651D03*
X1442003Y1127856D03*
X1443854Y1131060D03*
Y1137469D03*
X1430903Y1134264D03*
Y1140973D03*
X1432753Y1131060D03*
X1432754Y1137469D03*
X1434603Y1140973D03*
X1436454Y1131060D03*
Y1137469D03*
X1438303Y1134264D03*
Y1140973D03*
X1440154Y1131060D03*
Y1137469D03*
X1442003Y1134264D03*
Y1140973D03*
X1450820Y848176D03*
X1458220D03*
X1450820Y867401D03*
X1458220D03*
X1450820Y860993D03*
X1458220D03*
X1456371Y870606D03*
X1452671D03*
X1454520Y873810D03*
X1460071Y870606D03*
X1450820Y880219D03*
X1452671Y883423D03*
X1458220Y880219D03*
X1460071Y883423D03*
X1448971D03*
X1456371D03*
X1458220Y873810D03*
X1450820D03*
Y893036D03*
X1448971Y896240D03*
X1454520Y886627D03*
Y899445D03*
X1458220Y886627D03*
X1450820D03*
X1452671Y896240D03*
X1456371Y902649D03*
Y915466D03*
X1447122Y912262D03*
X1454521Y918670D03*
X1452671Y915466D03*
X1454522Y912262D03*
X1448971Y902649D03*
X1456370Y909057D03*
X1458220Y905853D03*
X1452671Y902649D03*
X1448970Y915466D03*
X1447120Y905853D03*
X1454520D03*
X1448971Y909057D03*
X1452671D03*
X1456371Y928283D03*
X1454522Y931488D03*
X1454520Y925079D03*
X1458220D03*
X1448971Y921875D03*
X1447120Y918670D03*
X1446677Y928348D03*
X1454520Y937896D03*
X1456371Y941100D03*
Y947509D03*
X1449992Y942195D03*
X1447692D03*
X1454520Y963530D03*
X1456371Y966735D03*
X1458220Y963529D03*
X1456370Y960326D03*
X1456371Y953917D03*
X1454520Y957122D03*
Y950713D03*
X1447545Y956619D03*
X1458220Y982756D03*
X1454521Y969939D03*
X1450045Y971099D03*
X1445445D03*
X1447745D03*
X1452426Y973825D03*
Y971525D03*
X1456371Y979552D03*
X1454520Y982756D03*
X1456371Y973143D03*
X1454520Y976347D03*
X1447545Y985579D03*
X1456804Y999684D03*
X1454953Y1002888D03*
Y1009297D03*
X1456804Y1012501D03*
X1447545Y1000079D03*
X1447345Y1014539D03*
X1456804Y1031727D03*
X1454953Y1028523D03*
Y1022114D03*
X1456803Y1018910D03*
X1454953Y1015705D03*
X1446934Y1028889D03*
X1452466Y1031794D03*
Y1029494D03*
Y1027194D03*
X1456804Y1025318D03*
X1458653Y1015705D03*
X1451253Y1047749D03*
X1445704Y1044544D03*
X1454953Y1034931D03*
X1456804Y1038136D03*
X1454953Y1041340D03*
X1456804Y1044544D03*
X1449404D03*
X1454953Y1047749D03*
X1453104Y1044544D03*
X1456804Y1063770D03*
X1458653Y1054157D03*
X1454954D03*
X1453104Y1057361D03*
Y1063770D03*
X1454954Y1060565D03*
X1456803Y1057361D03*
X1453103Y1050952D03*
X1445703Y1057361D03*
X1445704Y1063770D03*
X1447554Y1060565D03*
X1449403Y1057361D03*
X1449404Y1063770D03*
X1451254Y1054157D03*
X1445703Y1050952D03*
X1449404D03*
X1454953Y1066974D03*
X1445702Y1070178D03*
X1453104Y1076587D03*
X1456804D03*
Y1070178D03*
X1453104D03*
X1447553Y1073383D03*
X1449404Y1076587D03*
X1445704D03*
X1447553Y1079791D03*
X1451253Y1073383D03*
X1458653D03*
X1445704Y1082995D03*
X1456804Y1089404D03*
X1449404Y1095813D03*
X1454954Y1092607D03*
X1451254D03*
X1449403Y1089403D03*
X1447554Y1086199D03*
X1453103Y1082994D03*
X1458654Y1092607D03*
X1453103Y1095812D03*
X1447554Y1092607D03*
X1451254Y1086199D03*
X1454954D03*
X1456804Y1102221D03*
Y1121447D03*
X1449404D03*
X1456804Y1134264D03*
X1445703D03*
X1465620Y848176D03*
X1473020D03*
X1465620Y867401D03*
X1473020D03*
X1465620Y860993D03*
X1473020D03*
X1463771Y870606D03*
X1471171D03*
X1461920Y873810D03*
X1467471Y870606D03*
X1469320Y873810D03*
X1474871Y870606D03*
X1476720Y873810D03*
X1465620Y880219D03*
X1467471Y883423D03*
X1473020Y880219D03*
X1474871Y883423D03*
X1463771D03*
X1471171D03*
X1473020Y873810D03*
X1465620D03*
X1461920Y886627D03*
X1469320D03*
X1476720D03*
X1473020D03*
X1465620D03*
X1464204Y1095813D03*
X1477154Y1105426D03*
Y1111833D03*
X1464204Y1115039D03*
Y1121447D03*
X1471604Y1134264D03*
X1464204D03*
X1487820Y848176D03*
X1480420D03*
X1487820Y867401D03*
X1480420D03*
X1487820Y860993D03*
X1480420D03*
X1493371Y870606D03*
X1478571D03*
X1485971D03*
X1489671D03*
X1491520Y873810D03*
X1482271Y870606D03*
X1484120Y873810D03*
X1487820Y880219D03*
X1489671Y883423D03*
X1480420Y880219D03*
X1482271Y883423D03*
X1485971D03*
X1493371D03*
X1478571D03*
X1487820Y873810D03*
X1480420D03*
X1491520Y886627D03*
X1484120D03*
X1480420D03*
X1487820D03*
X1479004Y1006093D03*
X1486404Y1102221D03*
X1479003Y1108629D03*
X1488254Y1105426D03*
X1484554Y1111833D03*
X1482703Y1102220D03*
X1480854Y1111833D03*
Y1105426D03*
X1486403Y1108630D03*
X1488254Y1111833D03*
X1484554Y1105426D03*
X1479004Y1115039D03*
Y1121447D03*
X1493804D03*
X1486404D03*
X1482703Y1115038D03*
X1479004Y1134264D03*
X1493804D03*
X1486404D03*
X1495220Y848176D03*
Y867401D03*
X1502621D03*
X1495220Y860993D03*
X1502621D03*
X1500771Y870606D03*
X1508171D03*
X1497071D03*
X1498920Y873810D03*
X1504471Y870606D03*
X1506321Y873810D03*
X1495220Y880219D03*
X1497071Y883423D03*
X1502621Y880219D03*
X1504471Y883423D03*
X1500771D03*
X1495220Y873810D03*
X1502621D03*
X1506320Y893036D03*
X1498920Y886627D03*
X1506321D03*
X1495220D03*
X1502621D03*
X1510021D03*
X1506753Y1105426D03*
X1504904Y1102221D03*
X1501204D03*
X1499354Y1099017D03*
X1503053Y1118243D03*
X1510453D03*
X1501204Y1121447D03*
X1508603Y1121446D03*
X1510453Y1124650D03*
X1508603Y1127855D03*
X1501204Y1134264D03*
X1508603Y1140973D03*
X1504903D03*
X1517853Y1118243D03*
X1519703Y1121446D03*
X1516003Y1127855D03*
X1512303D03*
Y1121446D03*
X1516003D03*
X1517853Y1124650D03*
X1519703Y1127855D03*
X1514154Y1131059D03*
X1611475Y1259227D03*
X1714440Y1255381D03*
X1821083Y1252034D03*
G54D40*
X322500Y1391830D03*
X537477Y1395413D03*
X1298642Y1391830D03*
X1513618Y1395413D03*
G54D10*
X27559Y87795D03*
X40708Y631890D03*
Y1368897D03*
X51181Y1714961D03*
X373622Y87795D03*
X395670Y1714961D03*
X661023Y631890D03*
X707677Y1714961D03*
X800787Y87795D03*
X931692Y757874D03*
Y1072834D03*
Y1387795D03*
X1045865Y87795D03*
X1155708Y1714961D03*
X1271260Y631890D03*
X1461805Y1714961D03*
X1499606Y87795D03*
X1816771Y631890D03*
Y1368897D03*
X1806299Y1714961D03*
X1829921Y87795D03*
G54D36*
X238780Y1681456D03*
X230906Y1677519D03*
Y1682244D03*
X238780Y1686180D03*
Y1695629D03*
X230906Y1691692D03*
Y1696417D03*
X238780Y1700354D03*
Y1709803D03*
Y1714527D03*
X230906Y1705866D03*
Y1710590D03*
X254528Y1681456D03*
X246654Y1677519D03*
Y1682244D03*
X254528Y1686180D03*
Y1695629D03*
X246654Y1691692D03*
Y1696417D03*
X254528Y1700354D03*
Y1709803D03*
Y1714527D03*
X246654Y1705866D03*
Y1710590D03*
X270276Y1681456D03*
X262402Y1677519D03*
Y1682244D03*
X270276Y1686180D03*
Y1695629D03*
X262402Y1691692D03*
Y1696417D03*
X270276Y1700354D03*
Y1709803D03*
Y1714527D03*
X262402Y1705866D03*
Y1710590D03*
X286024Y1681456D03*
X278150Y1677519D03*
Y1682244D03*
X286024Y1686180D03*
Y1695629D03*
X278150Y1691692D03*
Y1696417D03*
X286024Y1700354D03*
Y1709803D03*
Y1714527D03*
X278150Y1705866D03*
Y1710590D03*
X297835Y1677519D03*
Y1682244D03*
X305709Y1681456D03*
Y1686180D03*
X297835Y1691692D03*
Y1696417D03*
X305709Y1695629D03*
Y1700354D03*
X297835Y1705866D03*
Y1710590D03*
X305709Y1709803D03*
Y1714527D03*
X313583Y1677519D03*
Y1682244D03*
X321457Y1681456D03*
Y1686180D03*
X313583Y1691692D03*
Y1696417D03*
X321457Y1695629D03*
Y1700354D03*
X313583Y1705866D03*
Y1710590D03*
X321457Y1709803D03*
Y1714527D03*
X329331Y1677519D03*
Y1682244D03*
X337205Y1681456D03*
Y1686180D03*
X329331Y1691692D03*
Y1696417D03*
X337205Y1695629D03*
Y1700354D03*
X329331Y1705866D03*
Y1710590D03*
X337205Y1709803D03*
Y1714527D03*
X345079Y1677519D03*
Y1682244D03*
X352953Y1681456D03*
Y1686180D03*
X345079Y1691692D03*
Y1696417D03*
X352953Y1695629D03*
Y1700354D03*
X345079Y1705866D03*
Y1710590D03*
X352953Y1709803D03*
Y1714527D03*
X495079Y1677519D03*
Y1682244D03*
Y1691692D03*
Y1696417D03*
Y1720039D03*
Y1724763D03*
X510827Y1677519D03*
X502953Y1681456D03*
X510827Y1682244D03*
X502953Y1686180D03*
X510827Y1691692D03*
X502953Y1695629D03*
X510827Y1696417D03*
X502953Y1700354D03*
X510827Y1720039D03*
X502953Y1723976D03*
X510827Y1724763D03*
X502953Y1728700D03*
X526575Y1677519D03*
X518701Y1681456D03*
X526575Y1682244D03*
X534449Y1681456D03*
X518701Y1686180D03*
X534449D03*
X526575Y1691692D03*
X518701Y1695629D03*
X526575Y1696417D03*
X534449Y1695629D03*
X518701Y1700354D03*
X534449D03*
X526575Y1720039D03*
X518701Y1723976D03*
X526575Y1724763D03*
X534449Y1723976D03*
X518701Y1728700D03*
X534449D03*
X542323Y1677519D03*
Y1682244D03*
X550197Y1681456D03*
Y1686180D03*
X542323Y1691692D03*
Y1696417D03*
X550197Y1695629D03*
Y1700354D03*
X542323Y1720039D03*
Y1724763D03*
X550197Y1723976D03*
Y1728700D03*
X562008Y1677519D03*
Y1682244D03*
Y1691692D03*
Y1696417D03*
Y1720039D03*
Y1724763D03*
X577756Y1677519D03*
X569882Y1681456D03*
X577756Y1682244D03*
X569882Y1686180D03*
X577756Y1691692D03*
X569882Y1695629D03*
X577756Y1696417D03*
X569882Y1700354D03*
X577756Y1720039D03*
X569882Y1723976D03*
X577756Y1724763D03*
X569882Y1728700D03*
X593504Y1677519D03*
X585630Y1681456D03*
X593504Y1682244D03*
X585630Y1686180D03*
X593504Y1691692D03*
X585630Y1695629D03*
X593504Y1696417D03*
X585630Y1700354D03*
X593504Y1720039D03*
X585630Y1723976D03*
X593504Y1724763D03*
X585630Y1728700D03*
X609252Y1677519D03*
X601378Y1681456D03*
X609252Y1682244D03*
X601378Y1686180D03*
X609252Y1691692D03*
X601378Y1695629D03*
X609252Y1696417D03*
X601378Y1700354D03*
X609252Y1720039D03*
X601378Y1723976D03*
X609252Y1724763D03*
X601378Y1728700D03*
X617126Y1681456D03*
Y1686180D03*
Y1695629D03*
Y1700354D03*
Y1723976D03*
Y1728700D03*
X1238780Y1677519D03*
Y1682244D03*
X1246654Y1681456D03*
Y1686180D03*
X1238780Y1691692D03*
Y1696417D03*
X1246654Y1695629D03*
Y1700354D03*
X1238780Y1705866D03*
Y1710590D03*
X1246654Y1709803D03*
Y1714527D03*
X1254528Y1677519D03*
Y1682244D03*
X1262402Y1681456D03*
Y1686180D03*
X1254528Y1691692D03*
Y1696417D03*
X1262402Y1695629D03*
Y1700354D03*
X1254528Y1705866D03*
Y1710590D03*
X1262402Y1709803D03*
Y1714527D03*
X1270276Y1677519D03*
Y1682244D03*
X1278150Y1681456D03*
Y1686180D03*
X1270276Y1691692D03*
Y1696417D03*
X1278150Y1695629D03*
Y1700354D03*
X1270276Y1705866D03*
Y1710590D03*
X1278150Y1709803D03*
Y1714527D03*
X1286024Y1677519D03*
Y1682244D03*
X1293898Y1681456D03*
Y1686180D03*
X1286024Y1691692D03*
Y1696417D03*
X1293898Y1695629D03*
Y1700354D03*
X1286024Y1705866D03*
Y1710590D03*
X1293898Y1709803D03*
Y1714527D03*
X1305709Y1677519D03*
Y1682244D03*
X1313583Y1681456D03*
Y1686180D03*
X1305709Y1691692D03*
Y1696417D03*
X1313583Y1695629D03*
Y1700354D03*
X1305709Y1705866D03*
Y1710590D03*
X1313583Y1709803D03*
Y1714527D03*
X1321457Y1677519D03*
Y1682244D03*
X1329331Y1681456D03*
Y1686180D03*
X1321457Y1691692D03*
Y1696417D03*
X1329331Y1695629D03*
Y1700354D03*
X1321457Y1705866D03*
Y1710590D03*
X1329331Y1709803D03*
Y1714527D03*
X1337205Y1677519D03*
Y1682244D03*
X1345079Y1681456D03*
Y1686180D03*
X1337205Y1691692D03*
Y1696417D03*
X1345079Y1695629D03*
Y1700354D03*
X1337205Y1705866D03*
Y1710590D03*
X1345079Y1709803D03*
Y1714527D03*
X1352953Y1677519D03*
Y1682244D03*
X1360827Y1681456D03*
Y1686180D03*
X1352953Y1691692D03*
Y1696417D03*
X1360827Y1695629D03*
Y1700354D03*
X1352953Y1705866D03*
Y1710590D03*
X1360827Y1709803D03*
Y1714527D03*
X1502953Y1677519D03*
Y1682244D03*
X1510827Y1681456D03*
Y1686180D03*
X1502953Y1691692D03*
Y1696417D03*
X1510827Y1695629D03*
Y1700354D03*
X1502953Y1720039D03*
Y1724763D03*
X1510827Y1723976D03*
Y1728700D03*
X1518701Y1677519D03*
Y1682244D03*
X1526575Y1681456D03*
Y1686180D03*
X1518701Y1691692D03*
Y1696417D03*
X1526575Y1695629D03*
Y1700354D03*
X1518701Y1720039D03*
Y1724763D03*
X1526575Y1723976D03*
Y1728700D03*
X1534449Y1677519D03*
Y1682244D03*
X1542323Y1681456D03*
Y1686180D03*
X1534449Y1691692D03*
Y1696417D03*
X1542323Y1695629D03*
Y1700354D03*
X1534449Y1720039D03*
Y1724763D03*
X1542323Y1723976D03*
Y1728700D03*
X1550197Y1677519D03*
Y1682244D03*
X1558071Y1681456D03*
Y1686180D03*
X1550197Y1691692D03*
Y1696417D03*
X1558071Y1695629D03*
Y1700354D03*
X1550197Y1720039D03*
Y1724763D03*
X1558071Y1723976D03*
Y1728700D03*
X1569882Y1677519D03*
Y1682244D03*
Y1691692D03*
Y1696417D03*
Y1720039D03*
Y1724763D03*
X1585630Y1677519D03*
X1577756Y1681456D03*
X1585630Y1682244D03*
X1577756Y1686180D03*
X1585630Y1691692D03*
X1577756Y1695629D03*
X1585630Y1696417D03*
X1577756Y1700354D03*
X1585630Y1720039D03*
X1577756Y1723976D03*
X1585630Y1724763D03*
X1577756Y1728700D03*
X1601378Y1677519D03*
X1593504Y1681456D03*
X1601378Y1682244D03*
X1593504Y1686180D03*
X1601378Y1691692D03*
X1593504Y1695629D03*
X1601378Y1696417D03*
X1593504Y1700354D03*
X1601378Y1720039D03*
X1593504Y1723976D03*
X1601378Y1724763D03*
X1593504Y1728700D03*
X1617126Y1677519D03*
X1609252Y1681456D03*
X1617126Y1682244D03*
X1609252Y1686180D03*
X1617126Y1691692D03*
X1609252Y1695629D03*
X1617126Y1696417D03*
X1609252Y1700354D03*
X1617126Y1720039D03*
X1609252Y1723976D03*
X1617126Y1724763D03*
X1609252Y1728700D03*
X1625000Y1681456D03*
Y1686180D03*
Y1695629D03*
Y1700354D03*
Y1723976D03*
Y1728700D03*
G54D37*
X277098Y185236D03*
X395208D03*
G54D32*
X205159Y1430034D03*
X393067Y1354446D03*
X422833D03*
X453169D03*
X468443Y1379662D03*
X482543Y1353962D03*
X718638Y1429579D03*
X1178470Y1466363D03*
X1369208Y1353946D03*
X1398974D03*
X1429310D03*
X1444043Y1379362D03*
X1459076Y1353946D03*
X1679944Y1463655D03*
X1836248Y269763D03*
Y299056D03*
G54D30*
X174685Y637367D03*
X174393Y668511D03*
X526478Y1439952D03*
X1502956Y1439530D03*
X1682882Y618174D03*
Y669109D03*
X1769790Y194789D03*
X1799350D03*
G54D48*
X493500Y246362D03*
X559236Y1441207D03*
G54D51*
X688500Y1601900D03*
X1041435Y153357D03*
X1056225Y153131D03*
X1099970Y1702570D03*
G54D66*
X1133779Y1653543D03*
G54D38*
X278126Y676260D03*
Y700414D03*
X395771Y1242785D03*
X420171D03*
X444493D03*
X468893D03*
X493293D03*
X1371912D03*
X1396312D03*
X1420634D03*
X1445034D03*
X1469434D03*
G54D28*
X159474Y1320753D03*
X183847Y1320778D03*
X208247D03*
X275289Y575702D03*
Y599861D03*
Y624015D03*
Y648169D03*
X673093Y1320778D03*
X697466Y1320803D03*
X721866D03*
X1100800Y251488D03*
X1100700Y275788D03*
X1131100Y1357088D03*
X1155500D03*
X1179900D03*
X1577000Y591888D03*
Y616388D03*
Y640888D03*
Y665288D03*
Y689788D03*
Y714288D03*
X1634259Y1354374D03*
X1658632Y1354399D03*
X1683032D03*
G54D78*
X1902608Y988322D03*
X1902682Y1351295D03*
X1951178Y1349597D03*
X1993618Y1349897D03*
G54D75*
X1881720Y988279D03*
X1881211Y1350983D03*
X1930200Y1349548D03*
X1972697Y1349606D03*
G54D23*
X40120Y744554D03*
Y1000853D03*
Y1287664D03*
X69820Y744554D03*
Y1000853D03*
Y1287664D03*
X99520Y744554D03*
Y1000853D03*
Y1287664D03*
X129220Y744554D03*
Y1000853D03*
Y1287664D03*
X158920Y744554D03*
Y1000853D03*
Y1287664D03*
X188620Y744554D03*
Y1000853D03*
Y1287664D03*
X218320Y744554D03*
Y1000853D03*
Y1287664D03*
X248020Y744554D03*
Y1000853D03*
Y1287664D03*
X633320Y744554D03*
Y1000853D03*
Y1287664D03*
X663020Y744554D03*
Y1000853D03*
Y1287664D03*
X692720Y744554D03*
Y1000853D03*
Y1287664D03*
X722420Y744554D03*
Y1000853D03*
Y1287664D03*
X752120Y744554D03*
Y1000853D03*
Y1287664D03*
X781820Y744554D03*
Y1000853D03*
Y1287664D03*
X811520Y744554D03*
Y1000853D03*
Y1287664D03*
X841220Y744554D03*
Y1000853D03*
Y1287664D03*
X1016262Y744554D03*
Y1000853D03*
Y1287664D03*
X1045962Y744554D03*
Y1000853D03*
Y1287664D03*
X1075662Y744554D03*
Y1000853D03*
Y1287664D03*
X1105362Y744554D03*
Y1000853D03*
Y1287664D03*
X1135062Y744554D03*
Y1000853D03*
Y1287664D03*
X1164762Y744554D03*
Y1000853D03*
Y1287664D03*
X1194462Y744554D03*
Y1000853D03*
Y1287664D03*
X1224162Y744554D03*
Y1000853D03*
Y1287664D03*
X1609462Y744554D03*
Y1000853D03*
Y1287664D03*
X1639162Y744554D03*
Y1000853D03*
Y1287664D03*
X1668862Y744554D03*
Y1000853D03*
Y1287664D03*
X1698562Y744554D03*
Y1000853D03*
Y1287664D03*
X1728262Y744554D03*
Y1000853D03*
Y1287664D03*
X1757962Y744554D03*
Y1000853D03*
Y1287664D03*
X1787662Y744554D03*
Y1000853D03*
Y1287664D03*
X1817362Y744554D03*
Y1000853D03*
Y1287664D03*
G54D61*
X928739Y321653D03*
G54D33*
X250326Y185236D03*
X368437D03*
G54D62*
X916545Y309459D03*
X911494Y321653D03*
X916545Y333847D03*
X940933Y309459D03*
X928739Y304408D03*
Y338898D03*
X940933Y333847D03*
X945984Y321653D03*
G54D68*
X1247638Y269488D03*
X1405118Y112008D03*
X1766929Y1714960D03*
G54D13*
X19685Y-29134D03*
Y1803261D03*
X1837795Y-29134D03*
Y1803261D03*
X2081889Y-29134D03*
Y1803261D03*
G54D69*
X1405876Y1453298D03*
X1430204Y1452014D03*
G54D18*
X38346Y1420330D03*
X117932Y605380D03*
X763601Y605413D03*
X1094074Y605380D03*
X1739706Y605455D03*
X1819208Y1420330D03*
G54D21*
X49280Y337402D03*
X41870Y1511291D03*
X441043Y1672205D03*
Y1718465D03*
X1416437Y1672204D03*
Y1718464D03*
X1808192Y1569255D03*
X1812980Y502472D03*
G54D39*
X306772Y991220D03*
X350099Y811121D03*
X356063Y1171318D03*
X531240Y811121D03*
X525276Y1171318D03*
X574567Y991220D03*
X1282914D03*
X1326240Y811121D03*
X1332205Y1171318D03*
X1507382Y811121D03*
X1501418Y1171318D03*
X1550709Y991220D03*
G54D54*
X791280Y1704890D03*
X1066280D03*
G54D34*
X238780Y1648385D03*
X230906Y1644448D03*
X238780Y1662558D03*
X230906Y1658621D03*
X238780Y1676732D03*
X230906Y1672795D03*
X238780Y1690905D03*
X230906Y1686968D03*
X238780Y1705078D03*
X230906Y1701141D03*
Y1715314D03*
X238780Y1719251D03*
X230906Y1729488D03*
X238780Y1733425D03*
X254528Y1648385D03*
X246654Y1644448D03*
X254528Y1662558D03*
X246654Y1658621D03*
X254528Y1676732D03*
X246654Y1672795D03*
X254528Y1690905D03*
X246654Y1686968D03*
X254528Y1705078D03*
X246654Y1701141D03*
Y1715314D03*
X254528Y1719251D03*
X246654Y1729488D03*
X254528Y1733425D03*
X270276Y1648385D03*
X262402Y1644448D03*
X270276Y1662558D03*
X262402Y1658621D03*
X270276Y1676732D03*
X262402Y1672795D03*
X270276Y1690905D03*
X262402Y1686968D03*
X270276Y1705078D03*
X262402Y1701141D03*
Y1715314D03*
X270276Y1719251D03*
X262402Y1729488D03*
X270276Y1733425D03*
X286024Y1648385D03*
X278150Y1644448D03*
X286024Y1662558D03*
X278150Y1658621D03*
X286024Y1676732D03*
X278150Y1672795D03*
X286024Y1690905D03*
X278150Y1686968D03*
X286024Y1705078D03*
X278150Y1701141D03*
Y1715314D03*
X286024Y1719251D03*
X278150Y1729488D03*
X286024Y1733425D03*
X297835Y1672795D03*
X305709Y1676732D03*
X297835Y1686968D03*
X305709Y1690905D03*
X297835Y1701141D03*
X305709Y1705078D03*
X297835Y1715314D03*
X305709Y1719251D03*
X297835Y1729488D03*
X305709Y1733425D03*
X313583Y1672795D03*
X321457Y1676732D03*
X313583Y1686968D03*
X321457Y1690905D03*
X313583Y1701141D03*
X321457Y1705078D03*
X313583Y1715314D03*
X321457Y1719251D03*
X313583Y1729488D03*
X321457Y1733425D03*
X329331Y1672795D03*
X337205Y1676732D03*
X329331Y1686968D03*
X337205Y1690905D03*
X329331Y1701141D03*
X337205Y1705078D03*
X329331Y1715314D03*
X337205Y1719251D03*
X329331Y1729488D03*
X337205Y1733425D03*
X345079Y1672795D03*
X352953Y1676732D03*
X345079Y1686968D03*
X352953Y1690905D03*
X345079Y1701141D03*
X352953Y1705078D03*
X345079Y1715314D03*
X352953Y1719251D03*
X345079Y1729488D03*
X352953Y1733425D03*
X495079Y1672795D03*
Y1686968D03*
Y1701141D03*
Y1715314D03*
Y1729488D03*
X510827Y1672795D03*
X502953Y1676732D03*
X518701D03*
X510827Y1686968D03*
X502953Y1690905D03*
X518701D03*
X510827Y1701141D03*
X502953Y1705078D03*
X518701D03*
X510827Y1715314D03*
X502953Y1719251D03*
X518701D03*
X510827Y1729488D03*
X502953Y1733425D03*
X518701D03*
X526575Y1672795D03*
X534449Y1676732D03*
X526575Y1686968D03*
X534449Y1690905D03*
X526575Y1701141D03*
X534449Y1705078D03*
X526575Y1715314D03*
X534449Y1719251D03*
X526575Y1729488D03*
X534449Y1733425D03*
X542323Y1672795D03*
X550197Y1676732D03*
X542323Y1686968D03*
X550197Y1690905D03*
X542323Y1701141D03*
X550197Y1705078D03*
X542323Y1715314D03*
X550197Y1719251D03*
X542323Y1729488D03*
X550197Y1733425D03*
X562008Y1672795D03*
Y1686968D03*
Y1701141D03*
Y1715314D03*
Y1729488D03*
X577756Y1672795D03*
X569882Y1676732D03*
X577756Y1686968D03*
X569882Y1690905D03*
X577756Y1701141D03*
X569882Y1705078D03*
X577756Y1715314D03*
X569882Y1719251D03*
X577756Y1729488D03*
X569882Y1733425D03*
X593504Y1672795D03*
X585630Y1676732D03*
X593504Y1686968D03*
X585630Y1690905D03*
X593504Y1701141D03*
X585630Y1705078D03*
X593504Y1715314D03*
X585630Y1719251D03*
X593504Y1729488D03*
X585630Y1733425D03*
X609252Y1672795D03*
X601378Y1676732D03*
X609252Y1686968D03*
X601378Y1690905D03*
X609252Y1701141D03*
X601378Y1705078D03*
X609252Y1715314D03*
X601378Y1719251D03*
X609252Y1729488D03*
X601378Y1733425D03*
X617126Y1676732D03*
Y1690905D03*
Y1705078D03*
Y1719251D03*
Y1733425D03*
X1238780Y1672795D03*
X1246654Y1676732D03*
X1238780Y1686968D03*
X1246654Y1690905D03*
X1238780Y1701141D03*
X1246654Y1705078D03*
X1238780Y1715314D03*
X1246654Y1719251D03*
X1238780Y1729488D03*
X1246654Y1733425D03*
X1254528Y1672795D03*
X1262402Y1676732D03*
X1254528Y1686968D03*
X1262402Y1690905D03*
X1254528Y1701141D03*
X1262402Y1705078D03*
X1254528Y1715314D03*
X1262402Y1719251D03*
X1254528Y1729488D03*
X1262402Y1733425D03*
X1270276Y1672795D03*
X1278150Y1676732D03*
X1270276Y1686968D03*
X1278150Y1690905D03*
X1270276Y1701141D03*
X1278150Y1705078D03*
X1270276Y1715314D03*
X1278150Y1719251D03*
X1270276Y1729488D03*
X1278150Y1733425D03*
X1286024Y1672795D03*
X1293898Y1676732D03*
X1286024Y1686968D03*
X1293898Y1690905D03*
X1286024Y1701141D03*
X1293898Y1705078D03*
X1286024Y1715314D03*
X1293898Y1719251D03*
X1286024Y1729488D03*
X1293898Y1733425D03*
X1305709Y1672795D03*
X1313583Y1676732D03*
X1305709Y1686968D03*
X1313583Y1690905D03*
X1305709Y1701141D03*
X1313583Y1705078D03*
X1305709Y1715314D03*
X1313583Y1719251D03*
X1305709Y1729488D03*
X1313583Y1733425D03*
X1321457Y1672795D03*
X1329331Y1676732D03*
X1321457Y1686968D03*
X1329331Y1690905D03*
X1321457Y1701141D03*
X1329331Y1705078D03*
X1321457Y1715314D03*
X1329331Y1719251D03*
X1321457Y1729488D03*
X1329331Y1733425D03*
X1337205Y1672795D03*
X1345079Y1676732D03*
X1337205Y1686968D03*
X1345079Y1690905D03*
X1337205Y1701141D03*
X1345079Y1705078D03*
X1337205Y1715314D03*
X1345079Y1719251D03*
X1337205Y1729488D03*
X1345079Y1733425D03*
X1352953Y1672795D03*
X1360827Y1676732D03*
X1352953Y1686968D03*
X1360827Y1690905D03*
X1352953Y1701141D03*
X1360827Y1705078D03*
X1352953Y1715314D03*
X1360827Y1719251D03*
X1352953Y1729488D03*
X1360827Y1733425D03*
X1502953Y1672795D03*
X1510827Y1676732D03*
X1502953Y1686968D03*
X1510827Y1690905D03*
X1502953Y1701141D03*
X1510827Y1705078D03*
X1502953Y1715314D03*
X1510827Y1719251D03*
X1502953Y1729488D03*
X1510827Y1733425D03*
X1518701Y1672795D03*
X1526575Y1676732D03*
X1518701Y1686968D03*
X1526575Y1690905D03*
X1518701Y1701141D03*
X1526575Y1705078D03*
X1518701Y1715314D03*
X1526575Y1719251D03*
X1518701Y1729488D03*
X1526575Y1733425D03*
X1534449Y1672795D03*
X1542323Y1676732D03*
X1534449Y1686968D03*
X1542323Y1690905D03*
X1534449Y1701141D03*
X1542323Y1705078D03*
X1534449Y1715314D03*
X1542323Y1719251D03*
X1534449Y1729488D03*
X1542323Y1733425D03*
X1550197Y1672795D03*
X1558071Y1676732D03*
X1550197Y1686968D03*
X1558071Y1690905D03*
X1550197Y1701141D03*
X1558071Y1705078D03*
X1550197Y1715314D03*
X1558071Y1719251D03*
X1550197Y1729488D03*
X1558071Y1733425D03*
X1569882Y1672795D03*
Y1686968D03*
Y1701141D03*
Y1715314D03*
Y1729488D03*
X1585630Y1672795D03*
X1577756Y1676732D03*
X1585630Y1686968D03*
X1577756Y1690905D03*
X1585630Y1701141D03*
X1577756Y1705078D03*
X1585630Y1715314D03*
X1577756Y1719251D03*
X1585630Y1729488D03*
X1577756Y1733425D03*
X1601378Y1672795D03*
X1593504Y1676732D03*
X1601378Y1686968D03*
X1593504Y1690905D03*
X1601378Y1701141D03*
X1593504Y1705078D03*
X1601378Y1715314D03*
X1593504Y1719251D03*
X1601378Y1729488D03*
X1593504Y1733425D03*
X1617126Y1672795D03*
X1609252Y1676732D03*
X1625000D03*
X1617126Y1686968D03*
X1609252Y1690905D03*
X1625000D03*
X1617126Y1701141D03*
X1609252Y1705078D03*
X1625000D03*
X1617126Y1715314D03*
X1609252Y1719251D03*
X1625000D03*
X1617126Y1729488D03*
X1609252Y1733425D03*
X1625000D03*
G54D45*
X441043Y1698268D03*
X1416437Y1698267D03*
G54D56*
X805690Y204724D03*
X1057658D03*
G54D20*
X41492Y290637D03*
X44833Y1659909D03*
X61340Y384362D03*
X61250Y396142D03*
X49250Y396332D03*
X49400Y384392D03*
X47618Y413113D03*
X47619Y421155D03*
X56799Y1524094D03*
Y1528094D03*
Y1532094D03*
Y1544094D03*
Y1548094D03*
Y1552094D03*
Y1556094D03*
X54333Y1604359D03*
X50900Y1677775D03*
X65881Y305426D03*
X72774Y1549669D03*
X66906Y1598324D03*
Y1603280D03*
X84274Y1517619D03*
X81038Y1536899D03*
X91538Y1539399D03*
X84700Y1627000D03*
X99274Y1526019D03*
X126225Y504368D03*
X120225D03*
Y510368D03*
X126225Y516368D03*
X120225D03*
X112749Y1524594D03*
Y1540594D03*
Y1544594D03*
Y1548594D03*
Y1536594D03*
Y1564594D03*
Y1560594D03*
X132225Y504368D03*
Y510368D03*
X132401Y516368D03*
X129670Y1563160D03*
X153271Y1540961D03*
X153138Y1549032D03*
X166986Y575918D03*
X161321Y1540858D03*
X161374Y1549073D03*
X189800Y705062D03*
X208312Y576125D03*
X196526Y567825D03*
X208312Y581085D03*
Y578605D03*
X197423Y601496D03*
X194059Y604901D03*
X208312Y615085D03*
Y610125D03*
Y612605D03*
X194059Y638901D03*
X197423Y635496D03*
X208312Y649085D03*
Y644125D03*
Y646605D03*
X213912Y576125D03*
X220668Y574131D03*
X223775D03*
X224064Y568113D03*
X221464D03*
X213912Y578605D03*
Y581085D03*
X217556Y590575D03*
X217561Y582131D03*
Y579531D03*
X223775Y587731D03*
X223759Y590675D03*
X220652D03*
X223775Y584531D03*
X220668Y576731D03*
Y579331D03*
X223775Y581931D03*
Y579331D03*
Y576731D03*
X220668Y581931D03*
Y608131D03*
X223775D03*
X224064Y602113D03*
X221464D03*
X223403Y596820D03*
Y594220D03*
X213912Y612605D03*
Y615085D03*
Y610125D03*
X217561Y616131D03*
Y613531D03*
X217556Y624575D03*
X223759Y624675D03*
X220652D03*
X223775Y618531D03*
X220668Y610731D03*
Y613331D03*
X223775Y615931D03*
Y613331D03*
Y610731D03*
X220668Y615931D03*
X223775Y621731D03*
X223403Y630820D03*
Y628220D03*
X224064Y636113D03*
X221464D03*
X213912Y646605D03*
Y649085D03*
Y644125D03*
X217561Y650131D03*
Y647531D03*
X223775Y655731D03*
Y652531D03*
X220668Y644731D03*
Y647331D03*
Y642131D03*
X223775Y649931D03*
Y647331D03*
Y644731D03*
Y642131D03*
X220668Y649931D03*
X217556Y658575D03*
X223403Y664820D03*
X223759Y658675D03*
X220652D03*
X217510Y668712D03*
X225167Y672006D03*
X222567D03*
X219967D03*
X217367D03*
X211348Y688087D03*
Y685287D03*
X214100Y687376D03*
Y690376D03*
Y684376D03*
Y681376D03*
Y678376D03*
X211348Y690787D03*
Y693587D03*
X214100Y693576D03*
X224506Y698138D03*
Y700738D03*
X221906Y698138D03*
Y700738D03*
X219306D03*
Y698138D03*
X231864Y568113D03*
X229264D03*
X226664D03*
X238393Y570490D03*
X240993D03*
X229264Y602113D03*
X226664D03*
X226003Y594220D03*
Y596820D03*
X228603Y594220D03*
Y596820D03*
X231864Y602113D03*
X233803Y594220D03*
Y596820D03*
X231203Y594220D03*
Y596820D03*
X238393Y604490D03*
X240993D03*
Y596820D03*
X238393D03*
X240993Y594220D03*
X238393D03*
X226003Y628220D03*
Y630820D03*
X228603Y628220D03*
Y630820D03*
X231864Y636113D03*
X233803Y628220D03*
Y630820D03*
X231203Y628220D03*
Y630820D03*
X229264Y636113D03*
X226664D03*
X238393Y638490D03*
X240993D03*
Y630820D03*
X238393D03*
X240993Y628220D03*
X238393D03*
X228603Y664820D03*
X233803D03*
X231203D03*
X226003D03*
X230367Y672006D03*
X227767D03*
X227106Y698138D03*
Y700738D03*
X246400Y563162D03*
X263580Y218627D03*
X318651Y22921D03*
X320825Y159062D03*
X410700Y1658460D03*
X435340Y125346D03*
X435240Y1609200D03*
X433383Y1602629D03*
X450380Y104647D03*
X440019Y1576809D03*
X442128Y1574879D03*
X441308Y1602654D03*
X505055Y1387601D03*
Y1382301D03*
Y1396001D03*
Y1398601D03*
Y1390201D03*
X563634Y1334315D03*
X561034D03*
X612670Y142872D03*
X612520Y154812D03*
X624610Y142842D03*
X624520Y154622D03*
X702975Y414864D03*
X739206Y608020D03*
Y603064D03*
X758830Y1674823D03*
X819114Y115223D03*
X824498Y145198D03*
X831114Y115223D03*
X829114Y150273D03*
X854577Y99651D03*
X876124Y66072D03*
Y86072D03*
Y106072D03*
Y126072D03*
X887869Y386618D03*
X881372Y920655D03*
X898062Y976652D03*
Y969716D03*
X942646Y400793D03*
X946865Y974077D03*
X953235Y972642D03*
X946938Y991162D03*
X943720Y985772D03*
X956022Y1620730D03*
X953022D03*
Y1632730D03*
X956022D03*
Y1629730D03*
X953022D03*
X956022Y1626730D03*
X953022D03*
Y1623730D03*
X956022D03*
X963610Y981292D03*
X959535Y990477D03*
X963780Y997496D03*
X962022Y1620730D03*
X959022D03*
Y1632730D03*
X962022D03*
Y1629730D03*
X959022D03*
X962022Y1626730D03*
X959022D03*
Y1623730D03*
X962022D03*
X978403Y-9022D03*
Y-13978D03*
Y-19022D03*
Y-23978D03*
Y6022D03*
Y10978D03*
Y20978D03*
Y16022D03*
X988835Y185443D03*
X989500Y376362D03*
X985672Y432961D03*
X987662Y1620870D03*
Y1629870D03*
Y1626870D03*
Y1623870D03*
Y1632870D03*
X1002500Y266862D03*
X991770Y418835D03*
X992608Y432961D03*
X1002640Y594692D03*
X990662Y1620870D03*
X993662D03*
Y1629870D03*
X990662D03*
X993662Y1626870D03*
X990662D03*
Y1623870D03*
X993662D03*
X990662Y1632870D03*
X993662D03*
X1001810Y1662700D03*
Y1665200D03*
X1018000Y263862D03*
X1022000Y264362D03*
X1014500Y263862D03*
X1010500D03*
X1018000Y266862D03*
X1010500D03*
X1006500D03*
X1014500D03*
X1011611Y430038D03*
X1019252Y1620870D03*
X1022252D03*
Y1623870D03*
Y1626870D03*
X1019252Y1623870D03*
Y1626870D03*
X1019910Y1662700D03*
Y1665200D03*
X1025000Y264362D03*
X1038220Y589862D03*
X1030980Y598722D03*
X1023740Y596152D03*
X1036480Y596272D03*
X1025252Y1620870D03*
Y1623870D03*
Y1626870D03*
X1023580Y1662700D03*
Y1665200D03*
X1027370Y1662700D03*
Y1665200D03*
X1040924Y286073D03*
X1043720Y589362D03*
X1050200Y598062D03*
X1050390Y604172D03*
X1053200Y612162D03*
X1050721Y1633043D03*
X1053721D03*
Y1624043D03*
Y1627043D03*
Y1630043D03*
X1050721Y1624043D03*
Y1627043D03*
Y1630043D03*
X1053721Y1621043D03*
X1050721D03*
X1044850Y1665050D03*
Y1662550D03*
X1067718Y288500D03*
X1070618D03*
X1056280Y601232D03*
X1056721Y1633043D03*
Y1624043D03*
Y1627043D03*
Y1630043D03*
Y1621043D03*
X1095900Y1646935D03*
X1095649Y1638875D03*
X1099457D03*
X1104457Y1675490D03*
X1120544Y312200D03*
X1129995Y301637D03*
X1150914Y197407D03*
X1148354Y222677D03*
X1150272Y638346D03*
X1160720Y180862D03*
X1165000Y190962D03*
X1162500D03*
X1164300Y197262D03*
X1163732Y204887D03*
X1160732D03*
X1158172Y230157D03*
X1159912Y638216D03*
X1166722Y636206D03*
X1158762Y642266D03*
X1168402Y642136D03*
X1159930Y1645632D03*
X1164830D03*
X1161613Y1669112D03*
X1173065Y194174D03*
X1172865Y210174D03*
X1172795Y222174D03*
X1180398Y289814D03*
X1171540Y310902D03*
X1176362Y636076D03*
X1180262Y642216D03*
X1181930Y1645632D03*
X1186830D03*
X1175830D03*
X1170930D03*
X1183613Y1669112D03*
X1172613D03*
X1189902Y642086D03*
X1192500Y1645942D03*
X1197400D03*
X1194183Y1669422D03*
X1192340Y1691422D03*
X1197240D03*
X1194023Y1714902D03*
X1206093Y120362D03*
X1214593Y168962D03*
X1208518Y174162D03*
X1203858Y185451D03*
X1208365Y271151D03*
X1210457Y1658415D03*
X1218810Y1691732D03*
X1213910D03*
X1203110Y1691467D03*
X1208010D03*
X1215593Y1715212D03*
X1204793Y1714947D03*
X1228704Y112122D03*
X1223100Y127300D03*
X1226093Y152792D03*
X1227500Y380400D03*
X1242520Y165362D03*
X1236593Y209562D03*
X1236584Y217462D03*
X1245614Y227462D03*
X1266093Y129962D03*
X1256093Y143462D03*
X1264685Y175506D03*
X1279485Y105752D03*
X1278949Y123567D03*
X1282293Y248962D03*
X1275557Y269477D03*
Y272436D03*
X1282653Y269446D03*
X1278557Y272436D03*
Y269477D03*
X1272557Y272436D03*
X1287795Y-29033D03*
Y-33989D03*
Y-9033D03*
Y-13989D03*
Y-19033D03*
Y-23989D03*
Y967D03*
Y-3989D03*
X1293430Y84072D03*
X1294354Y105912D03*
X1295053Y140181D03*
X1292293Y143162D03*
X1287943Y233748D03*
X1284437Y230280D03*
X1293893Y237962D03*
X1286611Y260908D03*
X1295887Y315571D03*
X1314741Y68652D03*
X1300454Y95302D03*
X1302964Y124633D03*
X1301993Y140462D03*
X1313950Y261612D03*
X1308790Y290172D03*
X1302450Y290072D03*
X1307798Y287561D03*
X1313246Y287631D03*
X1308220Y304262D03*
X1303120Y304162D03*
X1330102Y59025D03*
X1327920Y84418D03*
X1316478Y92970D03*
X1330273Y128373D03*
X1326493Y249562D03*
X1317893Y257462D03*
X1328393Y264262D03*
X1339280Y126175D03*
X1356223Y131569D03*
X1362793Y145262D03*
X1366124Y101529D03*
X1377597Y197604D03*
X1375300Y208422D03*
X1378452Y236055D03*
X1389609Y145291D03*
X1389443Y147859D03*
X1386780Y197668D03*
X1395321D03*
X1409558Y151948D03*
Y156904D03*
X1401240Y171672D03*
X1404071Y197668D03*
X1412851D03*
X1398700Y1597800D03*
X1436436Y300319D03*
X1456423Y209362D03*
X1453823Y205982D03*
X1445777Y362021D03*
X1449296Y410497D03*
X1451580Y1627990D03*
X1462777Y362021D03*
X1470877Y374496D03*
X1463277Y406446D03*
X1470954D03*
X1476570Y1657974D03*
X1480154Y-29033D03*
Y-33989D03*
Y-9033D03*
Y-13989D03*
Y-19033D03*
Y-23989D03*
Y967D03*
Y-3989D03*
X1481155Y1387742D03*
X1481255Y1382042D03*
X1481155Y1396342D03*
Y1398942D03*
Y1390342D03*
X1478724Y1637189D03*
X1505821Y215802D03*
X1524770Y195792D03*
X1521201Y215551D03*
X1531750Y199762D03*
X1529610Y211614D03*
X1532590Y225432D03*
X1561494Y584292D03*
X1604040Y219692D03*
X1604290Y242472D03*
X1636393Y181778D03*
X1632899Y213012D03*
X1670004Y537065D03*
Y543065D03*
Y531065D03*
X1683394Y469878D03*
X1683476Y473378D03*
X1684356Y476290D03*
X1681602Y485180D03*
X1684356Y485628D03*
X1677464Y491790D03*
X1682004Y537065D03*
X1682180Y543065D03*
X1676004D03*
X1682004Y531065D03*
X1676004D03*
X1697648Y463724D03*
X1693648D03*
X1692883Y703943D03*
X1709027Y655141D03*
X1725473Y474859D03*
X1754307Y262186D03*
X1751068Y262123D03*
X1754245Y269724D03*
X1751068Y266048D03*
X1754307Y266111D03*
X1754414Y275329D03*
X1752165Y273901D03*
X1749565D03*
X1751006Y269661D03*
X1749595Y276711D03*
X1752195D03*
X1748989Y380206D03*
X1764955Y301951D03*
X1768757Y380498D03*
X1793061Y24659D03*
X1828880Y1626595D03*
Y1646595D03*
Y1666595D03*
Y1686595D03*
X1840691Y329470D03*
Y349470D03*
Y369470D03*
Y389470D03*
Y409470D03*
Y429470D03*
Y449470D03*
Y469470D03*
Y489470D03*
Y509470D03*
Y529470D03*
Y549470D03*
Y569470D03*
Y589470D03*
Y669470D03*
Y1329470D03*
Y1409470D03*
Y1429470D03*
Y1449470D03*
Y1469470D03*
Y1489470D03*
Y1509470D03*
Y1529470D03*
Y1549470D03*
Y1569470D03*
Y1589470D03*
X1854470Y112379D03*
Y152379D03*
Y172379D03*
Y192379D03*
Y212379D03*
Y232379D03*
Y252379D03*
Y272379D03*
Y292379D03*
G54D60*
X922441Y154311D03*
Y243799D03*
G54D12*
X14092Y287115D03*
X17371Y49388D03*
X22223Y388057D03*
X29509Y398132D03*
X29962Y401000D03*
X24700Y765600D03*
X37371Y49388D03*
X36255Y304972D03*
X42809Y360862D03*
X39410Y384582D03*
X39226Y395346D03*
X33020Y382822D03*
X36524Y398013D03*
X30680Y438142D03*
X58379Y69340D03*
X60379Y66844D03*
Y71836D03*
X60692Y87118D03*
X54920Y185039D03*
Y177165D03*
X46834Y360862D03*
X55190D03*
X53825Y421746D03*
X54762Y444993D03*
X53800Y435451D03*
X58658Y754145D03*
X55177Y1322328D03*
X55277Y1326068D03*
X46994Y1663165D03*
X69058Y3010D03*
X79047Y23978D03*
X74091D03*
X72091Y25974D03*
X73020Y37106D03*
Y48720D03*
X67335Y69340D03*
X65335Y66844D03*
Y71836D03*
X65648Y87118D03*
X71379Y72844D03*
Y77836D03*
X76335Y72844D03*
Y77836D03*
X78335Y75340D03*
X69379D03*
X71772Y421746D03*
X75490Y432519D03*
X68365Y443677D03*
X64150Y434972D03*
X74340Y663422D03*
X76365Y699244D03*
X76565Y717949D03*
X72315Y717414D03*
X64325Y715674D03*
X75564Y1509952D03*
X78120Y1512936D03*
Y1521336D03*
X75922Y1564874D03*
Y1556474D03*
X73429Y1570008D03*
X78415D03*
X73832Y1689362D03*
X77833Y1689162D03*
X89058Y3010D03*
X81196Y17042D03*
Y22034D03*
X86152Y17042D03*
Y22034D03*
X95369Y17042D03*
Y22034D03*
X79196Y19538D03*
X88152D03*
X93369D03*
X88264Y23978D03*
X93220D03*
X86264Y25974D03*
X95220D03*
X81047D03*
X94279Y37106D03*
X87193D03*
X80106D03*
X94279Y48720D03*
X87193D03*
X80106D03*
X80379Y69340D03*
X89335D03*
X82379Y66844D03*
Y71836D03*
X87335Y66844D03*
Y71836D03*
X91379Y75340D03*
X93379Y72844D03*
Y77836D03*
X86490Y200787D03*
Y208661D03*
X85960Y224409D03*
X85788Y240157D03*
X90700Y282762D03*
Y300262D03*
X87654Y376026D03*
X87520Y386502D03*
X94811Y510173D03*
X80460Y655672D03*
X83100Y649762D03*
X82735Y717949D03*
X87865Y714394D03*
X85165D03*
X81225Y715854D03*
X79635Y717949D03*
X85835Y718049D03*
X93295Y762019D03*
X92071Y1492888D03*
X80649Y1509944D03*
X93544Y1510099D03*
X88459Y1510107D03*
X90998Y1513037D03*
Y1521437D03*
X84048Y1578008D03*
X90713Y1585852D03*
Y1589852D03*
Y1593867D03*
X90788Y1611821D03*
Y1605867D03*
Y1623821D03*
X90698Y1638362D03*
Y1634362D03*
X86245Y1690362D03*
X81833Y1689162D03*
X94220Y1686622D03*
X109058Y3010D03*
X100325Y17042D03*
Y22034D03*
X109542Y17042D03*
Y22034D03*
X102325Y19538D03*
X107542D03*
X102437Y23978D03*
X107393D03*
X100437Y25974D03*
X109393D03*
X108453Y37106D03*
X101366D03*
X108453Y48720D03*
X101366D03*
X102379Y69340D03*
X111335D03*
X104379Y66844D03*
Y71836D03*
X109335Y66844D03*
Y71836D03*
X98335Y72844D03*
Y77836D03*
X100335Y75340D03*
X101317Y431727D03*
X102060Y493578D03*
X111087Y520052D03*
X98134Y722501D03*
X99716Y1567878D03*
X99750Y1559478D03*
X96251Y1577532D03*
X107451Y1574704D03*
X100451D03*
X104318Y1592304D03*
Y1603690D03*
X110200Y1605200D03*
X104318Y1622380D03*
Y1641075D03*
X99980Y1685362D03*
Y1696052D03*
X114498Y17042D03*
Y22034D03*
X123716Y17042D03*
Y22034D03*
X116498Y19538D03*
X121716D03*
X121567Y23978D03*
X116611D03*
X114611Y25974D03*
X123567D03*
X122626Y37106D03*
X115539D03*
X122626Y48720D03*
X115539D03*
X124379Y69340D03*
X126379Y66844D03*
Y71836D03*
X115379Y72844D03*
Y77836D03*
X120335Y72844D03*
Y77836D03*
X122335Y75340D03*
X113379D03*
X114087Y285495D03*
Y302854D03*
X127206Y480216D03*
X123257Y547506D03*
X119087D03*
X115060D03*
X120267Y1327697D03*
X127366Y1535855D03*
Y1541874D03*
Y1547935D03*
X116798Y1586288D03*
Y1598572D03*
Y1635303D03*
X127195Y1670362D03*
X117795Y1698862D03*
X127195Y1688362D03*
Y1692362D03*
Y1708362D03*
X117255Y1730422D03*
X129058Y3010D03*
X128672Y17042D03*
Y22034D03*
X130672Y19538D03*
X129713Y37106D03*
Y48720D03*
X133335Y69340D03*
X131335Y66844D03*
Y71836D03*
X137379Y72844D03*
Y77836D03*
X142335Y72844D03*
Y77836D03*
X135379Y75340D03*
X130057Y636103D03*
X129600Y669400D03*
X132967Y760525D03*
X141470Y1359100D03*
X140104Y1560136D03*
X139080Y1731398D03*
X149058Y3010D03*
X159582Y17042D03*
Y22034D03*
X157582Y19538D03*
X152477Y23978D03*
X157433D03*
X150477Y25974D03*
X159433D03*
X158492Y37106D03*
X151405D03*
X158492Y48720D03*
X151405D03*
X146379Y69340D03*
X155335D03*
X148379Y66844D03*
Y71836D03*
X153335Y66844D03*
Y71836D03*
X158583Y75340D03*
X144335D03*
X149371Y423383D03*
Y419383D03*
Y427383D03*
Y439383D03*
Y431383D03*
Y435383D03*
Y443383D03*
X147141Y698811D03*
X147435Y690807D03*
X149861Y698831D03*
X150155Y690807D03*
X156685Y706836D03*
X153965Y706816D03*
X153879Y721660D03*
X156469D03*
X147031Y706835D03*
X149621D03*
X149669Y721660D03*
X147079D03*
X154477Y1360797D03*
X148663Y1378607D03*
X151163D03*
Y1383807D03*
Y1381207D03*
X158318Y1384286D03*
X155718D03*
X158318Y1387393D03*
X155718D03*
X148663Y1386407D03*
X151163D03*
X148663Y1383807D03*
Y1381207D03*
X160201Y1399732D03*
X157731D03*
Y1394132D03*
X160201D03*
X152806Y1414175D03*
X144748Y1514878D03*
X149728D03*
X154581Y1520981D03*
X158570D03*
X150502Y1572021D03*
X145522D03*
X159107Y1571364D03*
X144854Y1702389D03*
X154803Y1708532D03*
X155100Y1723262D03*
X169058Y3010D03*
X164538Y17042D03*
Y22034D03*
X173755Y17042D03*
Y22034D03*
X166538Y19538D03*
X171755D03*
X166650Y23978D03*
X171606D03*
X164650Y25974D03*
X173606D03*
X172665Y37106D03*
X165579D03*
X172665Y48720D03*
X165579D03*
X169583Y69340D03*
X171583Y66844D03*
Y71836D03*
X176539Y66844D03*
Y71836D03*
X165539Y72844D03*
X160583D03*
Y77836D03*
X165539D03*
X167539Y75340D03*
X174327Y230928D03*
X171180Y401885D03*
X163900Y409362D03*
X163132Y493299D03*
X162750Y512502D03*
X172807Y1360797D03*
X160918Y1384286D03*
X163518D03*
Y1387393D03*
X160918D03*
X169318Y1384286D03*
X166118D03*
X172262Y1384302D03*
Y1387409D03*
X174932Y1378797D03*
Y1381397D03*
X163718Y1390500D03*
X161118D03*
X162631Y1399732D03*
Y1394132D03*
X172231Y1390532D03*
X162693Y1411529D03*
X171262Y1443390D03*
X168900Y1520510D03*
X163920D03*
X166476Y1572464D03*
X171456D03*
X166529Y1707678D03*
X166661Y1721211D03*
X189058Y3010D03*
X178711Y17042D03*
Y22034D03*
X180711Y19538D03*
X179752Y37106D03*
Y48720D03*
X191583Y69340D03*
X178539D03*
X182583Y72844D03*
Y77836D03*
X187539Y72844D03*
Y77836D03*
X189539Y75340D03*
X180583D03*
X186457Y393071D03*
Y385071D03*
Y389071D03*
Y405071D03*
X192220Y408662D03*
Y412162D03*
X177871Y421383D03*
Y425383D03*
Y430883D03*
Y443383D03*
X187490Y568752D03*
X190977Y669718D03*
X191976Y684326D03*
X184215Y1361072D03*
X181403Y1361115D03*
X192620Y1360797D03*
X188233Y1387027D03*
Y1379227D03*
Y1381827D03*
Y1384427D03*
X183283Y1387987D03*
X185633Y1387027D03*
X180672Y1387987D03*
X185633Y1379227D03*
X180672Y1380187D03*
X183283D03*
X177532Y1378797D03*
X185633Y1384427D03*
Y1381827D03*
X180672Y1382787D03*
Y1385387D03*
X183283Y1382787D03*
Y1385387D03*
X177421Y1383997D03*
X177532Y1381397D03*
X182653Y1404535D03*
X192767Y1413725D03*
X185643Y1413945D03*
X185895Y1535462D03*
Y1539723D03*
Y1544029D03*
Y1548487D03*
Y1552875D03*
X176793Y1585173D03*
X188119Y1580678D03*
Y1575686D03*
Y1592590D03*
Y1587598D03*
X192529Y1728947D03*
X183822Y1720517D03*
X209058Y3010D03*
X203716Y17042D03*
Y22034D03*
X208672Y17042D03*
Y22034D03*
X201716Y19538D03*
X201567Y23978D03*
X196611D03*
X194611Y25974D03*
X203567D03*
X208784D03*
X202626Y37106D03*
X195539D03*
X202626Y48720D03*
X195539D03*
X200539Y69340D03*
X193583Y66844D03*
Y71836D03*
X198539Y66844D03*
Y71836D03*
X204717Y72844D03*
Y77836D03*
X202717Y75340D03*
X195888Y581071D03*
X194515Y583433D03*
X195888Y615071D03*
X194515Y617433D03*
Y651433D03*
X195888Y649071D03*
X205320Y667562D03*
X207856Y686443D03*
X203043Y686483D03*
X207824Y681560D03*
X203044Y684036D03*
X207834Y684006D03*
X203237Y681549D03*
X199720Y732862D03*
X206720Y731862D03*
X199220Y739362D03*
X207602Y756855D03*
X199602D03*
X201661Y1384286D03*
X193861D03*
X196461D03*
X199061D03*
X201661Y1387393D03*
X193861D03*
X196461D03*
X199061D03*
X204261Y1384286D03*
X207461D03*
X201861Y1390500D03*
X199261D03*
X195874Y1399732D03*
X198344D03*
X200774D03*
X195874Y1394132D03*
X198344D03*
X200774D03*
X201071Y1412173D03*
X193075Y1580678D03*
Y1575686D03*
X200179D03*
X205135D03*
X200179Y1580678D03*
X205135D03*
X193075Y1592590D03*
Y1587598D03*
X200179Y1592590D03*
X205135D03*
X200179Y1587598D03*
X205135D03*
X198375Y1599884D03*
X193419D03*
X205479D03*
X193419Y1616788D03*
Y1611796D03*
X198375D03*
X193419Y1604876D03*
X198375D03*
Y1616788D03*
X205479Y1611796D03*
Y1604876D03*
Y1616788D03*
X207229Y1631181D03*
X193410Y1711606D03*
X205582Y1700867D03*
X196443Y1722197D03*
X217889Y17042D03*
Y22034D03*
X222845Y17042D03*
Y22034D03*
X210672Y19538D03*
X215889D03*
X224845D03*
X215740Y23978D03*
X210784D03*
X217740Y25974D03*
X223886Y37106D03*
X216799D03*
X209713D03*
X223886Y48720D03*
X216799D03*
X209713D03*
X215717Y66844D03*
Y71836D03*
X220673Y66844D03*
Y71836D03*
X213717Y69340D03*
X222673D03*
X209673Y72844D03*
Y77836D03*
X211673Y75340D03*
X224717D03*
X209579Y457222D03*
Y462235D03*
X211220Y740362D03*
X215824Y1361199D03*
X211350Y1360797D03*
X218960Y1388312D03*
X210405Y1384302D03*
Y1387409D03*
X213075Y1381558D03*
X217133Y1384055D03*
X214425Y1384058D03*
X215675Y1381558D03*
X218175D03*
X213075Y1378958D03*
X215675D03*
X218175D03*
X210374Y1390532D03*
X212239Y1580678D03*
X217195D03*
Y1575686D03*
X212239D03*
X224299D03*
Y1580678D03*
X212239Y1587598D03*
X217195D03*
X212239Y1592590D03*
X217195D03*
X224299Y1587598D03*
Y1592590D03*
X210435Y1599884D03*
X222495D03*
X217539D03*
X210435Y1611796D03*
Y1604876D03*
Y1616788D03*
X222495D03*
X217539D03*
X222495Y1604876D03*
Y1611796D03*
X217539Y1604876D03*
Y1611796D03*
X212684Y1720307D03*
X229058Y3010D03*
X238063Y37162D03*
X230972Y37106D03*
Y48720D03*
X226717Y72844D03*
Y77836D03*
X231673Y72844D03*
Y77836D03*
X233673Y75340D03*
X233800Y162692D03*
X237539Y174266D03*
X228550Y420412D03*
X229255Y1575686D03*
Y1580678D03*
X236359D03*
Y1575686D03*
X241315Y1580678D03*
Y1575686D03*
X229255Y1587598D03*
Y1592590D03*
X236359D03*
Y1587598D03*
X241315Y1592590D03*
Y1587598D03*
X229599Y1599884D03*
X234555D03*
X229599Y1604876D03*
Y1611796D03*
X234555Y1604876D03*
Y1611796D03*
X229599Y1616788D03*
X234555D03*
X249058Y3010D03*
X243490Y23002D03*
X247720Y71862D03*
X244300Y59762D03*
X247720Y75862D03*
X251797Y100843D03*
X249735Y152694D03*
X242255Y162512D03*
X249300Y510362D03*
X253800Y515362D03*
X249860Y518222D03*
X248419Y1575686D03*
X253375D03*
X248419Y1580678D03*
X253375D03*
X248419Y1587598D03*
X253375D03*
X248419Y1592590D03*
X253375D03*
X246615Y1599884D03*
X241659D03*
X253719D03*
X241659Y1616788D03*
X246615D03*
Y1604876D03*
X241659D03*
X246615Y1611796D03*
X241659D03*
X253719Y1604876D03*
Y1611796D03*
Y1616788D03*
X269058Y3010D03*
X263280Y35312D03*
X272600Y27182D03*
X271600Y40162D03*
X272361Y120243D03*
X270364Y118415D03*
X261387Y133783D03*
X258257D03*
X264578Y155203D03*
Y159203D03*
X260700Y218662D03*
X268940Y217982D03*
X270745Y207562D03*
X265343Y244460D03*
X272029Y443735D03*
X274270Y746602D03*
X260479Y1580678D03*
X265435D03*
X260479Y1575592D03*
X265435D03*
X272539Y1575686D03*
Y1580678D03*
X260479Y1592590D03*
X265435D03*
X260479Y1587598D03*
X265435D03*
X272539D03*
Y1592590D03*
X258675Y1599884D03*
X270735Y1599790D03*
X265779D03*
X258675Y1604876D03*
Y1611796D03*
Y1616788D03*
X270735D03*
X265779D03*
X270735Y1611796D03*
Y1604876D03*
X265779D03*
Y1611796D03*
X289058Y3010D03*
X285900Y23962D03*
X287952Y39984D03*
X286071Y48720D03*
X286500Y52462D03*
X278984Y48720D03*
X287800Y60062D03*
X283953Y152503D03*
X288520Y157062D03*
X279740Y205962D03*
X276890Y249022D03*
X289920Y248652D03*
X286920D03*
X282420D03*
X287819Y691097D03*
X287820Y727962D03*
X278520Y738072D03*
X290077Y739735D03*
X289047Y760245D03*
X277495Y1575686D03*
Y1580678D03*
X284599D03*
X289555D03*
Y1575686D03*
X284599D03*
X277495Y1587598D03*
Y1592590D03*
X284599D03*
X289555D03*
X284599Y1587598D03*
X289555D03*
X282795Y1599884D03*
X277839D03*
X289899D03*
X282795Y1604876D03*
Y1611796D03*
X277839D03*
Y1604876D03*
X282795Y1616788D03*
X277839D03*
X289899D03*
Y1604876D03*
Y1611796D03*
X291520Y12762D03*
X291660Y21642D03*
X298720Y40017D03*
X306720Y39982D03*
X292942Y67513D03*
X293447Y78573D03*
X293452Y82483D03*
Y85983D03*
X303047Y79373D03*
X299947Y79273D03*
X299657Y92503D03*
X299628Y149203D03*
Y158703D03*
X294553Y153819D03*
X306087Y569718D03*
X294658Y637809D03*
X290680Y745312D03*
X299427Y768265D03*
X303831Y1318566D03*
X303807Y1342225D03*
X303831Y1344866D03*
X304047Y1368565D03*
X296659Y1575686D03*
X301615D03*
X296659Y1580678D03*
X301615D03*
X296659Y1587598D03*
X301615D03*
X296659Y1592590D03*
X301615D03*
X294855Y1599884D03*
X301959D03*
X294855Y1616788D03*
Y1604876D03*
Y1611796D03*
X301959Y1604876D03*
Y1611796D03*
Y1616788D03*
X309058Y3010D03*
X320057Y85803D03*
Y88803D03*
X314200Y585282D03*
X316080Y578262D03*
X320691Y602448D03*
X311820Y598762D03*
X316397Y776125D03*
X312301Y1345539D03*
Y1342432D03*
X309701Y1345539D03*
Y1342432D03*
X316655Y1352295D03*
X314175D03*
X311695D03*
X320101Y1342432D03*
X317701Y1348646D03*
X315101D03*
X314901Y1345539D03*
X317501D03*
X314901Y1342432D03*
X317501D03*
X316655Y1357895D03*
X311695D03*
X314175D03*
X317979Y1371248D03*
X315221Y1372445D03*
X308719Y1580678D03*
X313675D03*
X308719Y1575686D03*
X313675D03*
X320779D03*
Y1580678D03*
X308719Y1592590D03*
X313675D03*
X308719Y1587598D03*
X313675D03*
X320779D03*
Y1592590D03*
X306915Y1599884D03*
X318975D03*
X314019D03*
X306915Y1604876D03*
Y1611796D03*
Y1616788D03*
X318975D03*
X314019D03*
X318975Y1604876D03*
Y1611796D03*
X314019Y1604876D03*
Y1611796D03*
X329535Y49388D03*
X336240Y150738D03*
X330674Y368261D03*
X331760Y705882D03*
X328915Y1337104D03*
X331515D03*
X328915Y1331904D03*
X331515D03*
X328915Y1329304D03*
X331515D03*
X328915Y1334504D03*
X331515D03*
X328915Y1339704D03*
X326145Y1348651D03*
X326245Y1345555D03*
Y1342448D03*
X323301Y1342432D03*
X338917Y1349488D03*
X336347Y1348353D03*
X325735Y1575686D03*
Y1580678D03*
X332839D03*
X337795D03*
X332839Y1575686D03*
X337795D03*
X325735Y1587598D03*
Y1592590D03*
X332839D03*
X337795D03*
X332839Y1587598D03*
X337795D03*
X326079Y1599884D03*
X331035D03*
X338139D03*
X326079Y1604876D03*
Y1611796D03*
X331035Y1604876D03*
Y1611796D03*
X326079Y1616788D03*
X331035D03*
X338139D03*
Y1604876D03*
Y1611796D03*
X349535Y49388D03*
X343040Y122522D03*
X345869Y192716D03*
X353145Y228362D03*
X345164Y314234D03*
X349187Y715485D03*
X344446Y739434D03*
X348000Y755362D03*
X344429Y1322741D03*
X347029D03*
X341829D03*
X347029Y1319634D03*
X344429D03*
X341829D03*
X349629Y1322741D03*
Y1319634D03*
X352229D03*
X355429D03*
X346303Y1335097D03*
X343823D03*
Y1329497D03*
X346303D03*
X347229Y1325848D03*
X348783Y1329497D03*
X349829Y1325848D03*
X348783Y1335097D03*
X348804Y1346877D03*
X350470Y1349030D03*
X344899Y1575686D03*
X349855D03*
X344899Y1580678D03*
X349855D03*
X344899Y1587598D03*
X349855D03*
X344899Y1592590D03*
X349855D03*
X343095Y1599884D03*
X355155D03*
X350199D03*
X343095Y1616788D03*
Y1604876D03*
Y1611796D03*
X355155Y1604876D03*
Y1611796D03*
X350199Y1604876D03*
Y1611796D03*
X355155Y1616788D03*
X350199D03*
X366775Y127662D03*
X356250Y216342D03*
X358209Y208169D03*
X357764Y314234D03*
X363750Y369362D03*
X371370Y373622D03*
X364014Y382304D03*
X359930Y732985D03*
X360927Y757665D03*
X361043Y1306506D03*
X363643D03*
X367939Y1303319D03*
Y1305919D03*
Y1308519D03*
X358373Y1322757D03*
Y1319650D03*
X361043Y1314306D03*
Y1316906D03*
X362393Y1319406D03*
X361043Y1309106D03*
Y1311706D03*
X363643Y1316906D03*
Y1314306D03*
Y1309106D03*
Y1311706D03*
X358273Y1325853D03*
X370874Y1335876D03*
X367490Y1332568D03*
X356959Y1580678D03*
X361915D03*
X356959Y1575592D03*
X361915D03*
X369019Y1575686D03*
Y1580678D03*
X356959Y1592590D03*
X361915D03*
X356959Y1587598D03*
X361915D03*
X367215Y1599790D03*
X362259D03*
X369019Y1587598D03*
Y1592590D03*
X367215Y1616788D03*
X362259D03*
X367215Y1604876D03*
Y1611796D03*
X362259Y1604876D03*
Y1611796D03*
X376245Y212862D03*
Y217362D03*
Y221362D03*
Y225362D03*
X386120Y220322D03*
X385720Y323761D03*
X376500Y362736D03*
X373957Y1306208D03*
X381757D03*
X379157D03*
X376557D03*
X384357D03*
X387557D03*
X375951Y1321671D03*
X380911Y1316071D03*
X378431D03*
Y1321671D03*
X380911D03*
X373957Y1309315D03*
X381957Y1312422D03*
X381757Y1309315D03*
X379357Y1312422D03*
X379157Y1309315D03*
X376557D03*
X375951Y1316071D03*
X380842Y1334095D03*
X383549Y1333998D03*
X383127Y1395610D03*
X381060Y1433622D03*
X380930Y1531402D03*
X384210Y1534152D03*
X387152Y1582659D03*
X373975Y1575686D03*
Y1580678D03*
Y1587598D03*
Y1592590D03*
X379275Y1599884D03*
X374319D03*
X379275Y1604876D03*
Y1611796D03*
X374319Y1604876D03*
Y1611796D03*
X379275Y1616788D03*
X374319D03*
X374690Y1631700D03*
X375550Y1662052D03*
X386824Y1682866D03*
X387760Y1671092D03*
X393830Y62062D03*
X399800Y59662D03*
X403800D03*
X390830Y155833D03*
X388965Y209949D03*
X398720Y318643D03*
X403675Y363081D03*
X391195Y368199D03*
X391101Y380939D03*
X403581Y375880D03*
X390730Y394852D03*
X403570Y388874D03*
X395771Y1303480D03*
X393171D03*
X395771Y1300880D03*
X393171D03*
X395771Y1295680D03*
X393171D03*
X395771Y1298280D03*
X393171D03*
X394521Y1305980D03*
X390501Y1306224D03*
X400067Y1303319D03*
Y1300719D03*
Y1295519D03*
Y1298119D03*
Y1305919D03*
Y1308519D03*
X390401Y1312427D03*
X390501Y1309331D03*
X399673Y1332653D03*
X403130Y1335963D03*
X400919Y1411231D03*
X391370Y1424782D03*
X392108Y1582659D03*
X401812Y1616456D03*
X394910Y1632364D03*
Y1637320D03*
X402246Y1671745D03*
X409535Y49388D03*
X412930Y62572D03*
X413459Y129061D03*
X411434Y163662D03*
X407490Y216912D03*
X412820Y231922D03*
X405478Y236726D03*
X410090Y241932D03*
X420710Y242482D03*
X419023Y381760D03*
X418982Y407847D03*
X416485Y1306208D03*
X419685D03*
X413885D03*
X406085D03*
X411285D03*
X408685D03*
X414085Y1312422D03*
X413885Y1309315D03*
X411485Y1312422D03*
X408685Y1309315D03*
X406085D03*
X411285D03*
X413039Y1316071D03*
X408079D03*
X410559D03*
X413039Y1321671D03*
X408079D03*
X410559D03*
X416099Y1335568D03*
X414617Y1333473D03*
X412465Y1393878D03*
X419974Y1405289D03*
Y1412789D03*
X420474Y1420289D03*
X407125Y1424978D03*
X404475Y1552452D03*
X419002Y1600306D03*
X406526Y1591212D03*
Y1596168D03*
X406768Y1616456D03*
X408700Y1603500D03*
Y1614300D03*
X411910Y1629170D03*
Y1624214D03*
X410232Y1670244D03*
X429535Y49388D03*
X430655Y58677D03*
X433695Y214862D03*
X429395Y232562D03*
X426295Y227862D03*
X422210Y221452D03*
X429395Y236562D03*
Y240562D03*
X425249Y338061D03*
X431503Y376642D03*
X431462Y402729D03*
X422629Y1306224D03*
X432195Y1303319D03*
Y1305919D03*
X425299Y1303480D03*
X426649Y1305980D03*
X427899Y1303480D03*
X425299Y1295680D03*
X427899D03*
X432195Y1295519D03*
Y1298119D03*
X427899Y1298280D03*
X425299D03*
X432195Y1300719D03*
X427899Y1300880D03*
X425299D03*
X432195Y1308519D03*
X422529Y1312427D03*
X422629Y1309331D03*
X434983Y1335924D03*
X431578Y1332560D03*
X427474Y1405289D03*
X434974D03*
Y1412789D03*
X427474Y1420289D03*
X434974D03*
X423958Y1600306D03*
X428099Y1586282D03*
X428941Y1606441D03*
X449535Y49388D03*
X443678Y145710D03*
X445964Y314234D03*
X450400Y338812D03*
X442853Y542519D03*
Y547519D03*
X448613Y1306208D03*
X446013D03*
X443413D03*
X440813D03*
X438213D03*
X451813D03*
X443613Y1312422D03*
X443413Y1309315D03*
X440813D03*
X438213D03*
X446213Y1312422D03*
X446013Y1309315D03*
X440207Y1316071D03*
X445167D03*
X442687D03*
X440207Y1321671D03*
X445167D03*
X442687D03*
X446944Y1335928D03*
X445153Y1334095D03*
X446258Y1441606D03*
X449778D03*
X451910Y1643282D03*
X437562Y1649770D03*
X442518D03*
X469535Y49388D03*
X454568Y78782D03*
X466992Y145888D03*
X458264Y254862D03*
X460300Y303662D03*
X468490Y340572D03*
X469830Y366158D03*
X460323Y510183D03*
X458327Y1303980D03*
X460927D03*
X464427Y1305380D03*
X454757Y1306224D03*
X460927Y1306580D03*
X458327D03*
Y1301380D03*
X460927D03*
X464427Y1300180D03*
Y1302780D03*
X458327Y1296180D03*
X460927D03*
X464427D03*
X458327Y1298780D03*
X460927D03*
X464423Y1308519D03*
X454657Y1312427D03*
X454757Y1309331D03*
X464738Y1333085D03*
X467644Y1335981D03*
X455576Y1409125D03*
Y1417125D03*
Y1420625D03*
Y1427632D03*
Y1424125D03*
X454450Y1433580D03*
X464160Y1587122D03*
X458414Y1624994D03*
Y1629950D03*
X468040Y1654807D03*
X478240Y55935D03*
Y66575D03*
Y61129D03*
X484396Y161364D03*
X475500Y212685D03*
X472800Y299462D03*
X484800Y307362D03*
X476740Y309272D03*
X479740Y300202D03*
X482920Y398060D03*
X479379Y452445D03*
X480741Y1306208D03*
X478141D03*
X475541D03*
X472941D03*
X470341D03*
X483941D03*
X472941Y1309315D03*
X478141D03*
X470341D03*
X478341Y1312422D03*
X475741D03*
X475541Y1309315D03*
X472335Y1316071D03*
X477295D03*
X474815D03*
X472335Y1321671D03*
X477295D03*
X474815D03*
X477162Y1334095D03*
X478909Y1336038D03*
X485236Y1417844D03*
X482741Y1438698D03*
X482742Y1441312D03*
X484333Y1575686D03*
Y1580678D03*
X477229D03*
X472273D03*
Y1575686D03*
X477229D03*
X482529Y1599884D03*
X477573D03*
X484333Y1587598D03*
Y1592590D03*
X472273D03*
X477229D03*
Y1587598D03*
X472273D03*
X482529Y1616788D03*
X477573D03*
Y1611796D03*
X482529D03*
X477573Y1604876D03*
X482529D03*
X472210Y1618626D03*
X485150Y1624942D03*
X477905Y1667242D03*
X489535Y49347D03*
X497002Y88167D03*
X501540Y105152D03*
X498630Y140492D03*
X489980Y250512D03*
X492074Y300306D03*
X497568Y397632D03*
X494193Y550447D03*
X486885Y1306224D03*
X496451Y1306345D03*
X489555Y1303480D03*
X492155D03*
X490905Y1305980D03*
X492155Y1300880D03*
X489555D03*
X486785Y1312427D03*
X486885Y1309331D03*
X496220Y1322440D03*
X496451Y1316745D03*
Y1308945D03*
Y1314145D03*
Y1311545D03*
X499458Y1349468D03*
X499818Y1385027D03*
X499859Y1393027D03*
X490307Y1421499D03*
X491156Y1438713D03*
X499541Y1438698D03*
X491142Y1441312D03*
X499542D03*
X501349Y1580678D03*
X496393D03*
Y1575686D03*
X501349D03*
X489289D03*
Y1580678D03*
X501693Y1599884D03*
X494589D03*
X489633D03*
X501349Y1592590D03*
X496393D03*
X501349Y1587598D03*
X496393D03*
X489289D03*
Y1592590D03*
X501693Y1611796D03*
Y1604876D03*
Y1616788D03*
X489633Y1611796D03*
X494589Y1604876D03*
X489633D03*
X494589Y1611796D03*
X489633Y1616788D03*
X494589D03*
X487340Y1641352D03*
X517902Y69508D03*
X510815D03*
X503100Y78402D03*
X510030Y78412D03*
X504980Y101752D03*
X503290Y140492D03*
X507360D03*
X514850Y168443D03*
X504075Y231262D03*
X508000Y237862D03*
X505900Y311562D03*
X510740Y332592D03*
X513173Y408740D03*
X514425Y489112D03*
Y495112D03*
X509493Y539819D03*
X513025Y615742D03*
X516069Y1319634D03*
X502469D03*
Y1322741D03*
X512869Y1319634D03*
X510269D03*
X507669D03*
X505069D03*
X507669Y1322741D03*
X505069D03*
X510269D03*
X504463Y1329497D03*
Y1335097D03*
X509423Y1329497D03*
X506943D03*
X509423Y1335097D03*
X506943D03*
X510469Y1325848D03*
X507869D03*
X509382Y1347521D03*
X511149Y1349468D03*
X505018Y1385027D03*
X502418D03*
X505059Y1393027D03*
X502459D03*
X508001Y1438669D03*
X507942Y1441312D03*
X508453Y1575686D03*
X513409D03*
X508453Y1580678D03*
X513409D03*
X513753Y1599884D03*
X506649D03*
X508453Y1587598D03*
X513409D03*
X508453Y1592590D03*
X513409D03*
X513753Y1616788D03*
Y1604876D03*
Y1611796D03*
X506649D03*
Y1604876D03*
Y1616788D03*
X518606Y23797D03*
X532075Y69508D03*
Y57894D03*
X524988Y69508D03*
X529239Y99997D03*
Y92911D03*
X528400Y104225D03*
Y114275D03*
X527823Y131802D03*
Y149802D03*
X527278Y164726D03*
X529480Y183921D03*
X536127Y247652D03*
X523660Y323222D03*
X535220Y383552D03*
X528145Y408705D03*
X518735Y452442D03*
X526852Y511331D03*
X527042Y505830D03*
X526853Y516817D03*
X523033Y1319406D03*
X519013Y1319650D03*
Y1322757D03*
X527645Y1326076D03*
X528579Y1329143D03*
X528377Y1335982D03*
X518913Y1325853D03*
X528579Y1342143D03*
Y1344743D03*
X534597Y1345539D03*
Y1342432D03*
X528975Y1369724D03*
X532573Y1575686D03*
Y1580678D03*
X520513D03*
X525469D03*
X520513Y1575686D03*
X525469D03*
X525813Y1599884D03*
X530769D03*
X518709D03*
X532573Y1587598D03*
Y1592590D03*
X525469D03*
X520513D03*
Y1587598D03*
X525469D03*
X525813Y1611796D03*
X530769D03*
X525813Y1604876D03*
X530769D03*
Y1616788D03*
X525813D03*
X518709D03*
Y1604876D03*
Y1611796D03*
X548609Y32500D03*
X546248Y69508D03*
X539161D03*
Y57894D03*
X546234Y77443D03*
X542620Y103352D03*
X537360Y120522D03*
X550545Y147302D03*
X542798Y202646D03*
X535630Y306602D03*
X543035Y441005D03*
X538120Y463137D03*
X544813Y1322668D03*
X542213D03*
X538293D03*
X535693D03*
X548197Y1342432D03*
X539997Y1348646D03*
X542397Y1345539D03*
X542597Y1348646D03*
X537197Y1342432D03*
X539797D03*
X542397D03*
X544997D03*
X537197Y1345539D03*
X539797D03*
X539071Y1352295D03*
X536591D03*
X541551D03*
Y1357895D03*
X542256Y1369935D03*
X536591Y1357895D03*
X539071D03*
X549589Y1580678D03*
X544633D03*
X549589Y1575592D03*
X544633D03*
X537529Y1575686D03*
Y1580678D03*
X549933Y1599790D03*
X537873Y1599884D03*
X542829D03*
X549589Y1592590D03*
X544633D03*
X549589Y1587598D03*
X544633D03*
X537529D03*
Y1592590D03*
X549933Y1611796D03*
Y1604876D03*
Y1616788D03*
X542829D03*
X537873D03*
Y1604876D03*
X542829D03*
X537873Y1611796D03*
X542829D03*
X560421Y69508D03*
X553335D03*
X553320Y77443D03*
X564988Y118670D03*
X555545Y134340D03*
X565500Y145252D03*
X555220Y167937D03*
X553657Y193862D03*
X564944Y252173D03*
X553536Y307527D03*
X569080Y414002D03*
X559300Y422732D03*
X558933Y1323658D03*
Y1326258D03*
X556563Y1337918D03*
X553963D03*
X558933Y1328938D03*
X556563Y1335318D03*
Y1332718D03*
X558933Y1331538D03*
X553963Y1335318D03*
Y1332718D03*
X555313Y1340418D03*
X551141Y1345555D03*
X551041Y1348651D03*
X551141Y1342448D03*
X555372Y1343037D03*
X561070Y1346174D03*
X556693Y1575686D03*
X561649D03*
X556693Y1580678D03*
X561649D03*
X561993Y1599884D03*
X554889Y1599790D03*
X556693Y1587598D03*
X561649D03*
Y1592590D03*
X556693D03*
X561993Y1616788D03*
Y1604876D03*
Y1611796D03*
X554889D03*
Y1604876D03*
Y1616788D03*
X567673Y130542D03*
X581175Y164717D03*
X569965Y161232D03*
X579481Y202378D03*
Y210378D03*
X568149Y217916D03*
X580712Y215877D03*
X581645Y233362D03*
X569668Y229812D03*
X578711Y230109D03*
X578509Y265132D03*
X569880Y300992D03*
X580400Y302402D03*
X582436Y361032D03*
X570200Y372229D03*
X570760Y451710D03*
X571990Y501046D03*
X571700Y552200D03*
X580813Y1575686D03*
Y1580678D03*
X573709D03*
X568753D03*
Y1575686D03*
X573709D03*
X579009Y1599884D03*
X574053D03*
X566949D03*
X580813Y1587598D03*
Y1592590D03*
X573709D03*
X568753D03*
X573709Y1587598D03*
X568753D03*
X574053Y1616788D03*
X579009D03*
Y1611796D03*
X574053D03*
X579009Y1604876D03*
X574053D03*
X566949Y1616788D03*
Y1604876D03*
Y1611796D03*
X591395Y132142D03*
X595220Y140922D03*
X588000D03*
X592710Y156342D03*
X593248Y159480D03*
X598295Y171862D03*
X596581Y184849D03*
X590337Y177604D03*
X598760Y203712D03*
X593966Y229965D03*
X592039Y252202D03*
X588577Y285862D03*
X586820Y314662D03*
X597820Y317062D03*
X592920Y326362D03*
X591720Y430787D03*
X599220Y444362D03*
X593545Y488212D03*
X594090Y505107D03*
X589260Y519421D03*
X594240Y511953D03*
X593675Y534702D03*
X589989Y745475D03*
X597829Y1580678D03*
X592873D03*
X597829Y1575686D03*
X592873D03*
X585769D03*
Y1580678D03*
X598173Y1599884D03*
X586113D03*
X591069D03*
X597829Y1592590D03*
X592873D03*
X597829Y1587598D03*
X592873D03*
X585769D03*
Y1592590D03*
X598173Y1616788D03*
Y1611796D03*
Y1604876D03*
X586113D03*
X591069D03*
X586113Y1611796D03*
X591069D03*
Y1616788D03*
X586113D03*
X615185Y69508D03*
X603374D03*
X601050Y100008D03*
X610104Y119342D03*
X602306Y143077D03*
X602430Y153862D03*
X606260Y161652D03*
X615572Y173942D03*
X615573Y181984D03*
X614531Y200378D03*
X611030Y188372D03*
X603340Y208142D03*
X614531Y209878D03*
X609456Y204994D03*
X606719Y254966D03*
X609844Y330407D03*
X608830Y374302D03*
X605830Y402782D03*
X604779Y423862D03*
X600351Y461862D03*
X614220Y452862D03*
X610820Y472862D03*
X603779Y486922D03*
X606200Y514862D03*
X609520Y515162D03*
X614086Y537624D03*
X614000Y550800D03*
X603317Y738415D03*
X614660Y739553D03*
X602027Y761445D03*
X612407Y769485D03*
X609889Y1575686D03*
X604933D03*
X609889Y1580678D03*
X604933D03*
X615189Y1599884D03*
X610233D03*
X603129D03*
X609889Y1587598D03*
X604933D03*
X609889Y1592590D03*
X604933D03*
X615189Y1604876D03*
X610233D03*
X615189Y1611796D03*
X610233D03*
X615189Y1616788D03*
X610233D03*
X603129D03*
Y1611796D03*
Y1604876D03*
X631546Y85024D03*
X618460Y119342D03*
X631300Y167872D03*
X628195Y178414D03*
X628194Y170372D03*
X630818Y191248D03*
X625862D03*
X620030Y188782D03*
X627645Y236862D03*
X629564Y256277D03*
X623150Y273172D03*
X625800Y311912D03*
X628294Y317007D03*
X623580Y336429D03*
X629248Y436972D03*
X629220Y472862D03*
Y477862D03*
Y467862D03*
Y482862D03*
X626207Y747585D03*
X618114Y1258470D03*
X629053Y1575686D03*
Y1580678D03*
X621949D03*
X616993D03*
X621949Y1575686D03*
X616993D03*
X622293Y1599884D03*
X627249D03*
X629053Y1587598D03*
Y1592590D03*
X621949D03*
X616993D03*
X621949Y1587598D03*
X616993D03*
X627249Y1616788D03*
X622293D03*
Y1611796D03*
X627249D03*
X622293Y1604876D03*
X627249D03*
X646440Y43632D03*
X632463Y43302D03*
X645150Y69508D03*
X645350Y60612D03*
X632640Y107532D03*
X637500Y110362D03*
X642480Y184862D03*
X645876Y296231D03*
X633138Y296766D03*
X645528Y308623D03*
X645807Y304291D03*
X647200Y354300D03*
X643736Y457214D03*
X644245Y472862D03*
X644220Y467862D03*
X644245Y482862D03*
X636960Y516002D03*
X646069Y1580678D03*
X641113D03*
X646069Y1575592D03*
X641113D03*
X634009Y1575686D03*
Y1580678D03*
X646413Y1599790D03*
X639309Y1599884D03*
X634353D03*
X646069Y1592590D03*
X641113D03*
X646069Y1587598D03*
X641113D03*
X634009D03*
Y1592590D03*
X646413Y1616788D03*
Y1611796D03*
Y1604876D03*
X639309D03*
X634353D03*
X639309Y1611796D03*
X634353D03*
Y1616788D03*
X639309D03*
X641057Y1648659D03*
X645407Y1660425D03*
X639745Y1714362D03*
X648290Y1720052D03*
X639745Y1726362D03*
X661550Y45133D03*
X654464D03*
X652153Y98105D03*
X652680Y89712D03*
X651579Y102703D03*
X659000Y89262D03*
X651980Y133822D03*
X650790Y144982D03*
X660690Y408162D03*
X660720Y404362D03*
X653800Y498740D03*
X662282Y1386432D03*
X654606Y1431203D03*
X653173Y1575686D03*
X658129D03*
X653173Y1580678D03*
X658129D03*
X663429Y1599884D03*
X658473D03*
X651369Y1599790D03*
X653173Y1587598D03*
X658129D03*
X653173Y1592590D03*
X658129D03*
X663429Y1604876D03*
X658473D03*
X663429Y1611796D03*
X658473D03*
Y1616788D03*
X663429D03*
X651369D03*
Y1611796D03*
Y1604876D03*
X663043Y1647557D03*
X655307Y1647436D03*
X663118Y1659557D03*
X663145Y1664862D03*
Y1676862D03*
X656973Y1698727D03*
X652712Y1686275D03*
X672005Y44119D03*
X668800Y45262D03*
X666406Y69508D03*
X675225Y58108D03*
X673750Y77692D03*
X673690Y200672D03*
X673300Y211332D03*
X667020Y225762D03*
X680600Y375462D03*
X668329Y411714D03*
X677295Y404362D03*
X677195Y408262D03*
X674628Y414864D03*
Y443210D03*
X671479Y430612D03*
Y462108D03*
X668329Y481006D03*
X675220Y503837D03*
X680220D03*
X675220Y516852D03*
X671607Y742835D03*
X668096Y1360822D03*
X677137Y1384311D03*
X674537D03*
X671937D03*
X669337D03*
X677137Y1387418D03*
X674537D03*
X671937D03*
X669337D03*
X664782Y1383832D03*
Y1381232D03*
Y1378632D03*
Y1386432D03*
X679737Y1384311D03*
X677337Y1390525D03*
X674737D03*
X676250Y1399757D03*
X673820D03*
X671350D03*
X676250Y1394157D03*
X673820D03*
X671350D03*
X666425Y1414200D03*
X676312Y1411554D03*
X667926Y1547018D03*
X679192Y1564252D03*
X678515Y1573910D03*
X676648Y1657380D03*
X671620Y1670862D03*
X674195Y1708362D03*
X669120Y1718862D03*
X674195Y1732362D03*
X696838Y45112D03*
X686854Y43701D03*
X692380Y43532D03*
X682941Y69982D03*
X687050Y79212D03*
X685230Y76952D03*
X683820Y79192D03*
X682890Y72642D03*
X684953Y104968D03*
X694390Y133682D03*
X684520Y152482D03*
X688520D03*
X692520D03*
X686760Y222912D03*
X685600Y375462D03*
X690600D03*
X695600D03*
X688220Y388362D03*
X697220Y404362D03*
X697120Y408262D03*
X684077Y414864D03*
X680928Y424313D03*
X696676Y436911D03*
X693526Y443210D03*
Y440061D03*
Y436911D03*
X690376Y440061D03*
Y433761D03*
X693526Y452659D03*
Y449510D03*
X696676Y455809D03*
X693526D03*
X690376Y452659D03*
Y458959D03*
X696676Y477856D03*
X684077D03*
X680928Y468407D03*
X690220Y516852D03*
X684357Y742345D03*
X692784Y1298845D03*
X686426Y1360822D03*
X695022Y1361990D03*
X696462Y1386122D03*
X682937Y1384311D03*
X685881Y1384327D03*
Y1387434D03*
X691351Y1380922D03*
X688751D03*
X691240Y1383522D03*
X693851D03*
Y1378322D03*
Y1380922D03*
X691351Y1378322D03*
X688751D03*
X693851Y1386122D03*
X696462Y1378322D03*
Y1383522D03*
Y1380922D03*
X696272Y1404560D03*
X685850Y1390557D03*
X685015Y1438475D03*
X696940Y1437955D03*
X689875Y1577913D03*
X689128Y1652262D03*
X692595Y1670862D03*
X701838Y45112D03*
X700610Y57782D03*
X700741Y83050D03*
X706673Y122762D03*
X703520Y122540D03*
X704880Y133643D03*
X701926Y166535D03*
Y178346D03*
Y184252D03*
Y172441D03*
Y190157D03*
Y196063D03*
Y201968D03*
Y207874D03*
Y213779D03*
Y219685D03*
X700600Y375462D03*
X705600D03*
X706125Y421163D03*
X709274Y436911D03*
X706125Y440061D03*
Y436911D03*
X699825Y440061D03*
Y436911D03*
X712424Y443210D03*
Y440061D03*
Y436911D03*
Y455809D03*
X709274D03*
X706125D03*
Y452659D03*
X699825Y455809D03*
Y452659D03*
X712424D03*
Y449510D03*
X709274Y477856D03*
X699825Y468407D03*
X711220Y516852D03*
X705220D03*
X698600Y530700D03*
X701917Y742865D03*
X703755Y1290545D03*
X708795Y1303701D03*
X698094Y1361947D03*
X706239Y1360822D03*
X699062Y1380922D03*
Y1383522D03*
Y1378322D03*
X707480Y1384311D03*
X710080D03*
X707480Y1387418D03*
X710080D03*
X701662Y1380922D03*
Y1383522D03*
Y1378322D03*
X699062Y1386122D03*
X701662D03*
X712680Y1384311D03*
Y1387418D03*
X709493Y1399757D03*
Y1394157D03*
X712880Y1390525D03*
X711963Y1399757D03*
Y1394157D03*
X699262Y1413970D03*
X704568Y1414119D03*
X706680Y1437535D03*
X701730Y1437855D03*
X711440Y1436905D03*
X702112Y1583683D03*
X709111Y1618842D03*
X697595Y1658862D03*
X704433Y1657964D03*
X697770Y1680810D03*
X714015Y-27612D03*
X720308Y-26403D03*
X714015Y-21457D03*
Y-17583D03*
X714030Y-15068D03*
X714015Y-11428D03*
X714030Y-25097D03*
X720308Y-16374D03*
X714015Y-7554D03*
X714030Y-5039D03*
X720308Y-6345D03*
X728980Y39872D03*
X728028Y101968D03*
X728023Y98058D03*
X728028Y105468D03*
X727720Y356362D03*
X725220Y380787D03*
X715600Y375462D03*
X718220Y388362D03*
X715220Y404362D03*
X715120Y408262D03*
X725022Y414864D03*
X715574Y433761D03*
Y458959D03*
X728172Y449510D03*
X725022Y477856D03*
X722720Y521362D03*
X729200Y588952D03*
X713836Y1283689D03*
X724969Y1360822D03*
X729443Y1361224D03*
X726694Y1381583D03*
Y1378983D03*
X715280Y1384311D03*
X717880D03*
X715280Y1387418D03*
X721080Y1384311D03*
X724024Y1384327D03*
Y1387434D03*
X728044Y1384083D03*
X729294Y1381583D03*
Y1378983D03*
X715480Y1390525D03*
X723993Y1390557D03*
X714393Y1399757D03*
Y1394157D03*
X714455Y1411554D03*
X718230Y1600372D03*
X725378Y1614503D03*
X719770Y1614590D03*
X715780D03*
X722040Y1623970D03*
X713791Y1629816D03*
X721345Y1647300D03*
X716140Y1649895D03*
X726830Y1655380D03*
X724500Y1676500D03*
X744987Y49062D03*
X742840Y39832D03*
X736790D03*
X745130Y69508D03*
X738043D03*
X730957D03*
X731330Y60712D03*
X730820Y84062D03*
X737623Y98858D03*
X734523Y98758D03*
X735733Y111988D03*
X733220Y388362D03*
X737621Y411714D03*
X743720Y404362D03*
X743820Y408262D03*
X731322Y430612D03*
Y462108D03*
X737621Y481006D03*
X730070Y506212D03*
X744630Y506529D03*
X745220Y530362D03*
X737299Y766887D03*
X737784Y1360017D03*
X730752Y1384080D03*
X731794Y1381583D03*
Y1378983D03*
X732238Y1388343D03*
X738810Y1396665D03*
X741540Y1396585D03*
X739170Y1405655D03*
X741670Y1405675D03*
X738170Y1414185D03*
X740760Y1414165D03*
X758606Y23797D03*
X747487Y49062D03*
X752720Y59002D03*
X754219Y75707D03*
X754633Y108288D03*
Y105288D03*
X762172Y123898D03*
X754290Y286632D03*
X755200Y296062D03*
X759940Y438232D03*
X758420Y447662D03*
X751220Y530362D03*
X753137Y766625D03*
X757779Y1390645D03*
X757542Y1420684D03*
X761770Y1695347D03*
X765606Y44894D03*
X769474Y75360D03*
X765858Y87340D03*
X762368Y84088D03*
X769284Y103895D03*
X767061Y99959D03*
X767045Y95960D03*
X767028Y91490D03*
X776730Y117479D03*
X773943Y114633D03*
X771131Y111788D03*
X769775Y107977D03*
X766769Y140138D03*
X771774Y167518D03*
X773220Y296262D03*
X772866Y311558D03*
X776100Y375100D03*
X766195Y418212D03*
X765315Y464862D03*
Y488862D03*
X772220Y530362D03*
X775317Y764025D03*
X763747Y764335D03*
X768520Y1379962D03*
X768620Y1392762D03*
X767820Y1410262D03*
X785095Y49388D03*
X780617Y296345D03*
X779120Y306162D03*
X794600Y360600D03*
X787925Y387900D03*
X781195Y418212D03*
X791590Y417050D03*
X780020Y438287D03*
X781410Y431822D03*
X780340Y468982D03*
Y474862D03*
X793673Y512862D03*
X792720Y589862D03*
X789720Y581862D03*
X783100Y593582D03*
X788225Y1388683D03*
X805095Y49388D03*
X797443Y271469D03*
X806300Y279662D03*
X809700Y273562D03*
X795190Y298572D03*
X798620Y312773D03*
X809800Y360600D03*
X802200D03*
X806588Y351097D03*
X799800Y368700D03*
X802220Y393727D03*
X803150Y408512D03*
X795600Y402500D03*
X799458Y431217D03*
X795370Y474862D03*
X801567Y512942D03*
X798720Y585362D03*
X798220Y597362D03*
X808860Y603802D03*
X797720Y617862D03*
X799637Y763625D03*
X825095Y49388D03*
X821118Y134632D03*
X825698Y139062D03*
X813900Y269698D03*
X827403Y286625D03*
X816420Y287062D03*
X813855Y354008D03*
X820936Y356956D03*
X824980Y405260D03*
Y409260D03*
X821720Y428437D03*
X818500Y451700D03*
X816500Y476800D03*
X821720Y519082D03*
X815040Y590772D03*
X814800Y760922D03*
X822442Y762369D03*
X814234Y1340465D03*
X830975Y2388D03*
X830990Y4903D03*
X837268Y3597D03*
X830975Y22446D03*
Y8543D03*
Y12417D03*
X830990Y14932D03*
X830975Y18572D03*
X837268Y13626D03*
X830990Y24961D03*
X837268Y23655D03*
X836126Y62681D03*
X837791Y85186D03*
X831297Y104206D03*
X842864Y110296D03*
X830339Y228143D03*
X829680Y264580D03*
X836210Y272452D03*
X829720Y277562D03*
X829800Y271562D03*
X829320Y296762D03*
X834400Y283862D03*
X834900Y293462D03*
X828222Y359960D03*
X835471Y363003D03*
X843133Y366158D03*
X833300Y386500D03*
X838784Y392880D03*
X839200Y434300D03*
X841300Y446800D03*
X842600Y477200D03*
X842341Y474241D03*
X841795Y492862D03*
X829745Y498082D03*
X834635Y515447D03*
X830480Y527817D03*
X831700Y596962D03*
X836847Y762495D03*
X828799Y1336870D03*
X828910Y1331756D03*
Y1341725D03*
X845095Y49388D03*
X854107Y91232D03*
X850280Y113852D03*
X853828Y265057D03*
X854333Y276117D03*
X854338Y280027D03*
Y283527D03*
X852800Y288562D03*
X853200Y297462D03*
X856700Y304862D03*
X848000Y374622D03*
X851396Y369614D03*
X859734Y373032D03*
X857560Y417762D03*
X844200Y418800D03*
X847830Y443892D03*
X843810Y453322D03*
X846700Y473000D03*
X848710Y505641D03*
X860345Y522162D03*
X856698Y594011D03*
X853200Y751062D03*
X854687Y761685D03*
X865095Y49388D03*
X868187Y72006D03*
X860937Y71877D03*
X861350Y61672D03*
X871980Y199500D03*
X860833Y276817D03*
X863933Y276917D03*
X862043Y290047D03*
X867922Y376450D03*
X875922Y379793D03*
X870700Y382415D03*
Y390620D03*
Y394620D03*
X871320Y416752D03*
X862620Y503162D03*
Y499062D03*
X860345Y513062D03*
X892214Y141891D03*
X878220Y192055D03*
X880943Y283347D03*
Y286347D03*
X880473Y329370D03*
X883472Y382910D03*
X886362Y534380D03*
X886500Y739162D03*
X878152Y876760D03*
X889439Y1437938D03*
X903930Y202885D03*
X903980Y210355D03*
X903930Y217059D03*
X903980Y224529D03*
X893500Y339062D03*
X900061Y510962D03*
X906127Y496343D03*
X900061Y517898D03*
X893298Y534380D03*
X899462Y533380D03*
X906398D03*
X897000Y891895D03*
X894375Y913692D03*
X912214Y141891D03*
X917680Y174999D03*
Y177999D03*
Y171999D03*
X909386Y195925D03*
Y203011D03*
Y210098D03*
Y217185D03*
Y224271D03*
Y231358D03*
X919279Y461244D03*
X920682Y494586D03*
X920980Y503393D03*
X911720Y511662D03*
X911626Y523430D03*
X918562D03*
X924647Y526808D03*
Y533744D03*
X924600Y824262D03*
X922320Y1660953D03*
X932214Y141891D03*
X927133Y189386D03*
X925320Y203399D03*
X940709Y460438D03*
X938437Y455454D03*
X932724Y455538D03*
X926215Y461244D03*
X929234Y494915D03*
X938588Y485197D03*
X929698Y503595D03*
X928231Y530479D03*
X936273Y530478D03*
X927200Y811462D03*
X931496Y962082D03*
X929221Y1014664D03*
X927122Y1661380D03*
X938220Y1661062D03*
X952214Y141891D03*
X949710Y198289D03*
X941634Y199051D03*
Y193451D03*
X951354Y209437D03*
Y203837D03*
X944880Y210959D03*
Y216559D03*
Y230697D03*
Y225097D03*
X954874Y232071D03*
X954904Y225741D03*
X942827Y422743D03*
Y429679D03*
X945800Y432463D03*
Y439399D03*
X946492Y460410D03*
X956188Y495384D03*
Y502320D03*
X948495Y502784D03*
X948693Y509497D03*
X956188Y509484D03*
Y516420D03*
X952622Y529364D03*
X956700Y786862D03*
X941400Y810062D03*
X946100Y1661100D03*
X972214Y141891D03*
X963520Y214699D03*
X960703Y212668D03*
X971471Y242358D03*
X965792Y350959D03*
X965420Y365719D03*
X963856Y394202D03*
X960059Y387004D03*
X972986Y393171D03*
X970054Y478773D03*
Y485709D03*
X966720Y511362D03*
X960620Y509462D03*
X972379Y509303D03*
X959558Y529364D03*
X962162Y535130D03*
X969098D03*
X958755Y657078D03*
X963520Y665062D03*
X958866Y662378D03*
X959100Y789862D03*
X975688Y152950D03*
Y149950D03*
X985016Y344659D03*
X974791Y339990D03*
X986182Y361062D03*
X979380Y373082D03*
X988159Y409068D03*
X983760Y424292D03*
X980092Y421289D03*
X983720Y512362D03*
X976283Y534226D03*
X994553Y365711D03*
X997598Y382952D03*
X997612Y391804D03*
X1006221Y382945D03*
X997900Y400720D03*
X993387Y429827D03*
X999720Y512862D03*
X991097Y529902D03*
X996675Y1286985D03*
X1012214Y141826D03*
X1022002Y267342D03*
Y270142D03*
X1013500Y344900D03*
X1015638Y382968D03*
X1015637Y391334D03*
X1006589Y392017D03*
X1006750Y401010D03*
X1015657Y401013D03*
X1021259Y420548D03*
X1007249Y422682D03*
X1017511Y430038D03*
X1008720Y498362D03*
X1019145Y503823D03*
X1011720Y589362D03*
X1018720Y592362D03*
X1021720Y601862D03*
X1010630Y748741D03*
X1023407Y-27681D03*
X1029700Y-26472D03*
X1023407Y-32055D03*
X1029700Y-37001D03*
X1023407Y-17652D03*
X1023422Y-15137D03*
X1023407Y-11497D03*
X1029700Y-16443D03*
X1023422Y-25166D03*
X1023407Y-21526D03*
X1029700Y3615D03*
X1023422Y4921D03*
X1023407Y2406D03*
X1023422Y-5108D03*
X1023407Y-7623D03*
Y-1468D03*
X1029700Y-6414D03*
X1023407Y22464D03*
Y18590D03*
Y8561D03*
X1023422Y14950D03*
X1023407Y12435D03*
X1029700Y13644D03*
Y23673D03*
X1023422Y24979D03*
X1038609Y49388D03*
X1027520Y122732D03*
X1037650Y128842D03*
X1023220Y187574D03*
X1031502Y267342D03*
X1028202D03*
X1025102D03*
X1033133Y272564D03*
X1031502Y270142D03*
X1029833Y272564D03*
X1026733D03*
X1023633D03*
X1028202Y270142D03*
X1025102D03*
X1029094Y383070D03*
Y387872D03*
X1033860Y400802D03*
X1038294Y506504D03*
X1027190Y510672D03*
X1029220Y520032D03*
X1043629Y375078D03*
Y372578D03*
X1049100Y390162D03*
X1046156Y442699D03*
X1058609Y49388D03*
X1066820Y151632D03*
X1072310Y364422D03*
X1078609Y49388D03*
X1075100Y55682D03*
X1084146Y67102D03*
X1078270Y93462D03*
X1077270Y369061D03*
Y374131D03*
Y379251D03*
X1073724Y476867D03*
X1081906Y472577D03*
X1076739Y506461D03*
X1077751Y522235D03*
X1098609Y49388D03*
X1097794Y67881D03*
X1102480Y133722D03*
X1105553Y356475D03*
X1096477Y744385D03*
X1102930Y1668690D03*
X1092072Y1734244D03*
X1118609Y49388D03*
X1118110Y1398010D03*
X1109118Y1526046D03*
X1116338Y1711380D03*
X1113055Y1718338D03*
X1132856Y52926D03*
X1129948Y66786D03*
X1127788Y1397126D03*
X1131629Y1420615D03*
X1129029D03*
X1134229D03*
X1123674Y1414936D03*
X1121174D03*
X1123674Y1417536D03*
Y1420136D03*
X1121174Y1417536D03*
Y1420136D03*
X1131629Y1423722D03*
X1129029D03*
X1134229D03*
X1123674Y1422736D03*
X1121174D03*
X1131042Y1436061D03*
X1135942D03*
X1133512D03*
X1131042Y1430461D03*
X1135942D03*
X1133512D03*
X1134429Y1426829D03*
X1136004Y1447858D03*
X1126117Y1450504D03*
X1127008Y1550285D03*
X1133780Y1550301D03*
X1138609Y49388D03*
X1145603Y73679D03*
X1140465Y379592D03*
X1142302Y366532D03*
X1142790Y611122D03*
X1146118Y1397126D03*
X1150843Y1415126D03*
X1148243D03*
X1150843Y1417726D03*
X1148243D03*
X1150732Y1420326D03*
X1142629Y1420615D03*
X1145573Y1420631D03*
X1139429Y1420615D03*
X1136829D03*
X1145573Y1423738D03*
X1136829Y1423722D03*
X1145542Y1426861D03*
X1137029Y1426829D03*
X1145108Y1476732D03*
X1158609Y49388D03*
X1156790Y373231D03*
X1153467Y586462D03*
X1153490Y610322D03*
X1165931Y1397126D03*
X1154714Y1398295D03*
X1157786Y1398252D03*
X1167172Y1420615D03*
X1153913Y1420606D03*
Y1415406D03*
Y1418006D03*
X1159124D03*
Y1420606D03*
Y1415406D03*
X1161724D03*
Y1420606D03*
Y1418006D03*
X1156524Y1415406D03*
Y1420606D03*
Y1418006D03*
X1167172Y1423722D03*
X1153913Y1423206D03*
X1159124D03*
X1161724D03*
X1156524D03*
X1155964Y1440864D03*
X1164260Y1450423D03*
X1158954Y1450274D03*
X1168192Y1604130D03*
X1152950Y1616470D03*
X1165950Y1617729D03*
X1152930Y1633880D03*
X1174980Y585632D03*
X1174880Y592652D03*
X1173990Y602192D03*
X1183230Y739102D03*
X1184661Y1397126D03*
X1183716Y1420631D03*
X1180772Y1420615D03*
X1174972D03*
X1177572D03*
X1172372D03*
X1169772D03*
X1183716Y1423738D03*
X1174972Y1423722D03*
X1172372D03*
X1169772D03*
X1174085Y1436061D03*
Y1430461D03*
X1171655Y1436061D03*
X1169185D03*
X1171655Y1430461D03*
X1169185D03*
X1183685Y1426861D03*
X1175172Y1426829D03*
X1172572D03*
X1174147Y1447858D03*
X1179922Y1550285D03*
X1184501Y1606521D03*
X1185030Y1633010D03*
X1182470Y1618914D03*
X1172530Y1623020D03*
X1176900Y1627510D03*
X1198609Y49388D03*
X1188720Y56755D03*
X1191700Y56822D03*
X1185500Y101400D03*
X1190700Y99000D03*
X1197627Y132859D03*
X1196100Y188962D03*
X1193500D03*
X1192600Y217662D03*
X1193000Y204486D03*
X1195500D03*
X1195100Y217662D03*
X1194840Y240672D03*
X1199027Y588714D03*
X1189135Y1397529D03*
X1187736Y1420387D03*
X1188986Y1415287D03*
Y1417887D03*
X1186386Y1415287D03*
Y1417887D03*
X1191486Y1415287D03*
Y1417887D03*
X1190444Y1420384D03*
X1194750Y1424672D03*
X1197700Y1432672D03*
X1191930Y1424647D03*
X1198010Y1441902D03*
X1198880Y1457162D03*
X1197181Y1563587D03*
X1195994Y1580678D03*
Y1575686D03*
X1200950Y1580678D03*
Y1575686D03*
X1201294Y1599884D03*
X1195994Y1592590D03*
Y1587598D03*
X1200950Y1592590D03*
Y1587598D03*
X1201294Y1604876D03*
Y1611796D03*
Y1616788D03*
X1213026Y56742D03*
X1201800Y94600D03*
X1204800Y108900D03*
X1206900Y115900D03*
X1214573Y148909D03*
X1204420Y195362D03*
X1210084Y224362D03*
X1207220Y247148D03*
X1217720Y249862D03*
X1204880Y754032D03*
X1213010Y1575686D03*
X1208054D03*
X1213010Y1580678D03*
X1208054D03*
X1206250Y1599884D03*
X1213354D03*
X1213010Y1587598D03*
X1208054D03*
X1213010Y1592590D03*
X1208054D03*
X1206250Y1604876D03*
Y1611796D03*
Y1616788D03*
X1213354D03*
Y1604876D03*
Y1611796D03*
X1213980Y1676500D03*
X1218609Y49388D03*
X1228420Y58862D03*
X1230250Y89450D03*
X1223720Y217862D03*
Y205862D03*
X1232000Y244332D03*
Y248332D03*
X1225070Y1580678D03*
Y1575686D03*
X1220114D03*
Y1580678D03*
X1232174D03*
Y1575686D03*
X1218310Y1599884D03*
X1225414D03*
X1230370D03*
X1225070Y1592590D03*
X1220114D03*
X1225070Y1587598D03*
X1220114D03*
X1232174D03*
Y1592590D03*
X1218310Y1616788D03*
Y1604876D03*
Y1611796D03*
X1225414D03*
Y1604876D03*
X1230370Y1611796D03*
Y1604876D03*
X1225414Y1616788D03*
X1230370D03*
X1238609Y49388D03*
X1239907Y95008D03*
X1243808Y116832D03*
X1247333Y121999D03*
X1236520Y213462D03*
X1246444Y256098D03*
X1252040Y306480D03*
X1237130Y1575686D03*
Y1580678D03*
X1244234D03*
X1249190D03*
X1244234Y1575686D03*
X1249190D03*
X1242430Y1599884D03*
X1237474D03*
X1249534D03*
X1237130Y1587598D03*
Y1592590D03*
X1249190D03*
X1244234D03*
Y1587598D03*
X1249190D03*
X1242430Y1616788D03*
X1237474D03*
X1242430Y1611796D03*
Y1604876D03*
X1237474Y1611796D03*
Y1604876D03*
X1249534Y1611796D03*
Y1604876D03*
Y1616788D03*
X1258609Y49388D03*
X1262800Y101100D03*
X1264620Y92724D03*
X1252961Y111903D03*
X1267150Y305998D03*
X1256787Y749605D03*
X1261250Y1575686D03*
X1256294D03*
X1261250Y1580678D03*
X1256294D03*
X1254490Y1599884D03*
X1261594D03*
X1261250Y1587598D03*
X1256294D03*
X1261250Y1592590D03*
X1256294D03*
X1254490Y1611796D03*
Y1604876D03*
Y1616788D03*
X1261594D03*
Y1611796D03*
Y1604876D03*
X1278300Y81232D03*
X1280135Y1340002D03*
Y1337402D03*
Y1345202D03*
Y1342602D03*
X1280312Y1365689D03*
X1273310Y1580678D03*
Y1575592D03*
X1268354D03*
Y1580678D03*
X1280414Y1575686D03*
Y1580678D03*
X1266550Y1599884D03*
X1273654Y1599790D03*
X1278610D03*
X1273310Y1592590D03*
X1268354D03*
X1273310Y1587598D03*
X1268354D03*
X1280414D03*
Y1592590D03*
X1266550Y1616788D03*
Y1611796D03*
Y1604876D03*
X1273654Y1611796D03*
Y1604876D03*
X1278610Y1611796D03*
Y1604876D03*
X1273654Y1616788D03*
X1278610D03*
X1295278Y297056D03*
X1290322D03*
X1294937Y746965D03*
X1292904Y782048D03*
X1292614Y789910D03*
X1291205Y1345875D03*
X1286005Y1342768D03*
Y1345875D03*
X1296405Y1342768D03*
X1293805D03*
X1288605D03*
X1291205D03*
X1288605Y1345875D03*
X1293805D03*
X1291405Y1348982D03*
X1294005D03*
X1292916Y1352531D03*
X1290436D03*
X1287956D03*
X1292916Y1358131D03*
X1290436D03*
X1287956D03*
X1283280Y1372301D03*
X1293887Y1370043D03*
X1294477Y1372651D03*
X1285370Y1575686D03*
Y1580678D03*
X1297430D03*
X1292474D03*
Y1575686D03*
X1297430D03*
X1285714Y1599884D03*
X1290670D03*
X1297774D03*
X1285370Y1587598D03*
Y1592590D03*
X1297430D03*
X1292474D03*
X1297430Y1587598D03*
X1292474D03*
X1290670Y1616788D03*
X1285714D03*
Y1611796D03*
X1290670D03*
X1285714Y1604876D03*
X1290670D03*
X1297774Y1611796D03*
Y1604876D03*
Y1616788D03*
X1311960Y49672D03*
X1314450Y319841D03*
X1312845Y324764D03*
X1305909D03*
X1303017Y785837D03*
X1311952Y1321945D03*
X1307656Y1337104D03*
X1305056D03*
X1307656Y1334504D03*
Y1329304D03*
Y1331904D03*
X1305056Y1334504D03*
Y1329304D03*
Y1331904D03*
Y1339704D03*
X1312488Y1348353D03*
X1299605Y1342768D03*
X1302549Y1345891D03*
X1302520Y1348762D03*
X1315058Y1349488D03*
X1302549Y1342784D03*
X1309490Y1575686D03*
X1304534D03*
X1309490Y1580678D03*
X1304534D03*
X1302730Y1599884D03*
X1309834D03*
X1314790D03*
X1309490Y1587598D03*
X1304534D03*
X1309490Y1592590D03*
X1304534D03*
X1302730Y1611796D03*
Y1604876D03*
Y1616788D03*
X1309834D03*
Y1611796D03*
Y1604876D03*
X1314790Y1616788D03*
Y1611796D03*
Y1604876D03*
X1318609Y49388D03*
X1319125Y296540D03*
X1324081D03*
X1324636Y290920D03*
X1329592D03*
X1330248Y325670D03*
X1323312D03*
X1321386Y319841D03*
X1329977Y334384D03*
X1327601Y540049D03*
X1317970Y1322741D03*
Y1319634D03*
X1325770Y1322741D03*
X1323170D03*
X1331570Y1319634D03*
X1323170D03*
X1325770D03*
X1328370D03*
X1320570Y1322741D03*
Y1319634D03*
X1322444Y1329497D03*
X1324924D03*
X1319964D03*
X1322444Y1335097D03*
X1324924D03*
X1319964D03*
X1323370Y1325848D03*
X1325970D03*
X1324945Y1346877D03*
X1327196Y1349068D03*
X1321550Y1580678D03*
X1316594D03*
X1321550Y1575686D03*
X1316594D03*
X1328654D03*
Y1580678D03*
X1321894Y1599884D03*
X1326850D03*
X1321550Y1592590D03*
X1316594D03*
X1321550Y1587598D03*
X1316594D03*
X1328654D03*
Y1592590D03*
X1321894Y1611796D03*
Y1604876D03*
X1326850Y1611796D03*
Y1604876D03*
X1321894Y1616788D03*
X1326850D03*
X1332726Y-27681D03*
X1339019Y-26472D03*
X1332726Y-32055D03*
X1339019Y-37001D03*
X1332726Y-11497D03*
X1339019Y-16443D03*
X1332741Y-15137D03*
X1332726Y-17652D03*
Y-21526D03*
X1332741Y-25166D03*
X1332726Y2406D03*
X1332741Y4921D03*
X1339019Y3615D03*
X1332726Y-1468D03*
X1339019Y-6414D03*
X1332726Y-7623D03*
X1332741Y-5108D03*
X1332726Y18590D03*
Y22464D03*
X1339019Y13644D03*
X1332726Y12435D03*
X1332741Y14950D03*
X1332726Y8561D03*
X1332741Y24979D03*
X1339019Y23673D03*
X1338609Y49388D03*
X1346720Y82912D03*
X1343362Y283155D03*
X1335947Y290755D03*
X1340903D03*
X1343656Y330749D03*
X1343199Y324461D03*
X1336263D03*
X1336913Y334384D03*
X1335643Y540048D03*
X1336187Y755635D03*
X1339784Y1306506D03*
X1337184D03*
X1344080Y1305919D03*
X1343968Y1300579D03*
X1344080Y1308519D03*
X1334514Y1322757D03*
Y1319650D03*
X1337184Y1309106D03*
X1339784D03*
X1338534Y1319406D03*
X1339784Y1316906D03*
Y1314306D03*
Y1311706D03*
X1337184Y1314306D03*
Y1316906D03*
Y1311706D03*
X1334414Y1325853D03*
X1347015Y1335876D03*
X1343631Y1332568D03*
X1333610Y1575686D03*
Y1580678D03*
X1345670D03*
X1340714D03*
X1345670Y1575686D03*
X1340714D03*
X1338910Y1599884D03*
X1333954D03*
X1346014D03*
X1333610Y1587598D03*
Y1592590D03*
X1345670D03*
X1340714D03*
X1345670Y1587598D03*
X1340714D03*
X1338910Y1616788D03*
Y1611796D03*
Y1604876D03*
X1333954Y1616788D03*
Y1611796D03*
Y1604876D03*
X1346014Y1611796D03*
Y1604876D03*
Y1616788D03*
X1350550Y101632D03*
X1363846Y279848D03*
X1349362Y283155D03*
X1353902Y287540D03*
X1359902D03*
X1350592Y330749D03*
X1356968Y339611D03*
X1350032D03*
X1363539Y334043D03*
X1356603D03*
X1350098Y1306208D03*
X1352698D03*
X1355298D03*
X1360498D03*
X1363698D03*
X1357898D03*
X1352698Y1309315D03*
X1350098D03*
X1355498Y1312422D03*
X1358098D03*
X1355298Y1309315D03*
X1357898D03*
X1352092Y1316071D03*
Y1321671D03*
X1357052Y1316071D03*
X1354572D03*
X1357052Y1321671D03*
X1354572D03*
X1356983Y1334095D03*
X1359516Y1334058D03*
X1355357Y1396020D03*
X1357730Y1575686D03*
X1352774D03*
X1357730Y1580678D03*
X1352774D03*
X1350970Y1599884D03*
X1363030D03*
X1358074D03*
X1357730Y1587598D03*
X1352774D03*
X1357730Y1592590D03*
X1352774D03*
X1350970Y1611796D03*
Y1604876D03*
Y1616788D03*
X1363030D03*
Y1611796D03*
Y1604876D03*
X1358074Y1616788D03*
Y1611796D03*
Y1604876D03*
X1378550Y110692D03*
X1377742Y244372D03*
Y250372D03*
X1377626Y258914D03*
Y264914D03*
X1369846Y279848D03*
X1372381Y661428D03*
X1371931Y672978D03*
Y685278D03*
X1372243Y697108D03*
Y709108D03*
Y721108D03*
X1370662Y1305980D03*
X1371912Y1303480D03*
X1376208Y1305919D03*
Y1303319D03*
X1371912Y1300880D03*
X1376208Y1300719D03*
Y1295586D03*
X1371912Y1295747D03*
Y1298280D03*
X1376208Y1298119D03*
X1369312Y1303480D03*
X1366642Y1306224D03*
X1369312Y1300880D03*
Y1295747D03*
Y1298280D03*
X1376208Y1308519D03*
X1366542Y1312427D03*
X1366642Y1309331D03*
X1379271Y1335963D03*
X1375814Y1332653D03*
X1377060Y1411231D03*
X1371960Y1436172D03*
X1365040Y1431142D03*
X1369790Y1580678D03*
X1364834D03*
X1369790Y1575592D03*
X1364834D03*
X1376894Y1575686D03*
Y1580678D03*
X1375090Y1599790D03*
X1370134D03*
X1369790Y1592590D03*
X1364834D03*
X1369790Y1587598D03*
X1364834D03*
X1376894D03*
Y1592590D03*
X1375090Y1611796D03*
Y1604876D03*
Y1616788D03*
X1370134Y1611796D03*
Y1604876D03*
Y1616788D03*
X1383480Y88932D03*
X1383734Y243329D03*
Y237329D03*
X1388778Y250661D03*
X1388908Y260301D03*
X1386237Y265620D03*
Y275200D03*
X1385190Y501242D03*
X1390220Y497742D03*
X1381131Y656378D03*
Y668378D03*
X1395831Y666278D03*
X1386931Y660978D03*
X1381131Y680278D03*
X1396031Y680678D03*
X1386931Y675478D03*
X1387143Y690208D03*
X1380731Y692208D03*
X1395631Y695108D03*
X1380731Y704208D03*
X1387143Y704708D03*
X1380731Y716208D03*
X1395631Y709608D03*
X1387143Y719235D03*
X1395631Y724135D03*
X1382920Y733725D03*
X1391408Y738625D03*
X1382226Y1306208D03*
X1384826D03*
X1387426D03*
X1390026D03*
X1392626D03*
X1395826D03*
X1386700Y1321671D03*
X1389180D03*
X1382226Y1309315D03*
X1384826D03*
X1390226Y1312422D03*
X1387626D03*
X1390026Y1309315D03*
X1387426D03*
X1384220Y1316071D03*
Y1321671D03*
X1389180Y1316071D03*
X1386700D03*
X1390758Y1333473D03*
X1392076Y1335658D03*
X1388813Y1393160D03*
X1396115Y1405289D03*
Y1412789D03*
X1396615Y1420289D03*
X1384695Y1425047D03*
X1392475Y1576097D03*
X1381850Y1575686D03*
Y1580678D03*
X1396600Y1582500D03*
X1387150Y1599884D03*
X1382194D03*
X1381850Y1587598D03*
Y1592590D03*
X1396600Y1594000D03*
X1387150Y1616788D03*
X1382194D03*
X1387150Y1611796D03*
Y1604876D03*
X1382194Y1611796D03*
Y1604876D03*
X1404630Y220018D03*
X1412270Y230952D03*
X1405436Y238378D03*
X1400207Y238257D03*
X1398770Y1306224D03*
X1404040Y1303480D03*
X1408336Y1305919D03*
Y1303319D03*
X1404040Y1300880D03*
X1408336Y1300719D03*
Y1295586D03*
X1404040Y1295747D03*
Y1298280D03*
X1408336Y1298119D03*
X1401440Y1303480D03*
X1402790Y1305980D03*
X1401440Y1300880D03*
Y1295747D03*
Y1298280D03*
X1408336Y1308519D03*
X1398670Y1312427D03*
X1398770Y1309331D03*
X1411124Y1335924D03*
X1407719Y1332560D03*
X1403615Y1405289D03*
X1411115D03*
Y1412789D03*
X1403615Y1420289D03*
X1411115D03*
X1403350Y1516435D03*
X1403590Y1532255D03*
X1403350Y1521335D03*
X1403740Y1548375D03*
X1403590Y1537155D03*
X1403740Y1543475D03*
X1407200Y1591400D03*
X1411070Y1603282D03*
X1400000Y1630362D03*
Y1642362D03*
X1413350Y220018D03*
X1416020D03*
X1424690D03*
X1424520Y225002D03*
X1416810Y225422D03*
X1428640Y230022D03*
X1431430Y251265D03*
X1428940Y269292D03*
X1414354Y1306208D03*
X1416954D03*
X1419554D03*
X1422154D03*
X1424754D03*
X1427954D03*
X1418828Y1316071D03*
X1416348D03*
X1418828Y1321671D03*
X1416348D03*
X1421308Y1316071D03*
Y1321671D03*
X1414354Y1309315D03*
X1416954D03*
X1419554D03*
X1422354Y1312422D03*
X1419754D03*
X1422154Y1309315D03*
X1421294Y1334095D03*
X1423656Y1335468D03*
X1429345Y1433695D03*
X1427349Y1442776D03*
X1414264Y1439494D03*
X1419256Y1440258D03*
X1423829Y1442776D03*
X1416800Y1564862D03*
X1428403Y1581378D03*
X1418241Y1583441D03*
X1422145Y1575362D03*
X1426680Y1603262D03*
X1425770Y1633772D03*
X1413230Y1641042D03*
X1438609Y49388D03*
X1441125Y57362D03*
X1438680Y64412D03*
X1441490Y224062D03*
X1438720Y220018D03*
X1430130Y259342D03*
X1437177Y720965D03*
X1437182Y1298991D03*
X1430898Y1306224D03*
X1434582Y1304191D03*
Y1306791D03*
Y1301591D03*
Y1296458D03*
Y1298991D03*
X1440507Y1305430D03*
Y1302830D03*
Y1300230D03*
X1440536Y1296455D03*
X1440464Y1308519D03*
X1437182Y1304191D03*
Y1306791D03*
Y1301591D03*
Y1296458D03*
X1430798Y1312427D03*
X1430898Y1309331D03*
X1443785Y1335981D03*
X1440879Y1333085D03*
X1439155Y1399064D03*
X1431717Y1420625D03*
Y1417125D03*
Y1409125D03*
Y1427632D03*
X1436330Y1521152D03*
X1436570Y1536972D03*
X1436720Y1548192D03*
X1437140Y1576012D03*
X1438300Y1598400D03*
X1430250Y1608442D03*
X1438300Y1611000D03*
X1438273Y1671103D03*
X1458609Y49388D03*
X1458720Y153362D03*
Y149362D03*
Y169862D03*
Y165862D03*
Y161862D03*
Y157862D03*
Y181862D03*
Y177862D03*
Y173862D03*
X1446830Y236232D03*
X1453670Y278170D03*
X1459312Y341130D03*
X1460600Y352742D03*
X1456700Y369642D03*
X1454889Y658712D03*
X1454439Y670262D03*
Y682562D03*
X1454751Y694392D03*
Y706392D03*
X1454439Y718362D03*
X1459057Y733545D03*
X1457597Y739035D03*
X1446482Y1306208D03*
X1449082D03*
X1451682D03*
X1456882D03*
X1460082D03*
X1454282D03*
X1450956Y1321671D03*
X1448476D03*
X1453436Y1316071D03*
Y1321671D03*
X1446482Y1309315D03*
X1451882Y1312422D03*
X1449082Y1309315D03*
X1451682D03*
X1454482Y1312422D03*
X1454282Y1309315D03*
X1450956Y1316071D03*
X1448476D03*
X1453303Y1334095D03*
X1455436Y1335598D03*
X1461377Y1417844D03*
X1459135Y1439627D03*
X1459136Y1442241D03*
X1461517Y1575686D03*
Y1580678D03*
X1446600Y1595400D03*
X1461517Y1587598D03*
Y1592590D03*
X1460441Y1602441D03*
X1446786Y1610639D03*
X1452757Y1671399D03*
X1446380Y1676291D03*
X1464200Y67802D03*
X1470220Y145362D03*
X1470101Y207751D03*
X1476858Y225448D03*
X1466940Y230272D03*
X1466958Y244948D03*
X1468620Y258857D03*
X1467230Y252472D03*
X1466660Y273878D03*
X1475790Y404842D03*
X1473310Y418502D03*
X1463639Y653662D03*
X1469651Y655992D03*
X1462010Y645842D03*
X1463639Y665662D03*
X1478139Y660892D03*
X1469439Y670262D03*
X1463639Y677562D03*
X1463239Y689492D03*
X1478139Y689892D03*
X1469651Y684992D03*
X1463239Y701492D03*
X1478139Y704392D03*
X1469477Y699475D03*
X1463239Y713492D03*
X1478139Y718892D03*
X1469651Y713992D03*
X1474100Y735662D03*
X1466451Y726992D03*
X1474939Y731892D03*
X1472592Y1306345D03*
X1463026Y1306224D03*
X1465696Y1303480D03*
X1467046Y1305980D03*
X1468296Y1303480D03*
X1465696Y1300880D03*
X1468296D03*
X1472361Y1322440D03*
X1472592Y1308945D03*
Y1316745D03*
Y1314145D03*
Y1311545D03*
X1462926Y1312427D03*
X1463026Y1309331D03*
X1475599Y1349468D03*
X1475959Y1385027D03*
X1476000Y1393027D03*
X1465747Y1401405D03*
X1466448Y1421499D03*
X1475935Y1439627D03*
X1475936Y1442241D03*
X1467550Y1439642D03*
X1467536Y1442241D03*
X1473577Y1580678D03*
Y1575686D03*
X1466473D03*
Y1580678D03*
X1471773Y1599884D03*
X1466817D03*
X1473577Y1592590D03*
Y1587598D03*
X1466473D03*
Y1592590D03*
X1466817Y1611796D03*
X1471773D03*
X1466817Y1604876D03*
X1471773D03*
Y1616788D03*
X1466817D03*
X1478609Y49388D03*
X1481360Y358792D03*
X1488500Y410152D03*
X1478539Y675462D03*
X1486410Y1322741D03*
X1483810D03*
X1486410Y1319634D03*
X1483810D03*
X1481210Y1322741D03*
Y1319634D03*
X1492210D03*
X1489010D03*
X1478610Y1322741D03*
Y1319634D03*
X1484010Y1325848D03*
X1486610D03*
X1485564Y1335097D03*
X1483084D03*
X1485564Y1329497D03*
X1483084D03*
X1480604Y1335097D03*
Y1329497D03*
X1485523Y1347521D03*
X1487386Y1349258D03*
X1478559Y1385027D03*
X1481159Y1384727D03*
X1478600Y1393027D03*
X1481107Y1393095D03*
X1484395Y1439598D03*
X1484336Y1442241D03*
X1490593Y1580678D03*
Y1575686D03*
X1485637D03*
Y1580678D03*
X1478533D03*
Y1575686D03*
X1490937Y1599884D03*
X1478877D03*
X1483833D03*
X1490593Y1587598D03*
X1485637D03*
Y1592590D03*
X1490593D03*
X1478533D03*
Y1587598D03*
X1490937Y1604876D03*
Y1611796D03*
Y1616788D03*
X1483833D03*
X1478877D03*
Y1611796D03*
X1483833D03*
X1478877Y1604876D03*
X1483833D03*
X1498609Y49388D03*
X1496200Y359522D03*
X1497880Y373062D03*
X1503450Y382693D03*
X1497770Y732502D03*
X1495154Y1322757D03*
Y1319650D03*
X1499048Y1319946D03*
X1504720Y1329143D03*
X1495054Y1325853D03*
X1503786Y1326076D03*
X1504518Y1335982D03*
X1504720Y1342143D03*
Y1344743D03*
X1505116Y1369724D03*
X1509757Y1575686D03*
Y1580678D03*
X1502653D03*
X1497697D03*
X1502653Y1575686D03*
X1497697D03*
X1502997Y1599884D03*
X1507953D03*
X1495893D03*
X1509757Y1587598D03*
Y1592590D03*
X1502653D03*
X1497697D03*
X1502653Y1587598D03*
X1497697D03*
X1502997Y1616788D03*
X1507953D03*
X1502997Y1604876D03*
Y1611796D03*
X1507953Y1604876D03*
Y1611796D03*
X1495893Y1604876D03*
Y1611796D03*
Y1616788D03*
X1518608Y49377D03*
X1522920Y113030D03*
X1526675Y140117D03*
X1526083Y146225D03*
X1513759Y263676D03*
X1516683Y278437D03*
X1511624Y291175D03*
X1519336Y303426D03*
X1520094Y306543D03*
X1514369Y308467D03*
X1524505Y748912D03*
X1522066Y1312808D03*
X1526066D03*
X1518066D03*
X1515066D03*
X1511066D03*
X1510738Y1345539D03*
Y1342432D03*
X1518538Y1345539D03*
Y1342432D03*
X1515938Y1345539D03*
Y1342432D03*
X1513338Y1345539D03*
Y1342432D03*
X1521138D03*
X1524338D03*
X1518738Y1348646D03*
X1516138D03*
X1515212Y1352295D03*
X1512732D03*
X1517692D03*
X1515212Y1357895D03*
X1512732D03*
X1517692D03*
X1518451Y1369919D03*
X1521817Y1580678D03*
Y1575686D03*
X1514713D03*
Y1580678D03*
X1520013Y1599884D03*
X1515057D03*
X1521817Y1592590D03*
Y1587598D03*
X1514713D03*
Y1592590D03*
X1520013Y1604876D03*
X1515057D03*
X1520013Y1611796D03*
X1515057D03*
Y1616788D03*
X1520013D03*
X1534818Y66801D03*
Y71793D03*
X1539774Y66801D03*
Y71793D03*
X1541774Y69297D03*
X1532818D03*
X1534774Y103093D03*
X1529818D03*
X1535320Y113062D03*
X1529500Y129602D03*
X1545447Y156035D03*
X1537262Y197834D03*
X1540989Y616587D03*
X1535052Y1325904D03*
X1532552Y1334504D03*
X1535052D03*
X1529952D03*
X1532552Y1339704D03*
X1529952D03*
X1537652Y1325904D03*
Y1334504D03*
X1532552Y1337104D03*
X1529952D03*
X1538510Y1346392D03*
X1531302Y1342204D03*
X1535892Y1346354D03*
Y1343754D03*
X1527282Y1345555D03*
Y1342448D03*
X1538757Y1356355D03*
X1527182Y1348651D03*
X1538757Y1360855D03*
Y1365355D03*
X1533877Y1575592D03*
X1538833D03*
X1533877Y1580678D03*
X1538833D03*
X1526773D03*
Y1575686D03*
X1539177Y1599790D03*
X1527117Y1599884D03*
X1532073D03*
X1533877Y1587598D03*
X1538833D03*
X1533877Y1592590D03*
X1538833D03*
X1526773D03*
Y1587598D03*
X1539177Y1611796D03*
Y1604876D03*
Y1616788D03*
X1527117D03*
Y1604876D03*
Y1611796D03*
X1532073Y1616788D03*
Y1604876D03*
Y1611796D03*
X1547768Y3010D03*
X1555635Y16999D03*
Y21991D03*
X1553635Y19495D03*
X1553486Y23935D03*
X1548530D03*
X1546530Y25931D03*
X1555486D03*
X1547429Y37106D03*
X1554515D03*
Y48720D03*
X1547429D03*
X1554818Y69297D03*
X1556818Y66801D03*
Y71793D03*
X1543818Y75297D03*
X1552774D03*
X1550774Y77793D03*
Y72801D03*
X1545818Y77793D03*
Y72801D03*
X1554239Y138263D03*
X1554723Y200375D03*
X1557560Y196912D03*
X1554723Y224529D03*
Y248945D03*
X1554727Y631527D03*
X1550417Y677045D03*
X1550057Y693485D03*
X1548479Y706088D03*
X1557997Y1575686D03*
Y1580678D03*
X1550893D03*
X1545937D03*
X1550893Y1575686D03*
X1545937D03*
X1556193Y1599884D03*
X1551237D03*
X1544133Y1599790D03*
X1557997Y1587598D03*
Y1592590D03*
X1545937D03*
X1550893D03*
Y1587598D03*
X1545937D03*
X1551237Y1616788D03*
X1556193D03*
Y1604876D03*
X1551237D03*
X1556193Y1611796D03*
X1551237D03*
X1544133Y1604876D03*
Y1611796D03*
Y1616788D03*
X1567768Y3010D03*
X1560591Y16999D03*
Y21991D03*
X1569808Y16999D03*
Y21991D03*
X1574764Y16999D03*
Y21991D03*
X1562591Y19495D03*
X1567808D03*
X1567659Y23935D03*
X1562703D03*
X1560703Y25931D03*
X1569659D03*
X1574876D03*
X1561602Y37106D03*
X1568688D03*
Y48720D03*
X1561602D03*
X1563774Y69297D03*
X1561774Y66801D03*
Y71793D03*
X1565818Y75297D03*
X1574774D03*
X1572774Y77793D03*
Y72801D03*
X1567818Y77793D03*
Y72801D03*
X1559860Y240002D03*
X1575169Y303929D03*
X1560717Y648522D03*
X1570720Y729362D03*
X1570057Y1580678D03*
X1575013D03*
X1570057Y1575686D03*
X1575013D03*
X1562953D03*
Y1580678D03*
X1575357Y1599884D03*
X1563297D03*
X1568253D03*
X1570057Y1592590D03*
X1575013D03*
X1570057Y1587598D03*
X1575013D03*
X1562953D03*
Y1592590D03*
X1575357Y1616788D03*
Y1604876D03*
Y1611796D03*
X1563297Y1604876D03*
Y1611796D03*
X1568253Y1604876D03*
Y1611796D03*
X1563297Y1616788D03*
X1568253D03*
X1587768Y3010D03*
X1583981Y16999D03*
Y21991D03*
X1588937Y16999D03*
Y21991D03*
X1576764Y19495D03*
X1581981D03*
X1590937D03*
X1576876Y23935D03*
X1581832D03*
X1591050D03*
X1583832Y25931D03*
X1589050D03*
X1575775Y37106D03*
X1582862D03*
X1589948D03*
Y48720D03*
X1582862D03*
X1575775D03*
X1576818Y69297D03*
X1585774D03*
X1578818Y66801D03*
Y71793D03*
X1583774Y66801D03*
Y71793D03*
X1587818Y75297D03*
X1589818Y77793D03*
Y72801D03*
X1582117Y1575686D03*
X1587073D03*
X1582117Y1580678D03*
X1587073D03*
X1587417Y1599884D03*
X1580313D03*
X1582117Y1587598D03*
X1587073D03*
X1582117Y1592590D03*
X1587073D03*
X1587417Y1604876D03*
Y1611796D03*
Y1616788D03*
X1580313D03*
Y1604876D03*
Y1611796D03*
X1607768Y3010D03*
X1598155Y16999D03*
Y21991D03*
X1603111Y16999D03*
Y21991D03*
X1596155Y19495D03*
X1605111D03*
X1596006Y23935D03*
X1598006Y25931D03*
X1597035Y37106D03*
X1604122D03*
Y48720D03*
X1597035D03*
X1598818Y69297D03*
X1607774D03*
X1600818Y66801D03*
Y71793D03*
X1605774Y66801D03*
Y71793D03*
X1596774Y75297D03*
X1594774Y77793D03*
Y72801D03*
X1603778Y189943D03*
X1603726Y198061D03*
X1596444Y215526D03*
X1598030Y251002D03*
X1606980Y1449922D03*
X1606237Y1575686D03*
Y1580678D03*
X1594177D03*
X1599133D03*
X1594177Y1575686D03*
X1599133D03*
X1599477Y1599884D03*
X1604433D03*
X1592373D03*
X1606237Y1587598D03*
Y1592590D03*
X1594177D03*
X1599133D03*
X1594177Y1587598D03*
X1599133D03*
X1599477Y1616788D03*
X1604433D03*
X1599477Y1604876D03*
Y1611796D03*
X1604433Y1604876D03*
Y1611796D03*
X1592373Y1604876D03*
Y1611796D03*
Y1616788D03*
X1620818Y69297D03*
X1622818Y66801D03*
Y71793D03*
X1609818Y75297D03*
X1618774D03*
X1616774Y77793D03*
Y72801D03*
X1611818Y77793D03*
Y72801D03*
X1623448Y1420028D03*
Y1417428D03*
Y1414828D03*
Y1412228D03*
X1612630Y1418842D03*
X1615597Y1433669D03*
X1618297Y1580678D03*
X1623253D03*
X1618297Y1575686D03*
X1623253D03*
X1611193D03*
Y1580678D03*
X1623597Y1599884D03*
X1611537D03*
X1616493D03*
X1618297Y1592590D03*
X1623253D03*
X1618297Y1587598D03*
X1623253D03*
X1611193D03*
Y1592590D03*
X1623597Y1616788D03*
Y1604876D03*
Y1611796D03*
X1611537Y1604876D03*
Y1611796D03*
X1616493Y1604876D03*
Y1611796D03*
X1611537Y1616788D03*
X1616493D03*
X1634021Y16999D03*
Y21991D03*
X1638977Y16999D03*
Y21991D03*
X1632021Y19495D03*
X1631872Y23935D03*
X1626916D03*
X1624916Y25931D03*
X1633872D03*
X1639089D03*
X1625814Y37106D03*
X1632901D03*
X1639988D03*
X1625814Y48720D03*
X1632901D03*
X1639988D03*
X1629774Y69297D03*
X1627774Y66801D03*
Y71793D03*
X1633022Y75297D03*
X1635022Y77793D03*
X1639978D03*
Y72801D03*
X1635022D03*
X1635032Y196188D03*
X1642135Y414202D03*
X1629262Y1394418D03*
X1625948Y1417428D03*
Y1412228D03*
X1633103Y1417907D03*
X1630503D03*
X1635703D03*
X1633103Y1421014D03*
X1630503D03*
X1635703D03*
X1638303Y1417907D03*
Y1421014D03*
X1625948Y1414828D03*
Y1420028D03*
X1635903Y1424121D03*
X1638503D03*
X1632516Y1427753D03*
Y1433353D03*
X1634986Y1427753D03*
Y1433353D03*
X1637416Y1427753D03*
Y1433353D03*
X1627591Y1447796D03*
X1637478Y1445150D03*
X1630357Y1575592D03*
X1635313D03*
X1630357Y1580678D03*
X1635313D03*
X1640613Y1599790D03*
X1635657D03*
X1628553Y1599884D03*
X1630357Y1587598D03*
X1635313D03*
X1630357Y1592590D03*
X1635313D03*
X1640613Y1604876D03*
Y1611796D03*
X1635657Y1604876D03*
Y1611796D03*
X1640613Y1616788D03*
X1635657D03*
X1628553D03*
Y1604876D03*
Y1611796D03*
X1648194Y16999D03*
Y21991D03*
X1653150Y16999D03*
Y21991D03*
X1640977Y19495D03*
X1646194D03*
X1655150D03*
X1641089Y23935D03*
X1646045D03*
X1648045Y25931D03*
X1654161Y37106D03*
X1647074D03*
Y48720D03*
X1654161D03*
X1644022Y69297D03*
X1652978D03*
X1646022Y66801D03*
Y71793D03*
X1650978Y66801D03*
Y71793D03*
X1655022Y75297D03*
X1641978D03*
X1657022Y77793D03*
Y72801D03*
X1652610Y394727D03*
X1652810Y407402D03*
X1647110Y434177D03*
X1651890Y520540D03*
X1649220Y620662D03*
X1656188Y1394736D03*
X1647592Y1394418D03*
X1655779Y1417618D03*
Y1412418D03*
Y1415018D03*
X1644103Y1417907D03*
X1647047Y1417923D03*
Y1421030D03*
X1653279Y1412418D03*
X1650679D03*
X1653279Y1415018D03*
X1650679D03*
X1653168Y1417618D03*
X1650557D03*
X1640903Y1417907D03*
X1647016Y1424153D03*
X1648947Y1476695D03*
X1647373Y1580678D03*
X1642417D03*
X1647373Y1575686D03*
X1642417D03*
X1647717Y1599884D03*
X1652673D03*
X1647373Y1592590D03*
X1642417D03*
X1647373Y1587598D03*
X1642417D03*
X1647717Y1616788D03*
X1652673D03*
X1647717Y1604876D03*
Y1611796D03*
X1652673Y1604876D03*
Y1611796D03*
X1671050Y23935D03*
X1669050Y25931D03*
X1669948Y37106D03*
Y48720D03*
X1666022Y69297D03*
X1668022Y66801D03*
Y71793D03*
X1672978Y66801D03*
Y71793D03*
X1663978Y75297D03*
X1661978Y77793D03*
Y72801D03*
X1668030Y200580D03*
X1666074Y229710D03*
X1660176Y231100D03*
X1670400Y229462D03*
X1659610Y394727D03*
X1663610D03*
X1661110Y434177D03*
X1660866Y546749D03*
X1664040Y569642D03*
X1668040D03*
X1672040D03*
X1662120Y604782D03*
X1657220Y620662D03*
X1667405Y1394418D03*
X1659260Y1394693D03*
X1658390Y1420218D03*
Y1415018D03*
Y1412418D03*
Y1417618D03*
X1663590Y1420218D03*
X1660990D03*
Y1415018D03*
Y1417618D03*
Y1412418D03*
X1663590Y1415018D03*
Y1417618D03*
Y1412418D03*
X1668646Y1417907D03*
Y1421014D03*
X1671246Y1417907D03*
Y1421014D03*
X1670659Y1427753D03*
X1673129D03*
X1670659Y1433353D03*
X1673129D03*
X1657438Y1438156D03*
X1660428Y1447566D03*
X1667577Y1447545D03*
X1666123Y1497362D03*
X1665940Y1512862D03*
X1666110Y1504662D03*
X1666123Y1524862D03*
Y1537862D03*
Y1541862D03*
Y1553557D03*
X1666198Y1565557D03*
Y1585321D03*
X1678155Y16999D03*
Y21991D03*
X1683111Y16999D03*
Y21991D03*
X1676155Y19495D03*
X1685111D03*
X1676006Y23935D03*
X1685223D03*
X1678006Y25931D03*
X1683223D03*
X1677035Y37106D03*
X1684122D03*
X1677035Y48720D03*
X1684122D03*
X1688156Y69297D03*
X1674978D03*
X1677156Y75297D03*
X1686112D03*
X1684112Y77793D03*
Y72801D03*
X1679156Y77793D03*
Y72801D03*
X1676300Y219762D03*
X1681900Y227962D03*
X1682810Y465940D03*
X1676040Y569627D03*
X1688301Y722158D03*
X1683121D03*
X1680401D03*
X1686135Y1394418D03*
X1687860Y1415179D03*
X1689210Y1417679D03*
X1687860Y1412579D03*
X1685190Y1417923D03*
X1676446Y1417907D03*
X1679046D03*
X1682246D03*
X1676446Y1421014D03*
X1685190Y1421030D03*
X1673846Y1417907D03*
Y1421014D03*
X1676646Y1424121D03*
X1685159Y1424153D03*
X1675559Y1427753D03*
Y1433353D03*
X1674046Y1424121D03*
X1675621Y1445150D03*
X1679508Y1503421D03*
Y1522921D03*
Y1543921D03*
Y1563380D03*
Y1583880D03*
X1692328Y16999D03*
Y21991D03*
X1697284Y16999D03*
Y21991D03*
X1690328Y19495D03*
X1699284D03*
X1690179Y23935D03*
X1692179Y25931D03*
X1691208Y37106D03*
X1698295D03*
X1705381D03*
X1698295Y48720D03*
X1691208D03*
X1705381D03*
X1697112Y69297D03*
X1690156Y66801D03*
Y71793D03*
X1695112Y66801D03*
Y71793D03*
X1699156Y75297D03*
X1701156Y77793D03*
Y72801D03*
X1695950Y96437D03*
X1697725Y205120D03*
X1700846Y455894D03*
X1702760Y478207D03*
X1696760D03*
X1702760Y490207D03*
X1696760D03*
Y484207D03*
X1696120Y506937D03*
X1703720Y509362D03*
X1696851Y515607D03*
X1693701D03*
X1702270Y552742D03*
X1698920Y698562D03*
X1695227Y722325D03*
X1699307Y722465D03*
X1698137Y718345D03*
X1701087Y719055D03*
X1695367Y719345D03*
X1691021Y722158D03*
X1698537Y766015D03*
X1690809Y1393970D03*
X1699150Y1393613D03*
X1690460Y1415179D03*
Y1412579D03*
X1691918Y1417676D03*
X1692960Y1415179D03*
Y1412579D03*
X1693404Y1421939D03*
X1699593Y1428384D03*
X1697820Y1423616D03*
X1699545Y1425868D03*
X1699437Y1431295D03*
X1699457Y1439185D03*
Y1447805D03*
X1691988Y1498303D03*
Y1517803D03*
Y1538803D03*
Y1558262D03*
X1714520Y37162D03*
X1710920Y82162D03*
X1708112Y75297D03*
X1706112Y77793D03*
Y72801D03*
X1708000Y99122D03*
X1714180Y154790D03*
X1721400Y374462D03*
X1711477Y465229D03*
Y468379D03*
X1708760Y478031D03*
Y490207D03*
Y484207D03*
X1710500Y538162D03*
X1706720Y703762D03*
X1709107Y728449D03*
X1718149Y1496270D03*
X1717149Y1505895D03*
X1720174D03*
X1717988Y1520951D03*
X1711988D03*
X1717149Y1513945D03*
X1720174D03*
X1714988Y1520951D03*
X1708988D03*
X1717988Y1530445D03*
X1714988D03*
X1708988D03*
X1711988D03*
X1727768Y3010D03*
X1732320Y28162D03*
X1728820D03*
X1725320D03*
X1729520Y61762D03*
X1729620Y57262D03*
X1730820Y76362D03*
X1726918Y101967D03*
X1733378Y134907D03*
X1736508D03*
X1723240Y185200D03*
X1737704Y183139D03*
X1737260Y368132D03*
X1732660Y372692D03*
X1725400Y372062D03*
X1725500Y383662D03*
X1737434Y398990D03*
X1727760Y420415D03*
X1747768Y3010D03*
X1754090Y16302D03*
X1748400Y37262D03*
X1753398Y48720D03*
X1745485Y119539D03*
X1747482Y121367D03*
X1741222Y151527D03*
X1747591Y171733D03*
X1751084Y190928D03*
X1745000Y299862D03*
X1746970Y1451872D03*
X1750970Y1459172D03*
Y1456172D03*
X1767768Y3010D03*
X1769900Y37732D03*
X1760485Y48720D03*
X1759700Y57662D03*
X1764400Y57462D03*
X1758063Y68637D03*
X1758573Y87107D03*
Y83607D03*
X1768168Y80497D03*
X1758568Y79697D03*
X1765068Y80397D03*
X1766278Y93627D03*
X1768483Y166260D03*
X1763731Y283817D03*
X1766725Y282981D03*
X1763731Y279517D03*
X1760398Y279548D03*
X1766765Y279433D03*
X1757439Y279611D03*
X1760398Y283848D03*
X1759509Y292434D03*
X1762549Y286704D03*
X1757439Y283911D03*
X1768045Y295238D03*
X1765053Y295188D03*
X1762285Y295137D03*
X1759629Y295164D03*
X1767309Y290994D03*
X1763045Y289691D03*
X1759529Y289864D03*
X1766655Y286531D03*
X1767455Y302651D03*
X1758563Y310478D03*
X1754963D03*
X1770520Y364148D03*
Y368148D03*
X1767300Y461393D03*
X1765670Y458012D03*
X1767300Y465893D03*
X1764112Y703948D03*
X1761612D03*
X1764112Y695648D03*
X1763570Y693192D03*
X1761612Y695648D03*
X1764072Y720508D03*
X1761572D03*
X1764112Y712248D03*
X1761612D03*
X1760160Y1476032D03*
X1763730Y1483712D03*
Y1480712D03*
X1763830Y1490782D03*
Y1487782D03*
X1785178Y86927D03*
Y89927D03*
X1784238Y150744D03*
X1786690Y234782D03*
Y231782D03*
X1771029Y295164D03*
X1771229Y291064D03*
X1772863Y310478D03*
X1782420Y443987D03*
X1773870Y438222D03*
X1776160Y592792D03*
X1787768Y3010D03*
X1794910Y44573D03*
X1797324Y161465D03*
X1803129Y362293D03*
X1802929Y385293D03*
X1795479Y408056D03*
X1795468Y421334D03*
X1800107Y1256426D03*
X1795484Y1496401D03*
X1792645Y1511423D03*
X1798450Y1524830D03*
X1801450D03*
Y1527830D03*
X1814322Y49388D03*
X1807549Y56415D03*
X1807580Y59397D03*
X1810835Y163986D03*
X1806365Y154032D03*
X1819939Y177243D03*
X1820307Y373829D03*
X1820144Y398052D03*
X1819374Y410432D03*
X1818874Y423932D03*
X1818816Y468872D03*
X1803517Y1495567D03*
X1818410Y1525815D03*
X1812250Y1521830D03*
X1811250Y1524830D03*
Y1527830D03*
X1807850D03*
X1804650D03*
Y1524830D03*
X1807850D03*
X1814370Y1528900D03*
X1814210Y1525815D03*
X1818524Y1528991D03*
X1834322Y49388D03*
X1823508Y158868D03*
X1829026Y367701D03*
X1823426Y1507916D03*
X1831994Y1525977D03*
X1835334Y1520921D03*
X1828510Y1525915D03*
X1821710D03*
X1830466Y1606658D03*
X1838910Y185772D03*
X1843134Y244362D03*
X1836750Y373632D03*
X1838020Y459121D03*
X1854096Y52383D03*
G54D43*
X335349Y985939D03*
X549278Y949619D03*
X1300207Y177799D03*
X1311491Y985939D03*
X1355761Y177798D03*
X1525420Y949619D03*
X1879155Y592848D03*
Y840748D03*
X1889155Y592848D03*
Y840748D03*
X1900275Y964708D03*
X1910275D03*
X1931395Y592868D03*
X1921395D03*
X1952395Y1205248D03*
X1942395D03*
X1963362Y593010D03*
X1973362D03*
X1984482Y1205220D03*
X1994482D03*
X2015452Y593020D03*
X2005452D03*
X2026452Y1205400D03*
X2047419Y593162D03*
X2036452Y1205400D03*
X2057419Y593162D03*
X2078539Y1205372D03*
X2068539D03*
G54D57*
X828780Y1694890D03*
Y1684890D03*
X818780Y1694890D03*
Y1684890D03*
X828780Y1704890D03*
X818780D03*
X828780Y1714890D03*
X818780D03*
X853780Y1694890D03*
Y1684890D03*
Y1704890D03*
Y1714890D03*
X863780Y1694890D03*
Y1684890D03*
Y1704890D03*
Y1714890D03*
X888780Y1684890D03*
Y1694890D03*
Y1704890D03*
Y1714890D03*
X898780Y1684890D03*
Y1694890D03*
Y1704890D03*
Y1714890D03*
X918780Y1704890D03*
X958780Y1694890D03*
Y1684890D03*
Y1704890D03*
Y1714890D03*
X968780Y1694890D03*
Y1684890D03*
Y1704890D03*
Y1714890D03*
X993780Y1684890D03*
Y1694890D03*
X1003780Y1684890D03*
Y1694890D03*
X993780Y1704890D03*
Y1714890D03*
X1003780Y1704890D03*
Y1714890D03*
X1028780Y1684890D03*
Y1694890D03*
X1038780Y1684890D03*
Y1694890D03*
X1028780Y1704890D03*
Y1714890D03*
X1038780Y1704890D03*
Y1714890D03*
G54D16*
X27699Y770144D03*
Y783530D03*
Y776837D03*
Y800263D03*
Y793570D03*
Y820341D03*
Y813648D03*
Y806955D03*
Y830381D03*
Y850459D03*
Y843766D03*
Y837074D03*
Y867192D03*
Y857152D03*
Y880577D03*
Y873885D03*
Y893963D03*
Y887270D03*
Y917389D03*
Y910696D03*
Y904003D03*
Y930774D03*
Y924081D03*
Y947507D03*
Y940814D03*
Y964239D03*
Y954200D03*
Y977625D03*
Y970932D03*
Y991011D03*
Y984318D03*
Y1031168D03*
Y1024475D03*
Y1017782D03*
Y1044554D03*
Y1037861D03*
Y1057940D03*
Y1051247D03*
Y1078018D03*
Y1071326D03*
Y1064633D03*
Y1094751D03*
Y1088058D03*
Y1108137D03*
Y1101444D03*
Y1124869D03*
Y1114829D03*
Y1144948D03*
Y1138255D03*
Y1131562D03*
Y1161680D03*
Y1151641D03*
Y1175066D03*
Y1168373D03*
Y1188452D03*
Y1181759D03*
Y1205184D03*
Y1198491D03*
Y1225263D03*
Y1218570D03*
Y1211877D03*
Y1241995D03*
Y1235302D03*
Y1248688D03*
X43841Y766798D03*
X36399Y770144D03*
X43841Y780184D03*
Y773491D03*
X36399Y783530D03*
Y776837D03*
X43841Y803609D03*
Y796916D03*
Y790223D03*
X36399Y800263D03*
Y793570D03*
X43841Y816995D03*
Y810302D03*
X36399Y820341D03*
Y813648D03*
Y806955D03*
X43841Y833727D03*
Y827034D03*
X36399Y830381D03*
X43841Y847113D03*
Y840420D03*
X36399Y850459D03*
Y843766D03*
Y837074D03*
X43841Y863845D03*
Y853806D03*
X36399Y867192D03*
Y857152D03*
X43841Y883924D03*
Y877231D03*
Y870538D03*
X36399Y880577D03*
Y873885D03*
X43841Y900656D03*
Y890617D03*
X36399Y893963D03*
Y887270D03*
X43841Y914042D03*
Y907349D03*
X36399Y917389D03*
Y910696D03*
Y904003D03*
X43841Y927428D03*
Y920735D03*
X36399Y930774D03*
Y924081D03*
X43841Y944160D03*
Y937467D03*
X36399Y947507D03*
Y940814D03*
X43841Y960892D03*
Y950853D03*
X36399Y964239D03*
Y954200D03*
X43841Y980971D03*
Y974278D03*
Y967585D03*
X36399Y977625D03*
Y970932D03*
X43841Y987664D03*
X36399Y991011D03*
Y984318D03*
X43841Y1027822D03*
Y1017782D03*
X36399Y1031168D03*
Y1024475D03*
Y1017782D03*
X43841Y1047900D03*
Y1041207D03*
Y1034515D03*
X36399Y1044554D03*
Y1037861D03*
X43841Y1061286D03*
Y1054593D03*
X36399Y1057940D03*
Y1051247D03*
X43841Y1074672D03*
Y1067979D03*
X36399Y1078018D03*
Y1071326D03*
Y1064633D03*
X43841Y1091404D03*
Y1084711D03*
X36399Y1094751D03*
Y1088058D03*
X43841Y1111483D03*
Y1104790D03*
Y1098097D03*
X36399Y1108137D03*
Y1101444D03*
X43841Y1128215D03*
Y1121522D03*
X36399Y1124869D03*
Y1114829D03*
X43841Y1141601D03*
Y1134908D03*
X36399Y1144948D03*
Y1138255D03*
Y1131562D03*
X43841Y1158333D03*
Y1148294D03*
X36399Y1161680D03*
Y1151641D03*
X43841Y1171719D03*
Y1165026D03*
X36399Y1175066D03*
Y1168373D03*
X43841Y1185105D03*
Y1178412D03*
X36399Y1188452D03*
Y1181759D03*
X43841Y1208530D03*
Y1201837D03*
Y1195144D03*
X36399Y1205184D03*
Y1198491D03*
X43841Y1221916D03*
Y1215223D03*
X36399Y1225263D03*
Y1218570D03*
Y1211877D03*
X43841Y1238648D03*
Y1231955D03*
X36399Y1241995D03*
Y1235302D03*
X43841Y1245341D03*
X36399Y1248688D03*
X36449Y1257262D03*
X33546Y1273364D03*
X30746D03*
X57399Y770144D03*
X52541Y766798D03*
X57399Y783530D03*
Y776837D03*
X52541Y780184D03*
Y773491D03*
X57399Y800263D03*
Y793570D03*
X52541Y803609D03*
Y796916D03*
Y790223D03*
X57399Y820341D03*
Y813648D03*
Y806955D03*
X52541Y816995D03*
Y810302D03*
X57399Y830381D03*
X52541Y833727D03*
Y827034D03*
X57399Y850459D03*
Y843766D03*
Y837074D03*
X52541Y847113D03*
Y840420D03*
X57399Y867192D03*
Y857152D03*
X52541Y863845D03*
Y853806D03*
X57399Y880577D03*
Y873885D03*
X52541Y883924D03*
Y877231D03*
Y870538D03*
X57399Y893963D03*
Y887270D03*
X52541Y900656D03*
Y890617D03*
X57399Y917389D03*
Y910696D03*
Y904003D03*
X52541Y914042D03*
Y907349D03*
X57399Y930774D03*
Y924081D03*
X52541Y927428D03*
Y920735D03*
X57399Y947507D03*
Y940814D03*
X52541Y944160D03*
Y937467D03*
X57399Y964239D03*
Y954200D03*
X52541Y960892D03*
Y950853D03*
X57399Y977625D03*
Y970932D03*
X52541Y980971D03*
Y974278D03*
Y967585D03*
X57399Y991011D03*
Y984318D03*
X52541Y987664D03*
X57399Y1031168D03*
Y1024475D03*
Y1017782D03*
X52541Y1027822D03*
Y1017782D03*
X57399Y1044554D03*
Y1037861D03*
X52541Y1047900D03*
Y1041207D03*
Y1034515D03*
X57399Y1057940D03*
Y1051247D03*
X52541Y1061286D03*
Y1054593D03*
X57399Y1078018D03*
Y1071326D03*
Y1064633D03*
X52541Y1074672D03*
Y1067979D03*
X57399Y1094751D03*
Y1088058D03*
X52541Y1091404D03*
Y1084711D03*
X57399Y1108137D03*
Y1101444D03*
X52541Y1111483D03*
Y1104790D03*
Y1098097D03*
X57399Y1124869D03*
Y1114829D03*
X52541Y1128215D03*
Y1121522D03*
X57399Y1144948D03*
Y1138255D03*
Y1131562D03*
X52541Y1141601D03*
Y1134908D03*
X57399Y1161680D03*
Y1151641D03*
X52541Y1158333D03*
Y1148294D03*
X57399Y1175066D03*
Y1168373D03*
X52541Y1171719D03*
Y1165026D03*
X57399Y1188452D03*
Y1181759D03*
X52541Y1185105D03*
Y1178412D03*
X57399Y1205184D03*
Y1198491D03*
X52541Y1208530D03*
Y1201837D03*
Y1195144D03*
X57399Y1225263D03*
Y1218570D03*
Y1211877D03*
X52541Y1221916D03*
Y1215223D03*
X57399Y1241995D03*
Y1235302D03*
X52541Y1238648D03*
Y1231955D03*
Y1248688D03*
X57399D03*
X52541Y1245341D03*
X60446Y1273364D03*
X49546D03*
X46746D03*
X73541Y766798D03*
X66099Y770144D03*
X73541Y780184D03*
Y773491D03*
X66099Y783530D03*
Y776837D03*
X73541Y803609D03*
Y796916D03*
Y790223D03*
X66099Y800263D03*
Y793570D03*
X73541Y816995D03*
Y810302D03*
X66099Y820341D03*
Y813648D03*
Y806955D03*
X73541Y833727D03*
Y827034D03*
X66099Y830381D03*
X73541Y847113D03*
Y840420D03*
X66099Y850459D03*
Y843766D03*
Y837074D03*
X73541Y863845D03*
Y853806D03*
X66099Y867192D03*
Y857152D03*
X73541Y883924D03*
Y877231D03*
Y870538D03*
X66099Y880577D03*
Y873885D03*
X73541Y900656D03*
Y890617D03*
X66099Y893963D03*
Y887270D03*
X73541Y914042D03*
Y907349D03*
X66099Y917389D03*
Y910696D03*
Y904003D03*
X73541Y927428D03*
Y920735D03*
X66099Y930774D03*
Y924081D03*
X73541Y944160D03*
Y937467D03*
X66099Y947507D03*
Y940814D03*
X73541Y960892D03*
Y950853D03*
X66099Y964239D03*
Y954200D03*
X73541Y980971D03*
Y974278D03*
Y967585D03*
X66099Y977625D03*
Y970932D03*
X73541Y987664D03*
X66099Y991011D03*
Y984318D03*
X73541Y1027822D03*
Y1017782D03*
X66099Y1031168D03*
Y1024475D03*
Y1017782D03*
X73541Y1047900D03*
Y1041207D03*
Y1034515D03*
X66099Y1044554D03*
Y1037861D03*
X73541Y1061286D03*
Y1054593D03*
X66099Y1057940D03*
Y1051247D03*
X73541Y1074672D03*
Y1067979D03*
X66099Y1078018D03*
Y1071326D03*
Y1064633D03*
X73541Y1091404D03*
Y1084711D03*
X66099Y1094751D03*
Y1088058D03*
X73541Y1111483D03*
Y1104790D03*
Y1098097D03*
X66099Y1108137D03*
Y1101444D03*
X73541Y1128215D03*
Y1121522D03*
X66099Y1124869D03*
Y1114829D03*
X73541Y1141601D03*
Y1134908D03*
X66099Y1144948D03*
Y1138255D03*
Y1131562D03*
X73541Y1158333D03*
Y1148294D03*
X66099Y1161680D03*
Y1151641D03*
X73541Y1171719D03*
Y1165026D03*
X66099Y1175066D03*
Y1168373D03*
X73541Y1185105D03*
Y1178412D03*
X66099Y1188452D03*
Y1181759D03*
X73541Y1208530D03*
Y1201837D03*
Y1195144D03*
X66099Y1205184D03*
Y1198491D03*
X73541Y1221916D03*
Y1215223D03*
X66099Y1225263D03*
Y1218570D03*
Y1211877D03*
X73541Y1238648D03*
Y1231955D03*
X66099Y1241995D03*
Y1235302D03*
X66189Y1257488D03*
X73541Y1245341D03*
X66099Y1248688D03*
X76446Y1273364D03*
X63246D03*
X87099Y770144D03*
X82241Y766798D03*
X87099Y783530D03*
Y776837D03*
X82241Y780184D03*
Y773491D03*
X87099Y800263D03*
Y793570D03*
X82241Y803609D03*
Y796916D03*
Y790223D03*
X87099Y820341D03*
Y813648D03*
Y806955D03*
X82241Y816995D03*
Y810302D03*
X87099Y830381D03*
X82241Y833727D03*
Y827034D03*
X87099Y850459D03*
Y843766D03*
Y837074D03*
X82241Y847113D03*
Y840420D03*
X87099Y867192D03*
Y857152D03*
X82241Y863845D03*
Y853806D03*
X87099Y880577D03*
Y873885D03*
X82241Y883924D03*
Y877231D03*
Y870538D03*
X87099Y893963D03*
Y887270D03*
X82241Y900656D03*
Y890617D03*
X87099Y917389D03*
Y910696D03*
Y904003D03*
X82241Y914042D03*
Y907349D03*
X87099Y930774D03*
Y924081D03*
X82241Y927428D03*
Y920735D03*
X87099Y947507D03*
Y940814D03*
X82241Y944160D03*
Y937467D03*
X87099Y964239D03*
Y954200D03*
X82241Y960892D03*
Y950853D03*
X87099Y977625D03*
Y970932D03*
X82241Y980971D03*
Y974278D03*
Y967585D03*
X87099Y991011D03*
Y984318D03*
X82241Y987664D03*
X87099Y1031168D03*
Y1024475D03*
Y1017782D03*
X82241Y1027822D03*
Y1017782D03*
X87099Y1044554D03*
Y1037861D03*
X82241Y1047900D03*
Y1041207D03*
Y1034515D03*
X87099Y1057940D03*
Y1051247D03*
X82241Y1061286D03*
Y1054593D03*
X87099Y1078018D03*
Y1071326D03*
Y1064633D03*
X82241Y1074672D03*
Y1067979D03*
X87099Y1094751D03*
Y1088058D03*
X82241Y1091404D03*
Y1084711D03*
X87099Y1108137D03*
Y1101444D03*
X82241Y1111483D03*
Y1104790D03*
Y1098097D03*
X87099Y1124869D03*
Y1114829D03*
X82241Y1128215D03*
Y1121522D03*
X87099Y1144948D03*
Y1138255D03*
Y1131562D03*
X82241Y1141601D03*
Y1134908D03*
X87099Y1161680D03*
Y1151641D03*
X82241Y1158333D03*
Y1148294D03*
X87099Y1175066D03*
Y1168373D03*
X82241Y1171719D03*
Y1165026D03*
X87099Y1188452D03*
Y1181759D03*
X82241Y1185105D03*
Y1178412D03*
X87099Y1205184D03*
Y1198491D03*
X82241Y1208530D03*
Y1201837D03*
Y1195144D03*
X87099Y1225263D03*
Y1218570D03*
Y1211877D03*
X82241Y1221916D03*
Y1215223D03*
X87099Y1241995D03*
Y1235302D03*
X82241Y1238648D03*
Y1231955D03*
X87099Y1248688D03*
X82241Y1245341D03*
X92946Y1273364D03*
X90146D03*
X79246D03*
X103241Y766798D03*
X95799Y770144D03*
X103241Y780184D03*
Y773491D03*
X95799Y783530D03*
Y776837D03*
X103241Y803609D03*
Y796916D03*
Y790223D03*
X95799Y800263D03*
Y793570D03*
X103241Y816995D03*
Y810302D03*
X95799Y820341D03*
Y813648D03*
Y806955D03*
X103241Y833727D03*
Y827034D03*
X95799Y830381D03*
X103241Y847113D03*
Y840420D03*
X95799Y850459D03*
Y843766D03*
Y837074D03*
X103241Y863845D03*
Y853806D03*
X95799Y867192D03*
Y857152D03*
X103241Y883924D03*
Y877231D03*
Y870538D03*
X95799Y880577D03*
Y873885D03*
X103241Y900656D03*
Y890617D03*
X95799Y893963D03*
Y887270D03*
X103241Y914042D03*
Y907349D03*
X95799Y917389D03*
Y910696D03*
Y904003D03*
X103241Y927428D03*
Y920735D03*
X95799Y930774D03*
Y924081D03*
X103241Y944160D03*
Y937467D03*
X95799Y947507D03*
Y940814D03*
X103241Y960892D03*
Y950853D03*
X95799Y964239D03*
Y954200D03*
X103241Y980971D03*
Y974278D03*
Y967585D03*
X95799Y977625D03*
Y970932D03*
X103241Y987664D03*
X95799Y991011D03*
Y984318D03*
X103241Y1027822D03*
Y1017782D03*
X95799Y1031168D03*
Y1024475D03*
Y1017782D03*
X103241Y1047900D03*
Y1041207D03*
Y1034515D03*
X95799Y1044554D03*
Y1037861D03*
X103241Y1061286D03*
Y1054593D03*
X95799Y1057940D03*
Y1051247D03*
X103241Y1074672D03*
Y1067979D03*
X95799Y1078018D03*
Y1071326D03*
Y1064633D03*
X103241Y1091404D03*
Y1084711D03*
X95799Y1094751D03*
Y1088058D03*
X103241Y1111483D03*
Y1104790D03*
Y1098097D03*
X95799Y1108137D03*
Y1101444D03*
X103241Y1128215D03*
Y1121522D03*
X95799Y1124869D03*
Y1114829D03*
X103241Y1141601D03*
Y1134908D03*
X95799Y1144948D03*
Y1138255D03*
Y1131562D03*
X103241Y1158333D03*
Y1148294D03*
X95799Y1161680D03*
Y1151641D03*
X103241Y1171719D03*
Y1165026D03*
X95799Y1175066D03*
Y1168373D03*
X103241Y1185105D03*
Y1178412D03*
X95799Y1188452D03*
Y1181759D03*
X103241Y1208530D03*
Y1201837D03*
Y1195144D03*
X95799Y1205184D03*
Y1198491D03*
X103241Y1221916D03*
Y1215223D03*
X95799Y1225263D03*
Y1218570D03*
Y1211877D03*
X103241Y1238648D03*
Y1231955D03*
X95799Y1241995D03*
Y1235302D03*
X95849Y1257262D03*
X103241Y1245341D03*
X95799Y1248688D03*
X108946Y1273364D03*
X106146D03*
X125499Y770144D03*
X116799D03*
X111941Y766798D03*
X125499Y783530D03*
X116799D03*
X125499Y776837D03*
X116799D03*
X111941Y780184D03*
Y773491D03*
X125499Y800263D03*
X116799D03*
X125499Y793570D03*
X116799D03*
X111941Y803609D03*
Y796916D03*
Y790223D03*
X125499Y820341D03*
X116799D03*
X125499Y813648D03*
X116799D03*
X125499Y806955D03*
X116799D03*
X111941Y816995D03*
Y810302D03*
X125499Y830381D03*
X116799D03*
X111941Y833727D03*
Y827034D03*
X125499Y850459D03*
X116799D03*
X125499Y843766D03*
X116799D03*
X125499Y837074D03*
X116799D03*
X111941Y847113D03*
Y840420D03*
X125499Y867192D03*
X116799D03*
X125499Y857152D03*
X116799D03*
X111941Y863845D03*
Y853806D03*
X125499Y880577D03*
X116799D03*
X125499Y873885D03*
X116799D03*
X111941Y883924D03*
Y877231D03*
Y870538D03*
X125499Y893963D03*
X116799D03*
X125499Y887270D03*
X116799D03*
X111941Y900656D03*
Y890617D03*
X125499Y917389D03*
X116799D03*
X125499Y910696D03*
X116799D03*
X125499Y904003D03*
X116799D03*
X111941Y914042D03*
Y907349D03*
X125499Y930774D03*
X116799D03*
X125499Y924081D03*
X116799D03*
X111941Y927428D03*
Y920735D03*
X125499Y947507D03*
X116799D03*
X125499Y940814D03*
X116799D03*
X111941Y944160D03*
Y937467D03*
X125499Y964239D03*
X116799D03*
X125499Y954200D03*
X116799D03*
X111941Y960892D03*
Y950853D03*
X125499Y977625D03*
X116799D03*
X125499Y970932D03*
X116799D03*
X111941Y980971D03*
Y974278D03*
Y967585D03*
X125499Y991011D03*
X116799D03*
X125499Y984318D03*
X116799D03*
X111941Y987664D03*
X125499Y1031168D03*
X116799D03*
X125499Y1024475D03*
X116799D03*
X125499Y1017782D03*
X116799D03*
X111941Y1027822D03*
Y1017782D03*
X125499Y1044554D03*
X116799D03*
X125499Y1037861D03*
X116799D03*
X111941Y1047900D03*
Y1041207D03*
Y1034515D03*
X125499Y1057940D03*
X116799D03*
X125499Y1051247D03*
X116799D03*
X111941Y1061286D03*
Y1054593D03*
X125499Y1078018D03*
X116799D03*
X125499Y1071326D03*
X116799D03*
X125499Y1064633D03*
X116799D03*
X111941Y1074672D03*
Y1067979D03*
X125499Y1094751D03*
X116799D03*
X125499Y1088058D03*
X116799D03*
X111941Y1091404D03*
Y1084711D03*
X125499Y1108137D03*
X116799D03*
X125499Y1101444D03*
X116799D03*
X111941Y1111483D03*
Y1104790D03*
Y1098097D03*
X125499Y1124869D03*
X116799D03*
X125499Y1114829D03*
X116799D03*
X111941Y1128215D03*
Y1121522D03*
X125499Y1144948D03*
X116799D03*
X125499Y1138255D03*
X116799D03*
X125499Y1131562D03*
X116799D03*
X111941Y1141601D03*
Y1134908D03*
X125499Y1161680D03*
X116799D03*
X125499Y1151641D03*
X116799D03*
X111941Y1158333D03*
Y1148294D03*
X125499Y1175066D03*
X116799D03*
X125499Y1168373D03*
X116799D03*
X111941Y1171719D03*
Y1165026D03*
X125499Y1188452D03*
X116799D03*
X125499Y1181759D03*
X116799D03*
X111941Y1185105D03*
Y1178412D03*
X125499Y1205184D03*
X116799D03*
X125499Y1198491D03*
X116799D03*
X111941Y1208530D03*
Y1201837D03*
Y1195144D03*
X125499Y1225263D03*
X116799D03*
X125499Y1218570D03*
X116799D03*
X125499Y1211877D03*
X116799D03*
X111941Y1221916D03*
Y1215223D03*
X125499Y1241995D03*
X116799D03*
X125499Y1235302D03*
X116799D03*
X111941Y1238648D03*
Y1231955D03*
X125412Y1257102D03*
X125499Y1248688D03*
X116799D03*
X111941Y1245341D03*
X119846Y1273364D03*
X122646D03*
X141641Y766798D03*
X132941D03*
X141641Y773491D03*
X132941D03*
X141641Y780184D03*
X132941D03*
X141641Y803609D03*
X132941D03*
X141641Y790223D03*
X132941D03*
X141641Y796916D03*
X132941D03*
X141641Y816995D03*
X132941D03*
X141641Y810302D03*
X132941D03*
X141641Y833727D03*
X132941D03*
X141641Y827034D03*
X132941D03*
X141641Y840420D03*
X132941D03*
X141641Y847113D03*
X132941D03*
Y863845D03*
X141641D03*
Y853806D03*
X132941D03*
Y883924D03*
X141641D03*
X132941Y870538D03*
X141641D03*
X132941Y877231D03*
X141641D03*
X132941Y900656D03*
X141641D03*
X132941Y890617D03*
X141641D03*
X132941Y907349D03*
X141641D03*
X132941Y914042D03*
X141641D03*
X132941Y920735D03*
X141641D03*
X132941Y927428D03*
X141641D03*
X132941Y937467D03*
X141641D03*
X132941Y944160D03*
X141641D03*
X132941Y960892D03*
X141641D03*
X132941Y950853D03*
X141641D03*
X132941Y980971D03*
X141641D03*
X132941Y974278D03*
X141641D03*
X132941Y967585D03*
X141641D03*
X132941Y987664D03*
X141641D03*
X132941Y1027822D03*
X141641D03*
X132941Y1017782D03*
X141641D03*
X132941Y1047900D03*
X141641D03*
X132941Y1041207D03*
X141641D03*
X132941Y1034515D03*
X141641D03*
Y1061286D03*
X132941D03*
X141641Y1054593D03*
X132941D03*
X141641Y1074672D03*
X132941D03*
X141641Y1067979D03*
X132941D03*
X141641Y1091404D03*
X132941D03*
X141641Y1084711D03*
X132941D03*
X141641Y1111483D03*
X132941D03*
X141641Y1104790D03*
X132941D03*
X141641Y1098097D03*
X132941D03*
X141641Y1128215D03*
X132941D03*
X141641Y1121522D03*
X132941D03*
X141641Y1141601D03*
X132941D03*
X141641Y1134908D03*
X132941D03*
X141641Y1158333D03*
X132941D03*
X141641Y1148294D03*
X132941D03*
X141641Y1171719D03*
X132941D03*
X141641Y1165026D03*
X132941D03*
X141641Y1185105D03*
X132941D03*
X141641Y1178412D03*
X132941D03*
X141641Y1208530D03*
X132941D03*
X141641Y1201837D03*
X132941D03*
X141641Y1195144D03*
X132941D03*
Y1221916D03*
X141641D03*
X132941Y1215223D03*
X141641D03*
X132941Y1238648D03*
X141641D03*
X132941Y1231955D03*
X141641D03*
X132941Y1245341D03*
X141641D03*
X135846Y1273364D03*
X138646D03*
X146499Y770144D03*
X155199D03*
X146499Y783530D03*
X155199D03*
X146499Y776837D03*
X155199D03*
X146499Y800263D03*
X155199D03*
X146499Y793570D03*
X155199D03*
X146499Y820341D03*
X155199D03*
X146499Y813648D03*
X155199D03*
X146499Y806955D03*
X155199D03*
X146499Y830381D03*
X155199D03*
X146499Y850459D03*
X155199D03*
X146499Y843766D03*
X155199D03*
X146499Y837074D03*
X155199D03*
Y867192D03*
X146499D03*
Y857152D03*
X155199D03*
Y880577D03*
X146499D03*
X155199Y873885D03*
X146499D03*
X155199Y893963D03*
X146499D03*
X155199Y887270D03*
X146499D03*
X155199Y917389D03*
X146499D03*
X155199Y910696D03*
X146499D03*
X155199Y904003D03*
X146499D03*
X155199Y930774D03*
X146499D03*
X155199Y924081D03*
X146499D03*
X155199Y947507D03*
X146499D03*
X155199Y940814D03*
X146499D03*
X155199Y964239D03*
X146499D03*
X155199Y954200D03*
X146499D03*
X155199Y977625D03*
X146499D03*
X155199Y970932D03*
X146499D03*
X155199Y991011D03*
X146499D03*
X155199Y984318D03*
X146499D03*
X155199Y1031168D03*
X146499D03*
X155199Y1024475D03*
X146499D03*
X155199Y1017782D03*
X146499D03*
X155199Y1044554D03*
X146499D03*
X155199Y1037861D03*
X146499D03*
X155199Y1057940D03*
X146499D03*
X155199Y1051247D03*
X146499D03*
X155199Y1078018D03*
X146499D03*
X155199Y1071326D03*
X146499D03*
X155199Y1064633D03*
X146499D03*
X155199Y1094751D03*
X146499D03*
X155199Y1088058D03*
X146499D03*
X155199Y1108137D03*
X146499D03*
X155199Y1101444D03*
X146499D03*
X155199Y1124869D03*
X146499D03*
X155199Y1114829D03*
X146499D03*
X155199Y1144948D03*
X146499D03*
X155199Y1138255D03*
X146499D03*
X155199Y1131562D03*
X146499D03*
X155199Y1161680D03*
X146499D03*
X155199Y1151641D03*
X146499D03*
X155199Y1175066D03*
X146499D03*
X155199Y1168373D03*
X146499D03*
X155199Y1188452D03*
X146499D03*
X155199Y1181759D03*
X146499D03*
X155199Y1205184D03*
X146499D03*
X155199Y1198491D03*
X146499D03*
X155199Y1225263D03*
X146499D03*
X155199Y1218570D03*
X146499D03*
X155199Y1211877D03*
X146499D03*
X155199Y1241995D03*
X146499D03*
X155199Y1235302D03*
X146499D03*
X155135Y1257134D03*
X155199Y1248688D03*
X146499D03*
X149546Y1273364D03*
X152346D03*
X176199Y770144D03*
X162641Y766798D03*
X171341D03*
X176199Y783530D03*
Y776837D03*
X162641Y780184D03*
X171341D03*
Y773491D03*
X162641D03*
X176199Y800263D03*
X162641Y803609D03*
X171341D03*
X176199Y793570D03*
X162641Y796916D03*
X171341D03*
X162641Y790223D03*
X171341D03*
X176199Y820341D03*
X162641Y816995D03*
X171341D03*
X176199Y813648D03*
Y806955D03*
X162641Y810302D03*
X171341D03*
X162641Y833727D03*
X171341D03*
X176199Y830381D03*
X162641Y827034D03*
X171341D03*
X176199Y850459D03*
Y843766D03*
Y837074D03*
X162641Y847113D03*
X171341D03*
X162641Y840420D03*
X171341D03*
X176199Y867192D03*
X171341Y863845D03*
X162641D03*
X176199Y857152D03*
X162641Y853806D03*
X171341D03*
Y883924D03*
X162641D03*
X176199Y880577D03*
Y873885D03*
X171341Y877231D03*
X162641D03*
X171341Y870538D03*
X162641D03*
X171341Y900656D03*
X162641D03*
X176199Y893963D03*
Y887270D03*
X171341Y890617D03*
X162641D03*
X176199Y917389D03*
Y910696D03*
Y904003D03*
X171341Y914042D03*
X162641D03*
X171341Y907349D03*
X162641D03*
X176199Y930774D03*
Y924081D03*
X171341Y927428D03*
X162641D03*
X171341Y920735D03*
X162641D03*
X176199Y947507D03*
Y940814D03*
X171341Y944160D03*
X162641D03*
X171341Y937467D03*
X162641D03*
X176199Y964239D03*
Y954200D03*
X171341Y960892D03*
X162641D03*
X171341Y950853D03*
X162641D03*
X171341Y980971D03*
X162641D03*
X176199Y977625D03*
Y970932D03*
X171341Y974278D03*
X162641D03*
X171341Y967585D03*
X162641D03*
X176199Y991011D03*
Y984318D03*
X171341Y987664D03*
X162641D03*
X176199Y1031168D03*
Y1024475D03*
Y1017782D03*
X171341Y1027822D03*
X162641D03*
X171341Y1017782D03*
X162641D03*
X171341Y1047900D03*
X162641D03*
X176199Y1044554D03*
Y1037861D03*
X171341Y1041207D03*
X162641D03*
X171341Y1034515D03*
X162641D03*
X176199Y1057940D03*
Y1051247D03*
X171341Y1061286D03*
X162641D03*
X171341Y1054593D03*
X162641D03*
X176199Y1078018D03*
Y1071326D03*
Y1064633D03*
X171341Y1074672D03*
X162641D03*
X171341Y1067979D03*
X162641D03*
X176199Y1094751D03*
Y1088058D03*
X171341Y1091404D03*
X162641D03*
X171341Y1084711D03*
X162641D03*
X171341Y1111483D03*
X162641D03*
X176199Y1108137D03*
Y1101444D03*
X171341Y1104790D03*
X162641D03*
X171341Y1098097D03*
X162641D03*
X171341Y1128215D03*
X162641D03*
X176199Y1124869D03*
Y1114829D03*
X171341Y1121522D03*
X162641D03*
X176199Y1144948D03*
Y1138255D03*
Y1131562D03*
X171341Y1141601D03*
X162641D03*
X171341Y1134908D03*
X162641D03*
X176199Y1161680D03*
Y1151641D03*
X171341Y1158333D03*
X162641D03*
X171341Y1148294D03*
X162641D03*
X176199Y1175066D03*
Y1168373D03*
X171341Y1171719D03*
X162641D03*
X171341Y1165026D03*
X162641D03*
X176199Y1188452D03*
Y1181759D03*
X171341Y1185105D03*
X162641D03*
X171341Y1178412D03*
X162641D03*
X176199Y1205184D03*
Y1198491D03*
X171341Y1208530D03*
X162641D03*
X171341Y1201837D03*
X162641D03*
X171341Y1195144D03*
X162641D03*
X176199Y1225263D03*
Y1218570D03*
Y1211877D03*
X162641Y1221916D03*
X171341D03*
Y1215223D03*
X162641D03*
X176199Y1241995D03*
Y1235302D03*
X171341Y1238648D03*
X162641D03*
X171341Y1231955D03*
X162641D03*
X176199Y1248688D03*
X171341Y1245341D03*
X162641D03*
X165546Y1273364D03*
X168346D03*
X192341Y766798D03*
X184899Y770144D03*
X192341Y780184D03*
Y773491D03*
X184899Y783530D03*
Y776837D03*
X192341Y803609D03*
Y796916D03*
Y790223D03*
X184899Y800263D03*
Y793570D03*
X192341Y816995D03*
Y810302D03*
X184899Y820341D03*
Y813648D03*
Y806955D03*
X192341Y833727D03*
X191491Y827034D03*
X184899Y830381D03*
X192341Y847113D03*
Y840420D03*
X184899Y850459D03*
Y843766D03*
Y837074D03*
X191491Y863845D03*
X184899Y867192D03*
X192341Y853806D03*
X184899Y857152D03*
X192341Y883924D03*
Y877231D03*
Y870538D03*
X184899Y880577D03*
Y873885D03*
X192341Y900656D03*
Y890617D03*
X184899Y893963D03*
Y887270D03*
X192341Y914042D03*
Y907349D03*
X184899Y917389D03*
Y910696D03*
Y904003D03*
X191491Y927428D03*
X192341Y920735D03*
X184899Y930774D03*
Y924081D03*
X192341Y937467D03*
Y944160D03*
X184899Y947507D03*
Y940814D03*
X192341Y960892D03*
Y950853D03*
X184899Y964239D03*
Y954200D03*
X192341Y974278D03*
Y980971D03*
Y967585D03*
X184899Y977625D03*
Y970932D03*
X192341Y987664D03*
X184899Y991011D03*
Y984318D03*
X192341Y1027822D03*
Y1017782D03*
X184899Y1031168D03*
Y1024475D03*
Y1017782D03*
X192341Y1047900D03*
Y1041207D03*
Y1034515D03*
X184899Y1044554D03*
Y1037861D03*
X192341Y1054593D03*
Y1061286D03*
X184899Y1057940D03*
Y1051247D03*
X192341Y1074672D03*
Y1067979D03*
X184899Y1078018D03*
Y1071326D03*
Y1064633D03*
X192341Y1091404D03*
X191491Y1084711D03*
X184899Y1094751D03*
Y1088058D03*
X192341Y1111483D03*
Y1104790D03*
Y1098097D03*
X184899Y1108137D03*
Y1101444D03*
X192341Y1128215D03*
Y1121522D03*
X184899Y1124869D03*
Y1114829D03*
X192341Y1141601D03*
Y1134908D03*
X184899Y1144948D03*
Y1138255D03*
Y1131562D03*
X191491Y1158333D03*
X192341Y1148294D03*
X184899Y1161680D03*
Y1151641D03*
X192341Y1171719D03*
Y1165026D03*
X184899Y1175066D03*
Y1168373D03*
X192341Y1185105D03*
Y1178412D03*
X184899Y1188452D03*
Y1181759D03*
X192341Y1208530D03*
Y1201837D03*
Y1195144D03*
X184899Y1205184D03*
Y1198491D03*
X192341Y1221916D03*
Y1215223D03*
X184899Y1225263D03*
Y1218570D03*
Y1211877D03*
X192341Y1238648D03*
X191491Y1231955D03*
X184899Y1241995D03*
Y1235302D03*
X184923Y1258871D03*
X192341Y1245341D03*
X184899Y1248688D03*
X192594Y1271262D03*
X192605Y1268774D03*
X182046Y1273364D03*
X179246D03*
X186697Y1578182D03*
Y1590094D03*
X191997Y1602380D03*
Y1614292D03*
X205899Y770144D03*
X201041Y766798D03*
X205899Y783530D03*
Y776837D03*
X201041Y780184D03*
Y773491D03*
X205899Y800263D03*
Y793570D03*
X201041Y803609D03*
Y796916D03*
Y790223D03*
X205899Y813648D03*
Y806955D03*
X205049Y820341D03*
X201041Y816995D03*
Y810302D03*
X205049Y830381D03*
X201041Y833727D03*
Y827034D03*
X205899Y850459D03*
Y837074D03*
Y843766D03*
X201041Y847113D03*
Y840420D03*
X205049Y867192D03*
X201041Y863845D03*
X205049Y857152D03*
X201041Y853806D03*
X205899Y873885D03*
Y880577D03*
X201041Y883924D03*
Y877231D03*
Y870538D03*
X205899Y893963D03*
Y887270D03*
X201041Y900656D03*
Y890617D03*
X205899Y917389D03*
Y910696D03*
Y904003D03*
X201041Y914042D03*
Y907349D03*
X205049Y930774D03*
Y924081D03*
X201041Y927428D03*
Y920735D03*
X205899Y940814D03*
Y947507D03*
X201041Y937467D03*
Y944160D03*
X205899Y964239D03*
Y954200D03*
X201041Y960892D03*
Y950853D03*
X205899Y970932D03*
Y977625D03*
X201041Y974278D03*
Y980971D03*
Y967585D03*
X205899Y991011D03*
Y984318D03*
X201041Y987664D03*
X205899Y1031168D03*
Y1017782D03*
Y1024475D03*
X201041Y1027822D03*
Y1017782D03*
X205899Y1044554D03*
Y1037861D03*
X201041Y1047900D03*
Y1041207D03*
Y1034515D03*
X205899Y1057940D03*
Y1051247D03*
X201041Y1054593D03*
Y1061286D03*
X205049Y1078018D03*
X205899Y1071326D03*
Y1064633D03*
X201041Y1074672D03*
Y1067979D03*
X205899Y1094751D03*
X205049Y1088058D03*
X201041Y1091404D03*
Y1084711D03*
X205899Y1101444D03*
Y1108137D03*
X201041Y1111483D03*
Y1104790D03*
Y1098097D03*
X205899Y1114829D03*
Y1124869D03*
X201041Y1128215D03*
Y1121522D03*
X205899Y1144948D03*
Y1138255D03*
Y1131562D03*
X201041Y1141601D03*
Y1134908D03*
X205049Y1161680D03*
Y1151641D03*
X201041Y1158333D03*
Y1148294D03*
X205899Y1168373D03*
Y1175066D03*
X201041Y1171719D03*
Y1165026D03*
X205899Y1188452D03*
Y1181759D03*
X201041Y1185105D03*
Y1178412D03*
X205899Y1205184D03*
Y1198491D03*
X201041Y1208530D03*
Y1201837D03*
Y1195144D03*
X205049Y1225263D03*
X205899Y1211877D03*
Y1218570D03*
X201041Y1221916D03*
Y1215223D03*
X205899Y1241995D03*
X205049Y1235302D03*
X201041Y1238648D03*
Y1231955D03*
X205899Y1248688D03*
X201041Y1245341D03*
X206268Y1271348D03*
X206337Y1268720D03*
X194497Y1578182D03*
X206557D03*
X198757D03*
X194497Y1590094D03*
X206557D03*
X198757D03*
X199797Y1614292D03*
Y1602380D03*
X204057Y1614292D03*
Y1602380D03*
X222041Y766798D03*
X214599Y770144D03*
X222041Y780184D03*
Y773491D03*
X214599Y783530D03*
Y776837D03*
X222041Y803609D03*
Y796916D03*
Y790223D03*
X214599Y800263D03*
Y793570D03*
X222041Y810302D03*
X221191Y816995D03*
X214599Y813648D03*
Y806955D03*
X215449Y820341D03*
X222041Y833727D03*
X221191Y827034D03*
X215449Y830381D03*
X222041Y847113D03*
Y840420D03*
X214599Y850459D03*
Y837074D03*
Y843766D03*
X221191Y863845D03*
X215449Y867192D03*
X222041Y853806D03*
X215449Y857152D03*
X222041Y877231D03*
X221191Y870538D03*
X222041Y883924D03*
X214599Y873885D03*
Y880577D03*
X222041Y900656D03*
Y890617D03*
X214599Y893963D03*
Y887270D03*
X222041Y914042D03*
Y907349D03*
X214599Y917389D03*
Y910696D03*
Y904003D03*
X221241Y927428D03*
X222041Y920735D03*
X215449Y930774D03*
Y924081D03*
X222041Y944160D03*
X221191Y937467D03*
X214599Y940814D03*
Y947507D03*
X222041Y960892D03*
Y950853D03*
X214599Y964239D03*
Y954200D03*
X222041Y980971D03*
Y974278D03*
Y967585D03*
X214599Y970932D03*
Y977625D03*
Y991011D03*
Y984318D03*
X222041Y987664D03*
Y1027822D03*
Y1017782D03*
X214599Y1031168D03*
Y1017782D03*
Y1024475D03*
X222041Y1047900D03*
Y1041207D03*
Y1034515D03*
X214599Y1044554D03*
Y1037861D03*
X222041Y1054593D03*
Y1061286D03*
X214599Y1057940D03*
Y1051247D03*
X222041Y1067979D03*
X221191Y1074672D03*
X215449Y1078018D03*
X214599Y1071326D03*
Y1064633D03*
X222041Y1091404D03*
X221191Y1084711D03*
X214599Y1094751D03*
X215449Y1088058D03*
X222041Y1111483D03*
Y1098097D03*
Y1104790D03*
X214599Y1101444D03*
Y1108137D03*
X222041Y1128215D03*
Y1121522D03*
X214599Y1114829D03*
Y1124869D03*
X222041Y1141601D03*
X221191Y1134908D03*
X214599Y1144948D03*
Y1138255D03*
Y1131562D03*
X222041Y1158333D03*
X221191Y1148294D03*
X215449Y1161680D03*
Y1151641D03*
X222041Y1165026D03*
Y1171719D03*
X214599Y1168373D03*
Y1175066D03*
X222041Y1185105D03*
Y1178412D03*
X214599Y1188452D03*
Y1181759D03*
X222041Y1208530D03*
Y1201837D03*
Y1195144D03*
X214599Y1205184D03*
Y1198491D03*
X222041Y1221916D03*
Y1215223D03*
X215449Y1225263D03*
X214599Y1211877D03*
Y1218570D03*
X221191Y1231955D03*
Y1238648D03*
X214599Y1241995D03*
X215449Y1235302D03*
X222041Y1245341D03*
X214824Y1258711D03*
X214599Y1248688D03*
X224987Y1273535D03*
X218617Y1578182D03*
X210817D03*
X222877D03*
X218617Y1590094D03*
X210817D03*
X222877D03*
X211857Y1614292D03*
Y1602380D03*
X223917Y1614292D03*
X216117D03*
X223917Y1602380D03*
X216117D03*
X235599Y770144D03*
X230741Y766798D03*
X235599Y783530D03*
Y776837D03*
X230741Y780184D03*
Y773491D03*
X235599Y800263D03*
Y793570D03*
X230741Y803609D03*
Y796916D03*
Y790223D03*
X234749Y820341D03*
Y813648D03*
X235599Y806955D03*
X230741Y810302D03*
X231006Y817554D03*
X235599Y830381D03*
X230741Y833727D03*
X231591Y827034D03*
X235599Y850459D03*
Y837074D03*
Y843766D03*
X230741Y847113D03*
Y840420D03*
X234749Y867492D03*
X231591Y863845D03*
X234749Y857152D03*
X230741Y853806D03*
X235599Y874185D03*
Y880577D03*
X230741Y877231D03*
X231059Y871084D03*
X230741Y883924D03*
X235599Y893963D03*
Y887270D03*
X230741Y900656D03*
Y890617D03*
X235599Y917389D03*
Y910696D03*
Y904003D03*
X230741Y914042D03*
Y907349D03*
X235599Y930774D03*
Y924081D03*
X231541Y927428D03*
X230741Y920735D03*
X235599Y947507D03*
X234859Y940814D03*
X230741Y944660D03*
X231591Y937467D03*
X235599Y964239D03*
Y954200D03*
X230741Y960892D03*
Y950853D03*
X235599Y977625D03*
Y970932D03*
X230741Y980971D03*
Y974278D03*
Y967585D03*
X235599Y991011D03*
X230741Y987664D03*
X235599Y984318D03*
Y1031168D03*
X230741Y1027822D03*
Y1017782D03*
X235599D03*
Y1024475D03*
Y1044554D03*
Y1037861D03*
X230741Y1047900D03*
Y1041207D03*
Y1034515D03*
X235599Y1051247D03*
Y1057940D03*
X230741Y1054593D03*
Y1061286D03*
X234749Y1078018D03*
X235599Y1071326D03*
Y1064633D03*
X230741Y1067979D03*
X231591Y1074672D03*
X235599Y1094751D03*
X234749Y1088058D03*
X230741Y1091404D03*
Y1084711D03*
X235599Y1108137D03*
Y1101444D03*
X230741Y1111483D03*
Y1098097D03*
Y1104790D03*
X234749Y1124869D03*
X235599Y1114829D03*
X230741Y1128215D03*
Y1121522D03*
X235599Y1144948D03*
Y1138255D03*
X234749Y1131562D03*
X230741Y1141601D03*
X231591Y1134908D03*
X235599Y1151641D03*
Y1161680D03*
X230741Y1158333D03*
X231591Y1148294D03*
X235599Y1175066D03*
Y1168373D03*
X230741Y1165026D03*
Y1171719D03*
X235599Y1188452D03*
Y1181759D03*
X230741Y1185105D03*
Y1178412D03*
X235599Y1205184D03*
Y1198491D03*
X230741Y1208530D03*
Y1201837D03*
Y1195144D03*
X234749Y1225263D03*
X235599Y1218570D03*
Y1211877D03*
X230741Y1221916D03*
Y1215223D03*
X235599Y1241995D03*
X235186Y1234977D03*
X231591Y1231955D03*
Y1238648D03*
X235599Y1248688D03*
X230741Y1245341D03*
X227746Y1273364D03*
X240966Y1273143D03*
X238971Y1274353D03*
X230677Y1578182D03*
X234937D03*
X230677Y1590094D03*
X234937D03*
X228177Y1614292D03*
X235977D03*
X228177Y1602380D03*
X235977D03*
X240237D03*
Y1614292D03*
X233268Y1679920D03*
Y1675383D03*
X241142Y1679320D03*
X233268Y1698627D03*
Y1694093D03*
Y1689556D03*
Y1684454D03*
X241142Y1683857D03*
Y1688391D03*
Y1693493D03*
Y1698030D03*
X233268Y1712800D03*
Y1708266D03*
Y1703729D03*
X241142Y1702564D03*
Y1707666D03*
Y1712203D03*
X233268Y1717903D03*
Y1722440D03*
Y1726974D03*
X241142Y1716737D03*
Y1730911D03*
Y1726377D03*
Y1721840D03*
X251741Y766798D03*
X244299Y770144D03*
X251741Y780184D03*
Y773491D03*
X244299Y783530D03*
Y776837D03*
X251741Y803609D03*
Y796916D03*
Y790223D03*
X244299Y800263D03*
Y793570D03*
X250891Y816995D03*
X251741Y810302D03*
X245149Y820341D03*
Y813648D03*
X244299Y806955D03*
X251741Y833727D03*
X250891Y827034D03*
X244299Y830381D03*
X251741Y847113D03*
Y840420D03*
X244299Y850459D03*
Y837074D03*
Y843766D03*
X250891Y863845D03*
Y853806D03*
X245149Y867192D03*
Y857152D03*
X251741Y870538D03*
Y883924D03*
Y877231D03*
X244299Y873885D03*
Y880577D03*
X250891Y900656D03*
X251741Y890617D03*
X244299Y893963D03*
Y887270D03*
X251741Y914042D03*
Y907349D03*
X244299Y917389D03*
Y910696D03*
Y904003D03*
X250891Y927428D03*
X251741Y920735D03*
X245149Y930774D03*
X244299Y924081D03*
X251741Y944160D03*
X250891Y937467D03*
X244299Y947507D03*
X245149Y940814D03*
X251741Y960892D03*
Y950853D03*
X244299Y964239D03*
Y954200D03*
X251741Y980971D03*
Y974278D03*
Y967585D03*
X244299Y977625D03*
Y970932D03*
X251741Y987664D03*
X244299Y991011D03*
Y984318D03*
Y1031168D03*
X251741Y1027822D03*
Y1017782D03*
X244299D03*
Y1024475D03*
X251741Y1047900D03*
Y1041207D03*
Y1034515D03*
X244299Y1044554D03*
Y1037861D03*
X251741Y1061286D03*
Y1054593D03*
X244299Y1051247D03*
Y1057940D03*
X250891Y1074672D03*
Y1067979D03*
X245149Y1078018D03*
X244299Y1071326D03*
Y1064633D03*
X251741Y1091404D03*
Y1084711D03*
X244299Y1094751D03*
X245149Y1088058D03*
X251741Y1104790D03*
X250891Y1111483D03*
X251741Y1098097D03*
X244299Y1108137D03*
Y1101444D03*
X251741Y1128215D03*
X250891Y1121522D03*
X245149Y1124869D03*
X244299Y1114829D03*
X251741Y1134908D03*
Y1141601D03*
X244299Y1144948D03*
Y1138255D03*
X245149Y1131562D03*
X251741Y1158333D03*
Y1148294D03*
X244299Y1151641D03*
Y1161680D03*
X251741Y1171719D03*
Y1165026D03*
X244299Y1175066D03*
Y1168373D03*
X251741Y1185105D03*
Y1178412D03*
X244299Y1188452D03*
Y1181759D03*
X251741Y1208530D03*
Y1201837D03*
X250891Y1195144D03*
X244299Y1205184D03*
Y1198491D03*
X250891Y1221916D03*
X251741Y1215223D03*
X245149Y1225263D03*
X244299Y1218570D03*
Y1211877D03*
X250891Y1231955D03*
X244299Y1241995D03*
X245149Y1235302D03*
X251741Y1238648D03*
X244299Y1248688D03*
X251741Y1245341D03*
X244789Y1260093D03*
X254897Y1274040D03*
X257197Y1273640D03*
X242737Y1578182D03*
X246997D03*
X254797D03*
X242737Y1590094D03*
X246997D03*
X254797D03*
X248037Y1602380D03*
Y1614292D03*
X252297Y1602380D03*
Y1614292D03*
X249016Y1675383D03*
Y1679920D03*
X256890Y1679320D03*
X249016Y1684454D03*
Y1689556D03*
Y1694093D03*
Y1698627D03*
X256890Y1683857D03*
Y1688391D03*
Y1693493D03*
Y1698030D03*
X249016Y1703729D03*
Y1708266D03*
Y1712800D03*
X256890Y1702564D03*
Y1707666D03*
Y1712203D03*
X249016Y1726974D03*
Y1722440D03*
Y1717903D03*
X256890Y1716737D03*
Y1730911D03*
Y1726377D03*
Y1721840D03*
X260441Y766798D03*
Y780184D03*
Y773491D03*
Y803609D03*
Y796916D03*
Y790223D03*
X261291Y816995D03*
X260441Y810302D03*
Y833727D03*
X261291Y827034D03*
X260441Y847113D03*
Y840420D03*
X261291Y863845D03*
Y853806D03*
X260441Y870538D03*
Y883924D03*
Y877231D03*
Y900656D03*
Y890617D03*
Y914042D03*
Y907349D03*
X261291Y927428D03*
X260441Y920735D03*
Y944160D03*
X261291Y937467D03*
X260441Y960892D03*
Y950853D03*
Y980971D03*
Y974278D03*
Y967585D03*
Y987664D03*
Y1027822D03*
Y1017782D03*
Y1047900D03*
Y1041207D03*
Y1034515D03*
Y1061286D03*
Y1054593D03*
X261291Y1074672D03*
Y1067979D03*
X260441Y1091404D03*
Y1084711D03*
Y1104790D03*
X261291Y1111483D03*
X260441Y1098097D03*
Y1128215D03*
X261291Y1121522D03*
X260441Y1134908D03*
Y1141601D03*
Y1158333D03*
Y1148294D03*
Y1171719D03*
Y1165026D03*
Y1185105D03*
Y1178412D03*
Y1208530D03*
Y1201837D03*
Y1195144D03*
X261291Y1221916D03*
X260441Y1215223D03*
X261291Y1231955D03*
X260441Y1238648D03*
Y1245341D03*
X266857Y1578182D03*
X259057D03*
X271117D03*
X266857Y1590094D03*
X259057D03*
X271117D03*
X260097Y1602380D03*
Y1614292D03*
X272157Y1602380D03*
Y1614292D03*
X264357D03*
Y1602380D03*
X264764Y1675383D03*
Y1679920D03*
X272638Y1679320D03*
X264764Y1684454D03*
Y1689556D03*
Y1694093D03*
Y1698627D03*
X272638Y1683857D03*
Y1688391D03*
Y1693493D03*
Y1698030D03*
X264764Y1703729D03*
Y1708266D03*
Y1712800D03*
X272638Y1702564D03*
Y1707666D03*
Y1712203D03*
X264764Y1726974D03*
Y1722440D03*
Y1717903D03*
X272638Y1716737D03*
Y1730911D03*
Y1726377D03*
Y1721840D03*
X278917Y1578182D03*
X283177D03*
X278917Y1590094D03*
X283177D03*
X284217Y1602380D03*
Y1614292D03*
X276417D03*
Y1602380D03*
X288477Y1614292D03*
Y1602380D03*
X280512Y1675383D03*
Y1679920D03*
Y1684454D03*
Y1689556D03*
Y1694093D03*
Y1698627D03*
Y1703729D03*
Y1708266D03*
Y1712800D03*
Y1726974D03*
Y1722440D03*
Y1717903D03*
X290977Y1578182D03*
X295237D03*
X303037D03*
X290977Y1590094D03*
X295237D03*
X303037D03*
X296277Y1614292D03*
Y1602380D03*
X300537D03*
Y1614292D03*
X300197Y1679920D03*
Y1675383D03*
Y1698627D03*
Y1694093D03*
Y1689556D03*
Y1684454D03*
Y1712800D03*
Y1708266D03*
Y1703729D03*
Y1717903D03*
Y1722440D03*
Y1726974D03*
X315097Y1578182D03*
X307297D03*
X319357D03*
X315097Y1590094D03*
X307297D03*
X319357D03*
X308337Y1602380D03*
Y1614292D03*
X320397D03*
X312597D03*
X320397Y1602380D03*
X312597D03*
X308071Y1679320D03*
X315945Y1679920D03*
Y1675383D03*
X308071Y1683857D03*
Y1698030D03*
Y1693493D03*
Y1688391D03*
X315945Y1698627D03*
Y1694093D03*
Y1689556D03*
Y1684454D03*
X308071Y1702564D03*
Y1712203D03*
Y1707666D03*
X315945Y1712800D03*
Y1708266D03*
Y1703729D03*
X308071Y1716737D03*
Y1721840D03*
Y1726377D03*
Y1730911D03*
X315945Y1717903D03*
Y1722440D03*
Y1726974D03*
X327157Y1578182D03*
X331417D03*
X327157Y1590094D03*
X331417D03*
X324657Y1602380D03*
X332457D03*
X324657Y1614292D03*
X332457D03*
X336717Y1602380D03*
Y1614292D03*
X323819Y1679320D03*
X331693Y1679920D03*
Y1675383D03*
X323819Y1683857D03*
Y1698030D03*
Y1693493D03*
Y1688391D03*
X331693Y1698627D03*
Y1694093D03*
Y1689556D03*
Y1684454D03*
X323819Y1702564D03*
Y1712203D03*
Y1707666D03*
X331693Y1712800D03*
Y1708266D03*
Y1703729D03*
X323819Y1716737D03*
Y1721840D03*
Y1726377D03*
Y1730911D03*
X331693Y1717903D03*
Y1722440D03*
Y1726974D03*
X352579Y854584D03*
X347029Y870606D03*
Y889832D03*
X343707Y1091513D03*
X339217Y1578182D03*
X343477D03*
X351277D03*
X339217Y1590094D03*
X343477D03*
X351277D03*
X344517Y1602380D03*
Y1614292D03*
X348777Y1602380D03*
Y1614292D03*
X339567Y1679320D03*
X347441Y1679920D03*
Y1675383D03*
X355315Y1679320D03*
X339567Y1683857D03*
Y1698030D03*
Y1693493D03*
Y1688391D03*
X347441Y1698627D03*
Y1694093D03*
Y1689556D03*
Y1684454D03*
X355315Y1683857D03*
Y1698030D03*
Y1693493D03*
Y1688391D03*
X339567Y1702564D03*
Y1712203D03*
Y1707666D03*
X347441Y1712800D03*
Y1708266D03*
Y1703729D03*
X355315Y1702564D03*
Y1712203D03*
Y1707666D03*
X339567Y1716737D03*
Y1721840D03*
Y1726377D03*
Y1730911D03*
X347441Y1717903D03*
Y1722440D03*
Y1726974D03*
X355315Y1716737D03*
Y1721840D03*
Y1726377D03*
Y1730911D03*
X359979Y841467D03*
X367379D03*
X365529Y851380D03*
X369229D03*
X359979Y880219D03*
Y899445D03*
X371078D03*
X359979Y918670D03*
X365529Y941100D03*
X359979Y937896D03*
X371078D03*
X369662Y1006093D03*
X365962Y1076587D03*
X363337Y1578088D03*
X355537Y1578182D03*
X367597D03*
X363337Y1590094D03*
X355537D03*
X367597D03*
X356577Y1602380D03*
Y1614292D03*
X368637D03*
X360837D03*
X368637Y1602286D03*
X360837Y1602380D03*
X382179Y841467D03*
X374779D03*
X380329Y851380D03*
X376629D03*
X372929D03*
X384029D03*
X387729D03*
X378478Y931488D03*
X378911Y1060565D03*
X375397Y1578182D03*
Y1590094D03*
X372897Y1602380D03*
X380697D03*
X372897Y1614292D03*
X380697D03*
X389579Y841467D03*
X396978Y899445D03*
Y937896D03*
X415185Y985580D03*
X417575D03*
X415185Y1014540D03*
X417575D03*
X435829Y851380D03*
Y864197D03*
Y877014D03*
Y889832D03*
Y902649D03*
X428429Y921875D03*
X430279Y937897D03*
X433979D03*
X433980Y944305D03*
Y957123D03*
Y950714D03*
Y963531D03*
Y976348D03*
Y969940D03*
Y982757D03*
X434411Y1009298D03*
X434412Y1002889D03*
X434411Y1028524D03*
Y1022115D03*
X434412Y1015706D03*
Y1034932D03*
X434411Y1092608D03*
X450629Y851380D03*
Y877014D03*
X437678Y912262D03*
X441379Y937897D03*
X445079D03*
X437679D03*
X446929Y941101D03*
X446930Y947510D03*
Y960327D03*
Y953918D03*
Y966736D03*
Y979553D03*
Y973144D03*
X447362Y1006094D03*
Y999685D03*
Y1012502D03*
Y1025319D03*
Y1018911D03*
Y1031728D03*
X456178Y912262D03*
X461729Y921875D03*
X462261Y942152D03*
X464561D03*
X466861D03*
X454423Y949139D03*
X454393Y963829D03*
Y966129D03*
X463874Y956540D03*
X466272D03*
X454423Y951439D03*
X466272Y971100D03*
X463874Y971140D03*
X454263Y981209D03*
Y978909D03*
X454463Y995299D03*
Y992999D03*
X466272Y985580D03*
X463874D03*
X466272Y1014540D03*
X463874D03*
X454443Y1009409D03*
Y1007109D03*
X466272Y1000060D03*
X463874D03*
X468895Y1014550D03*
X465862Y1057361D03*
X458462Y1063770D03*
X465862D03*
X456611Y1073383D03*
X454762Y1070178D03*
X467711Y1073383D03*
Y1066974D03*
X474678Y899445D03*
Y912262D03*
X480229Y921875D03*
X471204Y1014540D03*
X475111Y1060565D03*
X484361Y1057361D03*
X475111Y1066974D03*
X473262Y1070178D03*
X478811Y1073383D03*
X484361Y1076587D03*
X482512Y1066974D03*
X478812Y1079791D03*
X475111D03*
X482911Y1578182D03*
X478651D03*
X470851D03*
X482911Y1590094D03*
X478651D03*
X470851D03*
X483951Y1614292D03*
Y1602380D03*
X476151D03*
Y1614292D03*
X489478Y912262D03*
X495462Y1057361D03*
X499162Y1063770D03*
X495462Y1076587D03*
X493612Y1073383D03*
X486211D03*
X497311Y1066974D03*
X495462Y1108630D03*
X493611Y1111834D03*
X494971Y1578182D03*
X490711D03*
X494971Y1590094D03*
X490711D03*
X500271Y1614292D03*
Y1602380D03*
X488211Y1614292D03*
Y1602380D03*
X496011D03*
Y1614292D03*
X497441Y1675383D03*
Y1679920D03*
Y1684454D03*
Y1689556D03*
Y1694093D03*
Y1698627D03*
Y1703729D03*
Y1708266D03*
Y1712800D03*
Y1726974D03*
Y1722440D03*
Y1717903D03*
X507978Y937896D03*
X509829Y947509D03*
X510262Y1057361D03*
X506562Y1063770D03*
X510262Y1076587D03*
X512111Y1073383D03*
X508411Y1066974D03*
X515811D03*
X508411Y1079791D03*
X515811Y1086200D03*
X507031Y1578182D03*
X514831D03*
X502771D03*
X507031Y1590094D03*
X514831D03*
X502771D03*
X512331Y1614292D03*
Y1602380D03*
X508071Y1614292D03*
Y1602380D03*
X513189Y1675383D03*
Y1679920D03*
X505315Y1679320D03*
X513189Y1684454D03*
Y1689556D03*
Y1694093D03*
Y1698627D03*
X505315Y1688391D03*
Y1693493D03*
Y1698030D03*
Y1683857D03*
X513189Y1703729D03*
Y1708266D03*
Y1712800D03*
X505315Y1707666D03*
Y1712203D03*
Y1702564D03*
X513189Y1726974D03*
Y1722440D03*
Y1717903D03*
X505315Y1730911D03*
Y1726377D03*
Y1721840D03*
Y1716737D03*
X521362Y1057361D03*
X525061Y1063770D03*
X532462D03*
X521362Y1076587D03*
X519512Y1073383D03*
X523211Y1066974D03*
X534311D03*
X531151Y1578182D03*
X519091D03*
X526891D03*
X531151Y1590094D03*
X519091D03*
X526891D03*
X532191Y1614292D03*
Y1602380D03*
X524391Y1614292D03*
Y1602380D03*
X520131D03*
Y1614292D03*
X528937Y1675383D03*
Y1679920D03*
X521063Y1679320D03*
X528937Y1684454D03*
Y1689556D03*
Y1694093D03*
Y1698627D03*
X521063Y1688391D03*
Y1693493D03*
Y1698030D03*
Y1683857D03*
X528937Y1703729D03*
Y1708266D03*
Y1712800D03*
X521063Y1707666D03*
Y1712203D03*
Y1702564D03*
X528937Y1726974D03*
Y1722440D03*
Y1717903D03*
X521063Y1730911D03*
Y1726377D03*
Y1721840D03*
Y1716737D03*
X543129Y928283D03*
X539429D03*
X537578Y925079D03*
X535729Y928283D03*
X548678Y925079D03*
X537578Y944304D03*
X548678D03*
X536161Y1057361D03*
X549422Y1064850D03*
X541711Y1073383D03*
X545411Y1066974D03*
X536161Y1076587D03*
X536162Y1070178D03*
X538011Y1073383D03*
X547262Y1070178D03*
X543211Y1578182D03*
X538951D03*
X543211Y1590094D03*
X538951D03*
X548511Y1614292D03*
Y1602380D03*
X536451D03*
Y1614292D03*
X544251Y1602380D03*
Y1614292D03*
X544685Y1675383D03*
Y1679920D03*
X536811Y1679320D03*
X544685Y1684454D03*
Y1689556D03*
Y1694093D03*
Y1698627D03*
X536811Y1688391D03*
Y1693493D03*
Y1698030D03*
Y1683857D03*
X544685Y1703729D03*
Y1708266D03*
Y1712800D03*
X536811Y1707666D03*
Y1712203D03*
Y1702564D03*
X544685Y1726974D03*
Y1722440D03*
Y1717903D03*
X536811Y1730911D03*
Y1726377D03*
Y1721840D03*
Y1716737D03*
X555271Y1578182D03*
X563071D03*
X551011D03*
X555271Y1590094D03*
X563071D03*
X551011D03*
X560571Y1602380D03*
X556311Y1614292D03*
Y1602380D03*
X552559Y1679320D03*
X564370Y1675383D03*
Y1679920D03*
X552559Y1688391D03*
Y1693493D03*
Y1698030D03*
Y1683857D03*
X564370Y1684454D03*
Y1689556D03*
Y1694093D03*
Y1698627D03*
X552559Y1707666D03*
Y1712203D03*
Y1702564D03*
X564370Y1703729D03*
Y1708266D03*
Y1712800D03*
X552559Y1730911D03*
Y1726377D03*
Y1721840D03*
Y1716737D03*
X564370Y1726974D03*
Y1722440D03*
Y1717903D03*
X579391Y1578182D03*
X567331D03*
X575131D03*
X579391Y1590094D03*
X567331D03*
X575131D03*
X580431Y1614292D03*
X572631D03*
Y1602380D03*
X568371D03*
Y1614292D03*
X580118Y1675383D03*
Y1679920D03*
X572244Y1679320D03*
X580118Y1684454D03*
Y1689556D03*
Y1694093D03*
Y1698627D03*
X572244Y1688391D03*
Y1693493D03*
Y1698030D03*
Y1683857D03*
X580118Y1703729D03*
Y1708266D03*
Y1712800D03*
X572244Y1707666D03*
Y1712203D03*
Y1702564D03*
X580118Y1726974D03*
Y1722440D03*
Y1717903D03*
X572244Y1730911D03*
Y1726377D03*
Y1721840D03*
Y1716737D03*
X599251Y1578182D03*
X591451D03*
X587191D03*
X599251Y1590094D03*
X591451D03*
X587191D03*
X596751Y1614292D03*
Y1602380D03*
X584691D03*
Y1614292D03*
X592491Y1602380D03*
Y1614292D03*
X595866Y1675383D03*
Y1679920D03*
X587992Y1679320D03*
X595866Y1684454D03*
Y1689556D03*
Y1694093D03*
Y1698627D03*
X587992Y1688391D03*
Y1693493D03*
Y1698030D03*
Y1683857D03*
X595866Y1703729D03*
Y1708266D03*
Y1712800D03*
X587992Y1707666D03*
Y1712203D03*
Y1702564D03*
X595866Y1726974D03*
Y1722440D03*
Y1717903D03*
X587992Y1730911D03*
Y1726377D03*
Y1721840D03*
Y1716737D03*
X615571Y1578182D03*
X603511D03*
X611311D03*
X615571Y1590094D03*
X603511D03*
X611311D03*
X608811Y1602380D03*
Y1614292D03*
X604551Y1602380D03*
Y1614292D03*
X611614Y1675383D03*
Y1679920D03*
X603740Y1679320D03*
X611614Y1684454D03*
Y1689556D03*
Y1694093D03*
Y1698627D03*
X603740Y1688391D03*
Y1693493D03*
Y1698030D03*
Y1683857D03*
X611614Y1703729D03*
Y1708266D03*
Y1712800D03*
X603740Y1707666D03*
Y1712203D03*
Y1702564D03*
X611614Y1726974D03*
Y1722440D03*
Y1717903D03*
X603740Y1730911D03*
Y1726377D03*
Y1721840D03*
Y1716737D03*
X629599Y770144D03*
X620899D03*
X629599Y783530D03*
X620899D03*
X629599Y776837D03*
X620899D03*
X620846Y800263D03*
X629599D03*
Y793570D03*
X620899D03*
Y820341D03*
X629599D03*
X620076Y813648D03*
X630593D03*
X619632Y806955D03*
X630792D03*
X620899Y830381D03*
X629599D03*
X620005Y850459D03*
X630754D03*
X620899Y843766D03*
X629599D03*
Y837074D03*
X620899D03*
Y867192D03*
X629599D03*
X620058Y857152D03*
X630481D03*
X620899Y880577D03*
X629599D03*
X620899Y873885D03*
X629599D03*
X630756Y893963D03*
X620899D03*
X629599Y887270D03*
X620899D03*
Y910696D03*
X629599D03*
Y917389D03*
X620899D03*
X629599Y904003D03*
X620899D03*
X630399Y930697D03*
X619905Y930774D03*
X620899Y924081D03*
X629599D03*
Y947507D03*
X620899D03*
X619964Y940814D03*
X630777D03*
X629599Y964239D03*
X620899D03*
X629599Y954200D03*
X620899D03*
Y977625D03*
X629599D03*
Y970932D03*
X620899D03*
Y991011D03*
X629599D03*
Y984318D03*
X620899D03*
Y1031168D03*
X629599D03*
X620899Y1017782D03*
X629599D03*
X620899Y1024475D03*
X629599D03*
X620899Y1044554D03*
X629599D03*
X620899Y1037861D03*
X629599D03*
X620899Y1057940D03*
X629599D03*
Y1051247D03*
X620899D03*
Y1078018D03*
X629599D03*
X630399Y1071326D03*
X619999D03*
X620899Y1064633D03*
X629599D03*
X620899Y1088058D03*
X629599D03*
Y1094751D03*
X620899D03*
Y1108137D03*
X629599D03*
Y1101444D03*
X620899D03*
X630363Y1124674D03*
X620369Y1124969D03*
X630399Y1114829D03*
X620099D03*
X620899Y1131562D03*
X629599D03*
Y1144948D03*
X620899D03*
X629599Y1138255D03*
X620899D03*
X620511Y1161680D03*
X629833Y1161581D03*
X629599Y1151641D03*
X620899D03*
X629599Y1175066D03*
X620899D03*
X629599Y1168373D03*
X620899D03*
X630623Y1188452D03*
X620899D03*
X629599Y1181759D03*
X620899D03*
X629599Y1205184D03*
X620899D03*
Y1198491D03*
X629599D03*
X620899Y1225263D03*
X629599D03*
Y1218570D03*
X620899D03*
X629599Y1211877D03*
X620899D03*
X629599Y1241995D03*
X620899D03*
X630922Y1235302D03*
X620036D03*
X620899Y1248688D03*
X629599D03*
X625246Y1273164D03*
X627646D03*
X627631Y1578182D03*
X623371D03*
X627631Y1590094D03*
X623371D03*
X628671Y1602380D03*
Y1614292D03*
X620871D03*
Y1602380D03*
X616611Y1614292D03*
Y1602380D03*
X619488Y1679320D03*
Y1688391D03*
Y1693493D03*
Y1698030D03*
Y1683857D03*
Y1707666D03*
Y1712203D03*
Y1702564D03*
Y1730911D03*
Y1726377D03*
Y1721840D03*
Y1716737D03*
X637041Y766798D03*
X645741D03*
Y773491D03*
X637041D03*
X645741Y780184D03*
X637041D03*
Y803609D03*
X645741D03*
X637041Y796916D03*
X645741D03*
Y790223D03*
X637041D03*
X636221Y810302D03*
X646844D03*
X646774Y816995D03*
X637041D03*
X645741Y833727D03*
X637041D03*
Y827034D03*
X645741D03*
X637041Y847113D03*
X645801D03*
X637041Y840420D03*
X645741D03*
X646819Y853806D03*
X636332Y853955D03*
X645918Y863845D03*
X636266D03*
X637041Y877231D03*
X645741D03*
X637041Y870538D03*
X645741D03*
Y883924D03*
X637041D03*
Y900656D03*
X645741D03*
X637041Y890617D03*
X645741D03*
X637041Y914042D03*
X645741D03*
Y907349D03*
X637041D03*
X646393Y927526D03*
X636026Y927428D03*
X645741Y920735D03*
X637041D03*
X645741Y944160D03*
X637041D03*
X636170Y937467D03*
X646703D03*
X645741Y960892D03*
X637041D03*
Y950853D03*
X645741D03*
X637041Y980971D03*
X645741D03*
X637041Y974278D03*
X645741D03*
X637041Y967585D03*
X645741D03*
X637041Y987664D03*
X645741D03*
X637041Y1027822D03*
X645741D03*
Y1017782D03*
X637041D03*
X645741Y1047900D03*
X637041D03*
Y1041207D03*
X645741D03*
X637041Y1034515D03*
X645741D03*
X637041Y1061286D03*
X645741D03*
Y1054593D03*
X637041D03*
X636141Y1074672D03*
X646541D03*
X645741Y1067979D03*
X636841D03*
X637041Y1091404D03*
X645741D03*
Y1084711D03*
X636241D03*
X645741Y1111483D03*
X637041D03*
X645741Y1098097D03*
X637041D03*
X645741Y1104790D03*
X637041D03*
Y1121522D03*
X645741D03*
X637041Y1128915D03*
X645741Y1128215D03*
X646584Y1135108D03*
X635744Y1134908D03*
X645741Y1141601D03*
X637041D03*
X645741Y1148294D03*
X637041D03*
X645741Y1158333D03*
X637041D03*
Y1171719D03*
X645741D03*
Y1165026D03*
X637041D03*
Y1185105D03*
X645741D03*
Y1178412D03*
X637041D03*
X645741Y1208530D03*
X637041D03*
X645741Y1201837D03*
X637041D03*
Y1195144D03*
X645741D03*
X636005Y1221916D03*
X646570D03*
X645741Y1215223D03*
X637041D03*
X645741Y1238648D03*
X637041D03*
X635995Y1231862D03*
X646539Y1231955D03*
X645741Y1245341D03*
X637041D03*
X634213Y1258679D03*
X642746Y1273364D03*
X639946D03*
X647491Y1578088D03*
X639691Y1578182D03*
X635431D03*
X647491Y1590094D03*
X639691D03*
X635431D03*
X644991Y1614292D03*
Y1602380D03*
X632931D03*
Y1614292D03*
X640731D03*
Y1602380D03*
X650599Y770144D03*
X659299D03*
X650599Y783530D03*
X659299D03*
X650599Y776837D03*
X659299D03*
Y800263D03*
X650599D03*
Y793570D03*
X659299D03*
Y806955D03*
X650599D03*
X660432Y813648D03*
X650599D03*
X660199Y820341D03*
X650599D03*
X659299Y830381D03*
X650599D03*
X659299Y850459D03*
X650599D03*
X659299Y843766D03*
X650599D03*
Y837074D03*
X659299D03*
Y857152D03*
X650599D03*
X649563Y867192D03*
X660299D03*
X659299Y873885D03*
X650599D03*
Y880577D03*
X659299D03*
X650599Y893963D03*
X659299D03*
X650599Y887270D03*
X659299D03*
Y917389D03*
X650599D03*
X659299Y910696D03*
X650599D03*
Y904003D03*
X659299D03*
X660504Y924081D03*
X650599D03*
X660174Y930774D03*
X649661D03*
X659299Y947507D03*
X650599D03*
X659299Y940814D03*
X650599D03*
X659299Y964239D03*
X650599D03*
Y954200D03*
X659299D03*
Y977625D03*
X650599D03*
X659299Y970932D03*
X650599D03*
X659299Y991011D03*
X650599D03*
X659299Y984318D03*
X650599D03*
X659299Y1031168D03*
X650599D03*
X659299Y1017782D03*
X650599D03*
X659299Y1024475D03*
X650599D03*
X659299Y1044554D03*
X650599D03*
X659299Y1037861D03*
X650599D03*
X659299Y1051247D03*
X650599D03*
Y1057940D03*
X659299D03*
X660099Y1078018D03*
X649799D03*
X659299Y1071326D03*
X650599D03*
X659299Y1064633D03*
X650599D03*
X659299Y1094751D03*
X650599D03*
X660099Y1088058D03*
X649799D03*
X650599Y1108137D03*
X659299D03*
X650599Y1101444D03*
X659299D03*
X660199Y1124869D03*
X649932Y1124640D03*
X659299Y1114829D03*
X650599D03*
X659299Y1130762D03*
X650599D03*
X659299Y1138255D03*
X650599D03*
X659299Y1144948D03*
X650599D03*
X659299Y1151641D03*
X650599D03*
Y1161680D03*
X659299D03*
X650599Y1175066D03*
X659299D03*
X650599Y1168373D03*
X659299D03*
X650599Y1188452D03*
X659299D03*
X650599Y1181759D03*
X659299D03*
X650599Y1205184D03*
X659299D03*
X650599Y1198491D03*
X659299D03*
X660070Y1225263D03*
X649913D03*
X659299Y1218570D03*
X650599D03*
X659299Y1211877D03*
X650599D03*
X659299Y1241995D03*
X650599D03*
X660234Y1235302D03*
X649701D03*
X650599Y1248688D03*
X659299D03*
X659546Y1257664D03*
X656446Y1273364D03*
X653646D03*
X651751Y1578182D03*
X659551D03*
X651751Y1590094D03*
X659551D03*
X657051Y1602380D03*
Y1614292D03*
X652791Y1602286D03*
Y1614292D03*
X680299Y770144D03*
X675441Y766798D03*
X666741D03*
X680299Y783530D03*
Y776837D03*
X666741Y773491D03*
X675441D03*
X666741Y780184D03*
X675441D03*
Y803609D03*
X666741D03*
X680299Y800263D03*
Y793570D03*
X666741Y796916D03*
X675441D03*
X666741Y790223D03*
X675441D03*
X676403Y816995D03*
X665803D03*
X675441Y810302D03*
X666741D03*
X680299Y820341D03*
Y813648D03*
Y806955D03*
X675441Y833727D03*
X666741D03*
X676625Y827034D03*
X665876D03*
X680299Y830381D03*
X675441Y847113D03*
X666741D03*
X680299Y850459D03*
Y843766D03*
Y837074D03*
X666741Y840420D03*
X675441D03*
X676417Y853806D03*
X665890D03*
X680299Y867192D03*
Y857152D03*
X665916Y863845D03*
X676600D03*
X675441Y877231D03*
X666741D03*
X675441Y870538D03*
X666741D03*
Y883924D03*
X675441D03*
X680299Y880577D03*
Y873885D03*
X666741Y900656D03*
X675441D03*
X680299Y893963D03*
Y887270D03*
X666741Y890617D03*
X675441D03*
Y914042D03*
X666741D03*
X680299Y917389D03*
Y910696D03*
Y904003D03*
X666741Y907349D03*
X675441D03*
X676488Y927428D03*
X665896D03*
X675441Y920735D03*
X666741D03*
X680299Y930774D03*
Y924081D03*
X675441Y944160D03*
X666741D03*
X676359Y937467D03*
X665923D03*
X680299Y947507D03*
Y940814D03*
Y964239D03*
X675441Y960892D03*
X666741D03*
X680299Y954200D03*
X666741Y950853D03*
X675441D03*
Y980971D03*
X666741D03*
X680299Y970932D03*
X675441Y974278D03*
X666741D03*
X675441Y967585D03*
X666741D03*
X680299Y977625D03*
X675441Y987664D03*
X666741D03*
X680299Y991011D03*
Y984318D03*
Y1031168D03*
Y1024475D03*
X675441Y1027822D03*
X666741D03*
X675441Y1017782D03*
X666741D03*
X680299D03*
X675441Y1047900D03*
X666741D03*
X680299Y1037861D03*
X675441Y1041207D03*
X666741D03*
X675441Y1034515D03*
X666741D03*
X680299Y1044554D03*
Y1057940D03*
Y1051247D03*
X675441Y1054593D03*
X666741D03*
Y1061286D03*
X675441D03*
X676341Y1074672D03*
X665841D03*
X675441Y1067979D03*
X666741D03*
X680299Y1078018D03*
Y1071326D03*
Y1064633D03*
X675441Y1091404D03*
X666741D03*
X676241Y1084711D03*
X665941D03*
X680299Y1094751D03*
Y1088058D03*
X666741Y1111483D03*
X675441D03*
X680299Y1108137D03*
Y1101444D03*
X666741Y1104790D03*
X675441D03*
X666741Y1098097D03*
X675441D03*
X666741Y1128215D03*
X675441D03*
X680299Y1124869D03*
Y1114829D03*
X666741Y1121522D03*
X675441D03*
X680299Y1144948D03*
Y1138255D03*
Y1131562D03*
X666741Y1141601D03*
X675441D03*
X666741Y1134908D03*
X675441D03*
X676652Y1148294D03*
X665602D03*
X676241Y1158333D03*
X665941D03*
X680299Y1161680D03*
Y1151641D03*
X675441Y1165026D03*
X666741D03*
X680299Y1175066D03*
Y1168373D03*
X666741Y1171719D03*
X675441D03*
X680299Y1188452D03*
Y1181759D03*
X666741Y1185105D03*
X675441D03*
X666741Y1178412D03*
X675441D03*
X680299Y1205184D03*
Y1198491D03*
X666741Y1208530D03*
X675441D03*
X666741Y1201837D03*
X675441D03*
X666741Y1195144D03*
X675441D03*
X680299Y1218570D03*
Y1225263D03*
X676448Y1221916D03*
X665651D03*
X675441Y1215223D03*
X666741D03*
X680299Y1211877D03*
X675441Y1238648D03*
X666741D03*
X676462Y1231955D03*
X665912D03*
X680299Y1241995D03*
Y1235302D03*
X675441Y1245341D03*
X666741D03*
X676046Y1257964D03*
X680299Y1248688D03*
X672446Y1273364D03*
X669646D03*
X664851Y1602380D03*
Y1614292D03*
X696441Y766798D03*
X688999Y770144D03*
X696441Y773491D03*
Y780184D03*
X688999Y783530D03*
Y776837D03*
X696441Y803609D03*
Y796916D03*
Y790223D03*
X688999Y800263D03*
Y793570D03*
X696441Y816995D03*
Y810302D03*
X689888Y820341D03*
X688999Y813648D03*
Y806955D03*
X696441Y833727D03*
Y827034D03*
X688999Y830381D03*
X696441Y847113D03*
X688999Y850459D03*
X696441Y840420D03*
X688999Y843766D03*
Y837074D03*
X696441Y863845D03*
Y853806D03*
X688999Y867192D03*
X689896Y857152D03*
X696441Y883924D03*
Y877231D03*
Y870538D03*
X688999Y880577D03*
Y873885D03*
X696441Y900656D03*
Y890617D03*
X688999Y893963D03*
Y887270D03*
X696441Y914042D03*
Y907349D03*
X688999Y917389D03*
Y910696D03*
Y904003D03*
X696441Y927428D03*
Y920735D03*
X690104Y930774D03*
X688999Y924081D03*
X696441Y944160D03*
Y937467D03*
X688999Y947507D03*
Y940814D03*
X696441Y960892D03*
Y950853D03*
X688999Y964239D03*
Y954200D03*
X696441Y980971D03*
Y974278D03*
Y967585D03*
X688999Y970932D03*
Y977625D03*
X696441Y987664D03*
X688999Y991011D03*
Y984318D03*
X696441Y1027822D03*
Y1017782D03*
X688999Y1031168D03*
Y1024475D03*
Y1017782D03*
X696441Y1047900D03*
Y1041207D03*
Y1034515D03*
X688999Y1037861D03*
Y1044554D03*
X696441Y1054593D03*
Y1061286D03*
X688999Y1057940D03*
X696441Y1074672D03*
Y1067979D03*
X688999Y1077118D03*
Y1071326D03*
Y1064633D03*
X696441Y1091404D03*
Y1084711D03*
X688999Y1094751D03*
Y1088058D03*
X696441Y1111483D03*
Y1104790D03*
Y1098097D03*
X688999Y1108137D03*
Y1101444D03*
X696441Y1128215D03*
Y1121522D03*
X688999Y1124869D03*
Y1114829D03*
X696441Y1141601D03*
Y1134908D03*
X688999Y1144948D03*
Y1138255D03*
Y1131562D03*
X696441Y1158333D03*
Y1148294D03*
X688999Y1161680D03*
X689999Y1151641D03*
X696441Y1171719D03*
Y1165026D03*
X688999Y1175066D03*
Y1168373D03*
X696441Y1185105D03*
Y1178412D03*
X688999Y1188452D03*
Y1181759D03*
X696441Y1208530D03*
Y1201837D03*
Y1195144D03*
X688999Y1205184D03*
Y1198491D03*
X696441Y1221916D03*
Y1215223D03*
X688999Y1218570D03*
X689799Y1225263D03*
X688999Y1211877D03*
X696441Y1238648D03*
Y1231955D03*
X688999Y1241995D03*
Y1235302D03*
X688916Y1256964D03*
X696441Y1245341D03*
X688999Y1248688D03*
X686146Y1273364D03*
X683346D03*
X709999Y770144D03*
X705141Y766798D03*
X709999Y783530D03*
Y776837D03*
X705141Y773491D03*
Y780184D03*
X709999Y800263D03*
Y793570D03*
X705141Y803609D03*
Y796916D03*
Y790223D03*
X709999Y820341D03*
Y813648D03*
Y806955D03*
X705141Y816995D03*
Y810302D03*
X709999Y830381D03*
X705141Y833727D03*
Y827034D03*
Y847113D03*
X709999Y850459D03*
Y843766D03*
Y837074D03*
X705141Y840420D03*
Y863845D03*
Y853806D03*
X709999Y867192D03*
Y857152D03*
X705141Y883924D03*
Y877231D03*
Y870538D03*
X709999Y880577D03*
Y873885D03*
X705141Y900656D03*
Y890617D03*
X709999Y893963D03*
Y887270D03*
X705141Y914042D03*
Y907349D03*
X709999Y917389D03*
Y910696D03*
Y904003D03*
X705141Y927428D03*
Y920735D03*
X709999Y930774D03*
Y924081D03*
X705141Y944160D03*
Y937467D03*
X709999Y947507D03*
Y940814D03*
X705141Y960892D03*
Y950853D03*
X709999Y964239D03*
Y954200D03*
X705141Y980971D03*
Y974278D03*
Y967585D03*
X709999Y977625D03*
Y970932D03*
X705141Y987664D03*
X709999Y991011D03*
Y984318D03*
X705141Y1027822D03*
Y1017782D03*
X709999Y1031168D03*
Y1024475D03*
Y1017782D03*
X705141Y1047900D03*
Y1041207D03*
Y1034515D03*
X709999Y1044554D03*
Y1037861D03*
X705141Y1054593D03*
Y1061286D03*
X709999Y1057940D03*
Y1051247D03*
X705141Y1074672D03*
Y1067979D03*
X709999Y1078018D03*
Y1071326D03*
Y1064633D03*
X705141Y1091404D03*
Y1084711D03*
X709999Y1094751D03*
Y1088058D03*
X705141Y1111483D03*
Y1104790D03*
Y1098097D03*
X709999Y1108137D03*
Y1101444D03*
X705141Y1128215D03*
Y1121522D03*
X709999Y1124869D03*
Y1114829D03*
X705141Y1141601D03*
Y1134908D03*
X709999Y1144948D03*
Y1138255D03*
Y1131562D03*
X705141Y1158333D03*
Y1148294D03*
X709999Y1161680D03*
Y1151641D03*
X705141Y1171719D03*
Y1165026D03*
X709999Y1175066D03*
Y1168373D03*
X705141Y1185105D03*
Y1178412D03*
X709999Y1188452D03*
Y1181759D03*
X705141Y1208530D03*
Y1201837D03*
Y1195144D03*
X709999Y1205184D03*
Y1198491D03*
X705141Y1221916D03*
Y1215223D03*
X709999Y1225263D03*
Y1218570D03*
Y1211877D03*
X705141Y1238648D03*
Y1231955D03*
X709999Y1241995D03*
Y1235302D03*
X705141Y1245341D03*
X709999Y1248688D03*
X713046Y1273364D03*
X702146D03*
X699346D03*
X726141Y766798D03*
X718699Y770144D03*
X726141Y773491D03*
Y780184D03*
X718699Y783530D03*
Y776837D03*
X726141Y803609D03*
Y796916D03*
Y790223D03*
X718699Y800263D03*
Y793570D03*
X726141Y816995D03*
Y810302D03*
X718699Y820341D03*
Y813648D03*
Y806955D03*
X726141Y833727D03*
Y827034D03*
X718699Y830381D03*
X726141Y847113D03*
Y840420D03*
X718699Y850459D03*
Y843766D03*
Y837074D03*
X726141Y863845D03*
Y853806D03*
X718699Y867192D03*
Y857152D03*
X726141Y883924D03*
Y877231D03*
Y870538D03*
X718699Y880577D03*
Y873885D03*
X726141Y900656D03*
Y890617D03*
X718699Y893963D03*
Y887270D03*
X726141Y914042D03*
Y907349D03*
X718699Y917389D03*
Y910696D03*
Y904003D03*
X726141Y927428D03*
Y920735D03*
X718699Y930774D03*
Y924081D03*
X726141Y944160D03*
Y937467D03*
X718699Y947507D03*
Y940814D03*
X726141Y960892D03*
Y950853D03*
X718699Y964239D03*
Y954200D03*
X726141Y980971D03*
Y974278D03*
Y967585D03*
X718699Y977625D03*
Y970932D03*
X726141Y987664D03*
X718699Y991011D03*
Y984318D03*
X726141Y1027822D03*
Y1017782D03*
X718699Y1031168D03*
Y1024475D03*
Y1017782D03*
X726141Y1047900D03*
Y1041207D03*
Y1034515D03*
X718699Y1044554D03*
Y1037861D03*
X726141Y1061286D03*
Y1054593D03*
X718699Y1057940D03*
Y1051247D03*
X726141Y1074672D03*
Y1067979D03*
X718699Y1078018D03*
Y1071326D03*
Y1064633D03*
X726141Y1091404D03*
Y1084711D03*
X718699Y1094751D03*
Y1088058D03*
X726141Y1111483D03*
Y1104790D03*
Y1098097D03*
X718699Y1108137D03*
Y1101444D03*
X726141Y1128215D03*
Y1121522D03*
X718699Y1124869D03*
Y1114829D03*
X726141Y1141601D03*
Y1134908D03*
X718699Y1144948D03*
Y1138255D03*
Y1131562D03*
X726141Y1158333D03*
Y1148294D03*
X718699Y1161680D03*
Y1151641D03*
X726141Y1171719D03*
Y1165026D03*
X718699Y1175066D03*
Y1168373D03*
X726141Y1185105D03*
Y1178412D03*
X718699Y1188452D03*
Y1181759D03*
X726141Y1208530D03*
Y1201837D03*
Y1195144D03*
X718699Y1205184D03*
Y1198491D03*
X726141Y1221916D03*
Y1215223D03*
X718699Y1225263D03*
Y1218570D03*
Y1211877D03*
X726141Y1238648D03*
Y1231955D03*
X718699Y1241995D03*
Y1235302D03*
X726141Y1245341D03*
X719046Y1257064D03*
X718699Y1248688D03*
X729046Y1273364D03*
X715846D03*
X739699Y770144D03*
X734841Y766798D03*
X739699Y783530D03*
Y776837D03*
X734841Y773491D03*
Y780184D03*
X739699Y800263D03*
Y793570D03*
X734841Y803609D03*
Y796916D03*
Y790223D03*
X739699Y820341D03*
Y813648D03*
Y806955D03*
X734841Y816995D03*
Y810302D03*
X739699Y830381D03*
X734841Y833727D03*
Y827034D03*
X739699Y850459D03*
Y843766D03*
Y837074D03*
X734841Y847113D03*
Y840420D03*
X739699Y867192D03*
Y857152D03*
X734841Y863845D03*
Y853806D03*
X739699Y880577D03*
Y873885D03*
X734841Y883924D03*
Y877231D03*
Y870538D03*
X739699Y893963D03*
Y887270D03*
X734841Y900656D03*
Y890617D03*
X739699Y917389D03*
Y910696D03*
Y904003D03*
X734841Y914042D03*
Y907349D03*
X739699Y930774D03*
Y924081D03*
X734841Y927428D03*
Y920735D03*
X739699Y947507D03*
Y940814D03*
X734841Y944160D03*
Y937467D03*
X739699Y964239D03*
Y954200D03*
X734841Y960892D03*
Y950853D03*
X739699Y977625D03*
Y970932D03*
X734841Y980971D03*
Y974278D03*
Y967585D03*
X739699Y991011D03*
Y984318D03*
X734841Y987664D03*
X739699Y1031168D03*
Y1024475D03*
Y1017782D03*
X734841Y1027822D03*
Y1017782D03*
X739699Y1044554D03*
Y1037861D03*
X734841Y1047900D03*
Y1041207D03*
Y1034515D03*
X739699Y1057940D03*
Y1051247D03*
X734841Y1061286D03*
Y1054593D03*
X739699Y1078018D03*
Y1071326D03*
Y1064633D03*
X734841Y1074672D03*
Y1067979D03*
X739699Y1094751D03*
Y1088058D03*
X734841Y1091404D03*
Y1084711D03*
X739699Y1108137D03*
Y1101444D03*
X734841Y1111483D03*
Y1104790D03*
Y1098097D03*
X739699Y1124869D03*
Y1114829D03*
X734841Y1128215D03*
Y1121522D03*
X739699Y1144948D03*
Y1138255D03*
Y1131562D03*
X734841Y1141601D03*
Y1134908D03*
X739699Y1161680D03*
Y1151641D03*
X734841Y1158333D03*
Y1148294D03*
X739699Y1175066D03*
Y1168373D03*
X734841Y1171719D03*
Y1165026D03*
X739699Y1188452D03*
Y1181759D03*
X734841Y1185105D03*
Y1178412D03*
X739699Y1205184D03*
Y1198491D03*
X734841Y1208530D03*
Y1201837D03*
Y1195144D03*
X739699Y1225263D03*
Y1218570D03*
Y1211877D03*
X734841Y1221916D03*
Y1215223D03*
X739699Y1241995D03*
Y1235302D03*
X734841Y1238648D03*
Y1231955D03*
X739699Y1248688D03*
X734841Y1245341D03*
X745546Y1273364D03*
X742746D03*
X731372Y1273464D03*
X755841Y766798D03*
X748399Y770144D03*
X755841Y780184D03*
Y773491D03*
X748399Y783530D03*
Y776837D03*
X755841Y803609D03*
Y796916D03*
Y790223D03*
X748399Y800263D03*
Y793570D03*
X755841Y816995D03*
Y810302D03*
X748399Y820341D03*
Y813648D03*
Y806955D03*
X755841Y833727D03*
Y827034D03*
X748399Y830381D03*
X755841Y847113D03*
Y840420D03*
X748399Y850459D03*
Y843766D03*
Y837074D03*
X755841Y863845D03*
Y853806D03*
X748399Y867192D03*
Y857152D03*
X755841Y883924D03*
Y877231D03*
Y870538D03*
X748399Y880577D03*
Y873885D03*
X755841Y900656D03*
Y890617D03*
X748399Y893963D03*
Y887270D03*
X755841Y914042D03*
Y907349D03*
X748399Y917389D03*
Y910696D03*
Y904003D03*
X755841Y927428D03*
Y920735D03*
X748399Y930774D03*
Y924081D03*
X755841Y944160D03*
Y937467D03*
X748399Y947507D03*
Y940814D03*
X755841Y960892D03*
Y950853D03*
X748399Y964239D03*
Y954200D03*
X755841Y980971D03*
Y974278D03*
Y967585D03*
X748399Y977625D03*
Y970932D03*
X755841Y987664D03*
X748399Y991011D03*
Y984318D03*
X755841Y1027822D03*
Y1017782D03*
X748399Y1031168D03*
Y1024475D03*
Y1017782D03*
X755841Y1047900D03*
Y1041207D03*
Y1034515D03*
X748399Y1044554D03*
Y1037861D03*
X755841Y1054593D03*
Y1061286D03*
X748399Y1057940D03*
X755841Y1067979D03*
Y1074672D03*
X748399Y1078018D03*
Y1071326D03*
Y1064633D03*
X755841Y1084711D03*
Y1091404D03*
X748399Y1094751D03*
Y1088058D03*
X755841Y1111483D03*
Y1104790D03*
Y1098097D03*
X748399Y1108137D03*
Y1101444D03*
X755841Y1128215D03*
Y1121522D03*
X748399Y1124869D03*
Y1114829D03*
X755841Y1141601D03*
Y1134908D03*
X748399Y1144948D03*
Y1138255D03*
Y1131562D03*
X755841Y1158333D03*
Y1148294D03*
X748399Y1161680D03*
Y1151641D03*
X755841Y1171719D03*
Y1165026D03*
X748399Y1175066D03*
Y1168373D03*
X755841Y1185105D03*
Y1178412D03*
X748399Y1188452D03*
Y1181759D03*
X755841Y1208530D03*
Y1201837D03*
Y1195144D03*
X748399Y1205184D03*
Y1198491D03*
X755841Y1221916D03*
Y1215223D03*
X748399Y1225263D03*
Y1218570D03*
Y1211877D03*
X755841Y1238648D03*
Y1231955D03*
X748399Y1241995D03*
Y1235302D03*
X755841Y1245341D03*
X748283Y1256964D03*
X748399Y1248688D03*
X758746Y1273364D03*
X761546D03*
X769399Y770144D03*
X778099D03*
X764541Y766798D03*
X769399Y783530D03*
X778099D03*
X769399Y776837D03*
X778099D03*
X764541Y780184D03*
Y773491D03*
X769399Y800263D03*
X778099D03*
X769399Y793570D03*
X778099D03*
X764541Y803609D03*
Y796916D03*
Y790223D03*
X769399Y820341D03*
X778099D03*
X769399Y813648D03*
X778099D03*
X769399Y806955D03*
X778099D03*
X764541Y816995D03*
Y810302D03*
X769399Y830381D03*
X778099D03*
X764541Y833727D03*
Y827034D03*
X769399Y850459D03*
X778099D03*
Y843766D03*
X769399D03*
Y837074D03*
X778099D03*
X764541Y847113D03*
Y840420D03*
X778099Y867192D03*
X769399D03*
Y857152D03*
X778099D03*
X764541Y863845D03*
Y853806D03*
X769399Y880577D03*
X778099D03*
X769399Y873885D03*
X778099D03*
X764541Y883924D03*
Y877231D03*
Y870538D03*
X778099Y893963D03*
X769399D03*
Y887270D03*
X778099D03*
X764541Y900656D03*
Y890617D03*
X769399Y917389D03*
X778099D03*
X769399Y910696D03*
X778099D03*
X769399Y904003D03*
X778099D03*
X764541Y914042D03*
Y907349D03*
X769399Y930774D03*
X778099D03*
X769399Y924081D03*
X778099D03*
X764541Y927428D03*
Y920735D03*
X769399Y947507D03*
X778099D03*
X769399Y940814D03*
X778099D03*
X764541Y944160D03*
Y937467D03*
X769399Y964239D03*
X778099D03*
X769399Y954200D03*
X778099D03*
X764541Y960892D03*
Y950853D03*
X769399Y977625D03*
X778099D03*
X769399Y970932D03*
X778099D03*
X764541Y980971D03*
Y974278D03*
Y967585D03*
X769399Y991011D03*
X778099D03*
X769399Y984318D03*
X778099D03*
X764541Y987664D03*
X769399Y1031168D03*
X778099D03*
X769399Y1024475D03*
X778099D03*
X769399Y1017782D03*
X778099D03*
X764541Y1027822D03*
Y1017782D03*
X778099Y1044554D03*
X769399D03*
Y1037861D03*
X778099D03*
X764541Y1047900D03*
Y1041207D03*
Y1034515D03*
X769399Y1057940D03*
X778099D03*
X769399Y1051247D03*
X778099D03*
X764541Y1054593D03*
Y1061286D03*
X778099Y1078018D03*
X769399D03*
X778099Y1071326D03*
X769399D03*
Y1064633D03*
X778099D03*
X764541Y1067979D03*
Y1074672D03*
X778099Y1094751D03*
X769399D03*
X778099Y1088058D03*
X769399D03*
X764541Y1084711D03*
Y1091404D03*
X778099Y1108137D03*
X769399D03*
X778099Y1101444D03*
X769399D03*
X764541Y1111483D03*
Y1104790D03*
Y1098097D03*
X778099Y1124869D03*
X769399D03*
X778099Y1114829D03*
X769399D03*
X764541Y1128215D03*
Y1121522D03*
X778099Y1144948D03*
X769399D03*
X778099Y1138255D03*
X769399D03*
X778099Y1131562D03*
X769399D03*
X764541Y1141601D03*
Y1134908D03*
X778099Y1161680D03*
X769399D03*
X778099Y1151641D03*
X769399D03*
X764541Y1158333D03*
Y1148294D03*
X778099Y1175066D03*
X769399D03*
X778099Y1168373D03*
X769399D03*
X764541Y1171719D03*
Y1165026D03*
X778099Y1188452D03*
X769399D03*
X778099Y1181759D03*
X769399D03*
X764541Y1185105D03*
Y1178412D03*
X769399Y1205184D03*
X778099D03*
Y1198491D03*
X769399D03*
X764541Y1208530D03*
Y1201837D03*
Y1195144D03*
X778099Y1225263D03*
X769399D03*
X778099Y1218570D03*
X769399D03*
Y1211877D03*
X778099D03*
X764541Y1221916D03*
Y1215223D03*
X778099Y1241995D03*
X769399D03*
X778099Y1235302D03*
X769399D03*
X764541Y1238648D03*
Y1231955D03*
X778346Y1257264D03*
X778099Y1248688D03*
X769399D03*
X764541Y1245341D03*
X772446Y1273364D03*
X775246D03*
X785541Y766798D03*
X794241D03*
X785541Y773491D03*
X794241D03*
X785541Y780184D03*
X794241D03*
X785541Y803609D03*
X794241D03*
X785541Y790223D03*
X794241D03*
X785541Y796916D03*
X794241D03*
X785541Y816995D03*
X794241D03*
X785541Y810302D03*
X794241D03*
X785541Y833727D03*
X794241D03*
X785541Y827034D03*
X794241D03*
X785541Y840420D03*
X794241D03*
X785541Y847113D03*
X794241D03*
X785541Y853806D03*
X794241D03*
X785541Y863845D03*
X794241D03*
X785541Y883924D03*
X794241D03*
X785541Y870538D03*
X794241D03*
X785541Y877231D03*
X794241D03*
X785541Y900656D03*
X794241D03*
X785541Y890617D03*
X794241D03*
X785541Y907349D03*
X794241D03*
X785541Y914042D03*
X794241D03*
X785541Y920735D03*
X794241D03*
X785541Y927428D03*
X794241D03*
X785541Y937467D03*
X794241D03*
X785541Y944160D03*
X794241D03*
X785541Y960892D03*
X794241D03*
X785541Y950853D03*
X794241D03*
X785541Y980971D03*
X794241D03*
X785541Y974278D03*
X794241D03*
X785541Y967585D03*
X794241D03*
X785541Y987664D03*
X794241D03*
X785541Y1027822D03*
X794241D03*
X785541Y1017782D03*
X794241D03*
X785541Y1047900D03*
X794241D03*
X785541Y1041207D03*
X794241D03*
X785541Y1034515D03*
X794241D03*
X785541Y1054593D03*
X794241D03*
X785541Y1061286D03*
X794241D03*
X785541Y1074672D03*
X794241D03*
X785541Y1067979D03*
X794241D03*
X785541Y1091404D03*
X794241D03*
X785541Y1084711D03*
X794241D03*
X785541Y1111483D03*
X794241D03*
X785541Y1104790D03*
X794241D03*
X785541Y1098097D03*
X794241D03*
X785541Y1128215D03*
X794241D03*
X785541Y1121522D03*
X794241D03*
X785541Y1141601D03*
X794241D03*
X785541Y1134908D03*
X794241D03*
X785541Y1158333D03*
X794241D03*
X785541Y1148294D03*
X794241D03*
X785541Y1171719D03*
X794241D03*
X785541Y1165026D03*
X794241D03*
X785541Y1178412D03*
X794241D03*
X785541Y1185105D03*
X794241D03*
X785541Y1208530D03*
X794241D03*
X785541Y1195144D03*
X794241D03*
X785541Y1201837D03*
X794241D03*
X785541Y1221916D03*
X794241D03*
X785541Y1215223D03*
X794241D03*
X785541Y1238648D03*
X794241D03*
X785541Y1231955D03*
X794241D03*
X785541Y1245341D03*
X794241D03*
X788446Y1273364D03*
X791246D03*
X799099Y770144D03*
X807799D03*
X799099Y783530D03*
X807799D03*
X799099Y776837D03*
X807799D03*
X799099Y800263D03*
X807799D03*
X799099Y793570D03*
X807799D03*
X799099Y820341D03*
X807799D03*
X799099Y806955D03*
X807799D03*
X799099Y813648D03*
X807799D03*
X799099Y830381D03*
X807799D03*
X799099Y850459D03*
X807799D03*
X799099Y837074D03*
X807799D03*
X799099Y843766D03*
X807799D03*
X799099Y867192D03*
X807799D03*
X799099Y857152D03*
X807799D03*
X799099Y873885D03*
X807799D03*
X799099Y880577D03*
X807799D03*
X799099Y887270D03*
X807799D03*
X799099Y893963D03*
X807799D03*
X799099Y917389D03*
X807799D03*
X799099Y904003D03*
X807799D03*
X799099Y910696D03*
X807799D03*
X799099Y930774D03*
X807799D03*
X799099Y924081D03*
X807799D03*
X799099Y947507D03*
X807799D03*
X799099Y940814D03*
X807799D03*
X799099Y964239D03*
X807799D03*
X799099Y954200D03*
X807799D03*
X799099Y970932D03*
X807799D03*
X799099Y977625D03*
X807799D03*
X799099Y991011D03*
X807799D03*
X799099Y984318D03*
X807799D03*
X799099Y1031168D03*
X807799D03*
X799099Y1024475D03*
X807799D03*
X799099Y1017782D03*
X807799D03*
X799099Y1037861D03*
X807799D03*
X799099Y1044554D03*
X807799D03*
X799099Y1057940D03*
X807799D03*
X799099Y1051247D03*
X807799D03*
X799099Y1078018D03*
X807799D03*
X799099Y1071326D03*
X807799D03*
X799099Y1064633D03*
X807799D03*
X799099Y1094751D03*
X807799D03*
X799099Y1088058D03*
X807799D03*
X799099Y1108137D03*
X807799D03*
X799099Y1101444D03*
X807799D03*
X799099Y1124869D03*
X807799D03*
X799099Y1114829D03*
X807799D03*
X799099Y1144948D03*
X807799D03*
X799099Y1138255D03*
X807799D03*
X799099Y1131562D03*
X807799D03*
X799099Y1161680D03*
X807799D03*
X799099Y1151641D03*
X807799D03*
X799099Y1175066D03*
X807799D03*
X799099Y1168373D03*
X807799D03*
X799099Y1188452D03*
X807799D03*
X799099Y1181759D03*
X807799D03*
X799099Y1205184D03*
X807799D03*
X799099Y1198491D03*
X807799D03*
X799099Y1225263D03*
X807799D03*
X799099Y1211877D03*
X807799D03*
X799099Y1218570D03*
X807799D03*
X799099Y1241995D03*
X807799D03*
X799099Y1235302D03*
X807799D03*
X799099Y1248688D03*
X807799D03*
X808046Y1257664D03*
X804946Y1273364D03*
X802146D03*
X815241Y766798D03*
X823941D03*
X815241Y773491D03*
X823941D03*
X815241Y780184D03*
X823941D03*
X815241Y803609D03*
X823941D03*
X815241Y790223D03*
X823941D03*
X815241Y796916D03*
X823941D03*
X815241Y816995D03*
X823941D03*
X815241Y810302D03*
X823941D03*
X815241Y833727D03*
X823941D03*
X815241Y827034D03*
X823941D03*
X815241Y840420D03*
X823941D03*
X815241Y847113D03*
X823941D03*
X815241Y853806D03*
X823941D03*
X815241Y863845D03*
X823941D03*
X815241Y883924D03*
X823941D03*
X815241Y870538D03*
X823941D03*
X815241Y877231D03*
X823941D03*
X815241Y900656D03*
X823941D03*
X815241Y890617D03*
X823941D03*
X815241Y907349D03*
X823941D03*
X815241Y914042D03*
X823941D03*
X815241Y920735D03*
X823941D03*
X815241Y927428D03*
X823941D03*
X815241Y937467D03*
X823941D03*
X815241Y944160D03*
X823941D03*
X815241Y960892D03*
X823941D03*
X815241Y950853D03*
X823941D03*
X815241Y980971D03*
X823941D03*
X815241Y974278D03*
X823941D03*
X815241Y967585D03*
X823941D03*
X815241Y987664D03*
X823941D03*
X815241Y1027822D03*
X823941D03*
X815241Y1017782D03*
X823941D03*
X815241Y1047900D03*
X823941D03*
X815241Y1041207D03*
X823941D03*
X815241Y1034515D03*
X823941D03*
X815241Y1054593D03*
X823941D03*
X815241Y1061286D03*
X823941D03*
X815241Y1074672D03*
X823941D03*
X815241Y1067979D03*
X823941D03*
X815241Y1091404D03*
X823941D03*
X815241Y1084711D03*
X823941D03*
X815241Y1111483D03*
X823941D03*
X815241Y1104790D03*
X823941D03*
X815241Y1098097D03*
X823941D03*
X815241Y1128215D03*
X823941D03*
X815241Y1121522D03*
X823941D03*
X815241Y1141601D03*
X823941D03*
X815241Y1134908D03*
X823941D03*
X815241Y1158333D03*
X823941D03*
X815241Y1148294D03*
X823941D03*
X815241Y1171719D03*
X823941D03*
X815241Y1165026D03*
X823941D03*
X815241Y1178412D03*
X823941D03*
X815241Y1185105D03*
X823941D03*
X815241Y1208530D03*
X823941D03*
X815241Y1195144D03*
X823941D03*
X815241Y1201837D03*
X823941D03*
X815241Y1221916D03*
X823941D03*
X815241Y1215223D03*
X823941D03*
X815241Y1238648D03*
X823941D03*
X815241Y1231955D03*
X823941D03*
X815241Y1245341D03*
X823941D03*
X820946Y1273364D03*
X818146D03*
X828799Y770144D03*
X837499D03*
X828799Y783530D03*
X837499D03*
X828799Y776837D03*
X837499D03*
Y800263D03*
X828799D03*
X837499Y793570D03*
X828799D03*
Y820341D03*
X837499D03*
X828799Y813648D03*
X837499D03*
X828799Y806955D03*
X837499D03*
X828799Y830381D03*
X837499D03*
X828799Y850459D03*
X837499D03*
X828799Y843766D03*
X837499D03*
X828799Y837074D03*
X837499D03*
X828799Y867192D03*
X837499D03*
X828799Y857152D03*
X837499D03*
X828799Y880577D03*
X837499D03*
X828799Y873885D03*
X837499D03*
X828799Y893963D03*
X837499D03*
X828799Y887270D03*
X837499D03*
X828799Y917389D03*
X837499D03*
Y904003D03*
X828799D03*
X837499Y910696D03*
X828799D03*
Y930774D03*
X837499D03*
X828799Y924081D03*
X837499D03*
X828799Y947507D03*
X837499D03*
X828799Y940814D03*
X837499D03*
X828799Y964239D03*
X837499D03*
X828799Y954200D03*
X837499D03*
X828799Y977625D03*
X837499D03*
X828799Y970932D03*
X837499D03*
X828799Y991011D03*
X837499D03*
X828799Y984318D03*
X837499D03*
X828799Y1031168D03*
X837499D03*
X828799Y1024475D03*
X837499D03*
X828799Y1017782D03*
X837499D03*
X828799Y1044554D03*
X837499D03*
X828799Y1037861D03*
X837499D03*
X828799Y1057940D03*
X837499D03*
X828799Y1051247D03*
X837499D03*
X828799Y1078018D03*
X837499D03*
X828799Y1071326D03*
X837499D03*
X828799Y1064633D03*
X837499D03*
X828799Y1094751D03*
X837499D03*
Y1088058D03*
X828799D03*
X837499Y1108137D03*
X828799D03*
Y1101444D03*
X837499D03*
Y1124869D03*
X828799D03*
X837499Y1114829D03*
X828799D03*
X837499Y1144948D03*
X828799D03*
X837499Y1138255D03*
X828799D03*
X837499Y1131562D03*
X828799D03*
X837499Y1161680D03*
X828799D03*
X837499Y1151641D03*
X828799D03*
X837499Y1175066D03*
X828799D03*
X837499Y1168373D03*
X828799D03*
Y1188452D03*
X837499D03*
Y1181759D03*
X828799D03*
X837499Y1205184D03*
X828799D03*
X837499Y1198491D03*
X828799D03*
X837499Y1225263D03*
X828799D03*
X837499Y1218570D03*
X828799D03*
X837499Y1211877D03*
X828799D03*
X837499Y1241995D03*
X828799D03*
X837499Y1235302D03*
X828799D03*
X837499Y1248688D03*
X828799D03*
X837846Y1256964D03*
X839246Y1273064D03*
X842046D03*
X831846Y1273364D03*
X834646D03*
X844941Y766798D03*
X853641D03*
X844941Y780184D03*
X853641D03*
X844941Y773491D03*
X853641D03*
X844941Y803609D03*
X853641D03*
X844941Y796916D03*
X853641D03*
X844941Y790223D03*
X853641D03*
X844941Y816995D03*
X853641D03*
X844941Y810302D03*
X853641D03*
X844941Y833727D03*
X853641D03*
X844941Y827034D03*
X853641D03*
X844941Y847113D03*
X853641D03*
X844941Y840420D03*
X853641D03*
X844941Y863845D03*
X853641D03*
X844941Y853806D03*
X853641D03*
X844941Y883924D03*
X853641D03*
X844941Y877231D03*
X853641D03*
X844941Y870538D03*
X853641D03*
X844941Y900656D03*
X853641D03*
X844941Y890617D03*
X853641D03*
X844941Y914042D03*
X853641D03*
X844941Y907349D03*
X853641D03*
X844941Y927428D03*
X853641D03*
X844941Y920735D03*
X853641D03*
X844941Y944160D03*
X853641D03*
X844941Y937467D03*
X853641D03*
X844941Y960892D03*
X853641D03*
X844941Y950853D03*
X853641D03*
X844941Y980971D03*
X853641D03*
X844941Y974278D03*
X853641D03*
X844941Y967585D03*
X853641D03*
X844941Y987664D03*
X853641D03*
X844941Y1027822D03*
X853641D03*
X844941Y1017782D03*
X853641D03*
X844941Y1047900D03*
X853641D03*
X844941Y1041207D03*
X853641D03*
X844941Y1034515D03*
X853641D03*
X844941Y1061286D03*
X853641D03*
X844941Y1054593D03*
X853641D03*
X844941Y1074672D03*
X853641D03*
X844941Y1067979D03*
X853641D03*
X844941Y1091404D03*
X853641D03*
X844941Y1084711D03*
X853641D03*
X844941Y1111483D03*
X853641D03*
X844941Y1104790D03*
X853641D03*
X844941Y1098097D03*
X853641D03*
X844941Y1128215D03*
X853641D03*
X844941Y1121522D03*
X853641D03*
X844941Y1141601D03*
X853641D03*
X844941Y1134908D03*
X853641D03*
X844941Y1158333D03*
X853641D03*
X844941Y1148294D03*
X853641D03*
X844941Y1171719D03*
X853641D03*
X844941Y1165026D03*
X853641D03*
X844941Y1185105D03*
X853641D03*
X844941Y1178412D03*
X853641D03*
X844941Y1208530D03*
X853641D03*
X844941Y1201837D03*
X853641D03*
X844941Y1195144D03*
X853641D03*
X844941Y1221916D03*
X853641D03*
X844941Y1215223D03*
X853641D03*
X844941Y1238648D03*
X853641D03*
X844941Y1231955D03*
X853641D03*
X844941Y1245341D03*
X853641D03*
X1003841Y770144D03*
Y783530D03*
Y776837D03*
Y800263D03*
Y793570D03*
Y820341D03*
Y813648D03*
Y806955D03*
Y830381D03*
Y850459D03*
Y843766D03*
Y837074D03*
Y867192D03*
Y857152D03*
Y880577D03*
Y873885D03*
Y893963D03*
Y887270D03*
Y917389D03*
Y910696D03*
Y904003D03*
Y930774D03*
Y924081D03*
Y947507D03*
Y940814D03*
Y964239D03*
Y954200D03*
Y977625D03*
Y970932D03*
Y991011D03*
Y984318D03*
Y1031168D03*
Y1024475D03*
Y1017782D03*
Y1044554D03*
Y1037861D03*
Y1057940D03*
Y1051247D03*
Y1078018D03*
Y1071326D03*
Y1064633D03*
Y1094751D03*
Y1088058D03*
Y1108137D03*
Y1101444D03*
Y1124869D03*
Y1114829D03*
Y1144948D03*
Y1138255D03*
Y1131562D03*
Y1161680D03*
Y1151641D03*
Y1175066D03*
Y1168373D03*
Y1188452D03*
Y1181759D03*
Y1205184D03*
Y1198491D03*
Y1225263D03*
Y1218570D03*
Y1211877D03*
Y1241995D03*
Y1235302D03*
Y1248688D03*
X1019983Y766798D03*
X1012541Y770144D03*
X1019983Y780184D03*
Y773491D03*
X1012541Y783530D03*
Y776837D03*
X1019983Y803609D03*
Y796916D03*
Y790223D03*
X1012541Y800263D03*
Y793570D03*
X1019983Y816995D03*
Y810302D03*
X1012541Y820341D03*
Y813648D03*
Y806955D03*
X1019983Y833727D03*
Y827034D03*
X1012541Y830381D03*
X1019983Y847113D03*
Y840420D03*
X1012541Y850459D03*
Y843766D03*
Y837074D03*
X1019983Y863845D03*
Y853806D03*
X1012541Y867192D03*
Y857152D03*
X1019983Y883924D03*
Y877231D03*
Y870538D03*
X1012541Y880577D03*
Y873885D03*
X1019983Y900656D03*
Y890617D03*
X1012541Y893963D03*
Y887270D03*
X1019983Y914042D03*
Y907349D03*
X1012541Y917389D03*
Y910696D03*
Y904003D03*
X1019983Y927428D03*
Y920735D03*
X1012541Y930774D03*
Y924081D03*
X1019983Y944160D03*
Y937467D03*
X1012541Y947507D03*
Y940814D03*
X1019983Y960892D03*
Y950853D03*
X1012541Y964239D03*
Y954200D03*
X1019983Y980971D03*
Y974278D03*
Y967585D03*
X1012541Y977625D03*
Y970932D03*
X1019983Y987664D03*
X1012541Y991011D03*
Y984318D03*
X1019983Y1027822D03*
Y1017782D03*
X1012541Y1031168D03*
Y1024475D03*
Y1017782D03*
X1019983Y1047900D03*
Y1041207D03*
Y1034515D03*
X1012541Y1044554D03*
Y1037861D03*
X1019983Y1061286D03*
Y1054593D03*
X1012541Y1057940D03*
Y1051247D03*
X1019983Y1067979D03*
Y1074672D03*
X1012541Y1078018D03*
Y1071326D03*
Y1064633D03*
X1019983Y1091404D03*
Y1084711D03*
X1012541Y1094751D03*
Y1088058D03*
X1019983Y1111483D03*
Y1104790D03*
Y1098097D03*
X1012541Y1108137D03*
Y1101444D03*
X1019983Y1128215D03*
Y1121522D03*
X1012541Y1124869D03*
Y1114829D03*
X1019983Y1141601D03*
Y1134908D03*
X1012541Y1144948D03*
Y1138255D03*
Y1131562D03*
X1019983Y1158333D03*
Y1148294D03*
X1012541Y1161680D03*
Y1151641D03*
X1019983Y1171719D03*
Y1165026D03*
X1012541Y1175066D03*
Y1168373D03*
X1019983Y1185105D03*
Y1178412D03*
X1012541Y1188452D03*
Y1181759D03*
X1019983Y1208530D03*
Y1201837D03*
Y1195144D03*
X1012541Y1205184D03*
Y1198491D03*
X1019983Y1221916D03*
Y1215223D03*
X1012541Y1225263D03*
Y1218570D03*
Y1211877D03*
X1019983Y1238648D03*
Y1231955D03*
X1012541Y1241995D03*
Y1235302D03*
X1012543Y1257198D03*
X1019983Y1245341D03*
X1012541Y1248688D03*
X1017111Y1273299D03*
X1014111D03*
X1033541Y770144D03*
X1028683Y766798D03*
X1033541Y783530D03*
Y776837D03*
X1028683Y780184D03*
Y773491D03*
X1033541Y800263D03*
Y793570D03*
X1028683Y803609D03*
Y796916D03*
Y790223D03*
X1033541Y820341D03*
Y813648D03*
Y806955D03*
X1028683Y816995D03*
Y810302D03*
X1033541Y830381D03*
X1028683Y833727D03*
Y827034D03*
X1033541Y850459D03*
Y843766D03*
Y837074D03*
X1028683Y847113D03*
Y840420D03*
X1033541Y867192D03*
Y857152D03*
X1028683Y863845D03*
Y853806D03*
X1033541Y880577D03*
Y873885D03*
X1028683Y883924D03*
Y877231D03*
Y870538D03*
X1033541Y893963D03*
Y887270D03*
X1028683Y900656D03*
Y890617D03*
X1033541Y917389D03*
Y910696D03*
Y904003D03*
X1028683Y914042D03*
Y907349D03*
X1033541Y930774D03*
Y924081D03*
X1028683Y927428D03*
Y920735D03*
X1033541Y947507D03*
Y940814D03*
X1028683Y944160D03*
Y937467D03*
X1033541Y964239D03*
Y954200D03*
X1028683Y960892D03*
Y950853D03*
X1033541Y977625D03*
Y970932D03*
X1028683Y980971D03*
Y974278D03*
Y967585D03*
X1033541Y991011D03*
Y984318D03*
X1028683Y987664D03*
X1033541Y1031168D03*
Y1017782D03*
Y1024475D03*
X1028683Y1027822D03*
Y1017782D03*
X1033541Y1044554D03*
Y1037861D03*
X1028683Y1047900D03*
Y1041207D03*
Y1034515D03*
X1033541Y1057940D03*
Y1051247D03*
X1028683Y1061286D03*
Y1054593D03*
X1033541Y1078018D03*
Y1071326D03*
Y1064633D03*
X1028683Y1067979D03*
Y1074672D03*
X1033541Y1094751D03*
Y1088058D03*
X1028683Y1091404D03*
Y1084711D03*
X1033541Y1108137D03*
Y1101444D03*
X1028683Y1111483D03*
Y1104790D03*
Y1098097D03*
X1033541Y1114829D03*
Y1124869D03*
X1028683Y1128215D03*
Y1121522D03*
X1033541Y1144948D03*
Y1138255D03*
Y1131562D03*
X1028683Y1141601D03*
Y1134908D03*
X1033541Y1161680D03*
Y1151641D03*
X1028683Y1158333D03*
Y1148294D03*
X1033541Y1175066D03*
Y1168373D03*
X1028683Y1171719D03*
Y1165026D03*
X1033541Y1188452D03*
Y1181759D03*
X1028683Y1185105D03*
Y1178412D03*
X1033541Y1205184D03*
Y1198491D03*
X1028683Y1208530D03*
Y1201837D03*
Y1195144D03*
X1033541Y1225263D03*
Y1218570D03*
Y1211877D03*
X1028683Y1221916D03*
Y1215223D03*
X1033541Y1241995D03*
Y1235302D03*
X1028683Y1238648D03*
Y1231955D03*
X1033541Y1248688D03*
X1028683Y1245341D03*
X1036588Y1273344D03*
X1022888D03*
X1025688D03*
X1049683Y766798D03*
X1042241Y770144D03*
X1049683Y780184D03*
Y773491D03*
X1042241Y783530D03*
Y776837D03*
X1049683Y803609D03*
Y796916D03*
Y790223D03*
X1042241Y800263D03*
Y793570D03*
X1049683Y816995D03*
Y810302D03*
X1042241Y820341D03*
Y813648D03*
Y806955D03*
X1049683Y833727D03*
Y827034D03*
X1042241Y830381D03*
X1049683Y847113D03*
Y840420D03*
X1042241Y850459D03*
Y843766D03*
Y837074D03*
X1049683Y863845D03*
Y853806D03*
X1042241Y867192D03*
Y857152D03*
X1049683Y883924D03*
Y877231D03*
Y870538D03*
X1042241Y880577D03*
Y873885D03*
X1049683Y900656D03*
Y890617D03*
X1042241Y893963D03*
Y887270D03*
X1049683Y914042D03*
Y907349D03*
X1042241Y917389D03*
Y910696D03*
Y904003D03*
X1049683Y927428D03*
Y920735D03*
X1042241Y930774D03*
Y924081D03*
X1049683Y944160D03*
Y937467D03*
X1042241Y947507D03*
Y940814D03*
X1049683Y960892D03*
Y950853D03*
X1042241Y964239D03*
Y954200D03*
X1049683Y980971D03*
Y974278D03*
Y967585D03*
X1042241Y977625D03*
Y970932D03*
X1049683Y987664D03*
X1042241Y991011D03*
Y984318D03*
X1049683Y1027822D03*
Y1017782D03*
X1042241Y1031168D03*
Y1017782D03*
Y1024475D03*
X1049683Y1047900D03*
Y1041207D03*
Y1034515D03*
X1042241Y1044554D03*
Y1037861D03*
X1049683Y1061286D03*
Y1054593D03*
X1042241Y1057940D03*
Y1051247D03*
X1049683Y1074672D03*
Y1067979D03*
X1042241Y1078018D03*
Y1071326D03*
Y1064633D03*
X1049683Y1091404D03*
Y1084711D03*
X1042241Y1094751D03*
Y1088058D03*
X1049683Y1111483D03*
Y1104790D03*
Y1098097D03*
X1042241Y1108137D03*
Y1101444D03*
Y1114829D03*
X1049683Y1128215D03*
Y1121522D03*
X1042241Y1124869D03*
X1049683Y1141601D03*
Y1134908D03*
X1042241Y1144948D03*
Y1138255D03*
Y1131562D03*
Y1161680D03*
X1049683Y1158333D03*
Y1148294D03*
X1042241Y1151641D03*
X1049683Y1171719D03*
Y1165026D03*
X1042241Y1175066D03*
Y1168373D03*
X1049683Y1185105D03*
Y1178412D03*
X1042241Y1188452D03*
Y1181759D03*
X1049683Y1208530D03*
Y1201837D03*
Y1195144D03*
X1042241Y1205184D03*
Y1198491D03*
X1049683Y1215223D03*
Y1221916D03*
X1042241Y1225263D03*
Y1218570D03*
Y1211877D03*
X1049683Y1238648D03*
Y1231955D03*
X1042241Y1241995D03*
Y1235302D03*
X1042331Y1257488D03*
X1049683Y1245341D03*
X1042241Y1248688D03*
X1052588Y1273344D03*
X1039388D03*
X1063241Y770144D03*
X1058383Y766798D03*
X1063241Y783530D03*
Y776837D03*
X1058383Y780184D03*
Y773491D03*
X1063241Y800263D03*
Y793570D03*
X1058383Y803609D03*
Y796916D03*
Y790223D03*
X1063241Y820341D03*
Y813648D03*
Y806955D03*
X1058383Y816995D03*
Y810302D03*
X1063241Y830381D03*
X1058383Y833727D03*
Y827034D03*
X1063241Y850459D03*
Y843766D03*
Y837074D03*
X1058383Y847113D03*
Y840420D03*
X1063241Y867192D03*
Y857152D03*
X1058383Y863845D03*
Y853806D03*
X1063241Y880577D03*
Y873885D03*
X1058383Y883924D03*
Y877231D03*
Y870538D03*
X1063241Y893963D03*
Y887270D03*
X1058383Y900656D03*
Y890617D03*
X1063241Y917389D03*
Y910696D03*
Y904003D03*
X1058383Y914042D03*
Y907349D03*
X1063241Y930774D03*
Y924081D03*
X1058383Y927428D03*
Y920735D03*
X1063241Y947507D03*
Y940814D03*
X1058383Y944160D03*
Y937467D03*
X1063241Y964239D03*
Y954200D03*
X1058383Y960892D03*
Y950853D03*
X1063241Y977625D03*
Y970932D03*
X1058383Y980971D03*
Y974278D03*
Y967585D03*
X1063241Y991011D03*
Y984318D03*
X1058383Y987664D03*
X1063241Y1031168D03*
Y1024475D03*
Y1017782D03*
X1058383Y1027822D03*
Y1017782D03*
X1063241Y1044554D03*
Y1037861D03*
X1058383Y1047900D03*
Y1041207D03*
Y1034515D03*
X1063241Y1057940D03*
Y1051247D03*
X1058383Y1061286D03*
Y1054593D03*
X1063241Y1078018D03*
Y1071326D03*
Y1064633D03*
X1058383Y1074672D03*
Y1067979D03*
X1063241Y1094751D03*
Y1088058D03*
X1058383Y1091404D03*
Y1084711D03*
X1063241Y1108137D03*
Y1101444D03*
X1058383Y1111483D03*
Y1104790D03*
Y1098097D03*
X1063241Y1124869D03*
Y1114829D03*
X1058383Y1128215D03*
Y1121522D03*
X1063241Y1144948D03*
Y1138255D03*
Y1131562D03*
X1058383Y1141601D03*
Y1134908D03*
X1063241Y1161680D03*
Y1151641D03*
X1058383Y1158333D03*
Y1148294D03*
X1063241Y1175066D03*
Y1168373D03*
X1058383Y1171719D03*
Y1165026D03*
X1063241Y1188452D03*
Y1181759D03*
X1058383Y1185105D03*
Y1178412D03*
X1063241Y1205184D03*
Y1198491D03*
X1058383Y1208530D03*
Y1201837D03*
Y1195144D03*
X1063241Y1225263D03*
Y1218570D03*
Y1211877D03*
X1058383Y1215223D03*
Y1221916D03*
X1063241Y1241995D03*
Y1235302D03*
X1058383Y1238648D03*
Y1231955D03*
X1063241Y1248688D03*
X1058383Y1245341D03*
X1069088Y1273344D03*
X1066288D03*
X1055388D03*
X1079383Y766798D03*
X1071941Y770144D03*
X1079383Y780184D03*
Y773491D03*
X1071941Y783530D03*
Y776837D03*
X1079383Y803609D03*
Y796916D03*
Y790223D03*
X1071941Y800263D03*
Y793570D03*
X1079383Y816995D03*
Y810302D03*
X1071941Y820341D03*
Y813648D03*
Y806955D03*
X1079383Y833727D03*
Y827034D03*
X1071941Y830381D03*
X1079383Y847113D03*
Y840420D03*
X1071941Y850459D03*
Y843766D03*
Y837074D03*
X1079383Y863845D03*
Y853806D03*
X1071941Y867192D03*
Y857152D03*
X1079383Y883924D03*
Y877231D03*
Y870538D03*
X1071941Y880577D03*
Y873885D03*
X1079383Y900656D03*
Y890617D03*
X1071941Y893963D03*
Y887270D03*
X1079383Y914042D03*
Y907349D03*
X1071941Y917389D03*
Y910696D03*
Y904003D03*
X1079383Y927428D03*
Y920735D03*
X1071941Y930774D03*
Y924081D03*
X1079383Y944160D03*
Y937467D03*
X1071941Y947507D03*
Y940814D03*
X1079383Y960892D03*
Y950853D03*
X1071941Y964239D03*
Y954200D03*
X1079383Y980971D03*
Y974278D03*
Y967585D03*
X1071941Y977625D03*
Y970932D03*
X1079383Y987664D03*
X1071941Y991011D03*
Y984318D03*
X1079383Y1027822D03*
Y1017782D03*
X1071941Y1031168D03*
Y1024475D03*
Y1017782D03*
X1079383Y1047900D03*
Y1041207D03*
Y1034515D03*
X1071941Y1044554D03*
Y1037861D03*
X1079383Y1061286D03*
Y1054593D03*
X1071941Y1057940D03*
Y1051247D03*
X1079383Y1074672D03*
Y1067979D03*
X1071941Y1078018D03*
Y1071326D03*
Y1064633D03*
X1079383Y1091404D03*
Y1084711D03*
X1071941Y1094751D03*
Y1088058D03*
X1079383Y1111483D03*
Y1104790D03*
Y1098097D03*
X1071941Y1108137D03*
Y1101444D03*
X1079383Y1128215D03*
Y1121522D03*
X1071941Y1124869D03*
Y1114829D03*
X1079383Y1141601D03*
Y1134908D03*
X1071941Y1144948D03*
Y1138255D03*
Y1131562D03*
X1079383Y1158333D03*
Y1148294D03*
X1071941Y1161680D03*
Y1151641D03*
X1079383Y1171719D03*
Y1165026D03*
X1071941Y1175066D03*
Y1168373D03*
X1079383Y1185105D03*
Y1178412D03*
X1071941Y1188452D03*
Y1181759D03*
X1079383Y1208530D03*
Y1201837D03*
Y1195144D03*
X1071941Y1205184D03*
Y1198491D03*
X1079383Y1221916D03*
Y1215223D03*
X1071941Y1225263D03*
Y1218570D03*
Y1211877D03*
X1079383Y1238648D03*
Y1231955D03*
X1071941Y1241995D03*
Y1235302D03*
X1071991Y1257262D03*
X1079383Y1245341D03*
X1071941Y1248688D03*
X1085088Y1273344D03*
X1082288D03*
X1092941Y770144D03*
X1101641D03*
X1088083Y766798D03*
X1092941Y783530D03*
X1101641D03*
X1092941Y776837D03*
X1101641D03*
X1088083Y780184D03*
Y773491D03*
X1101641Y800263D03*
X1092941D03*
X1101641Y793570D03*
X1092941D03*
X1088083Y803609D03*
Y796916D03*
Y790223D03*
X1101641Y820341D03*
X1092941D03*
X1101641Y813648D03*
X1092941D03*
X1101641Y806955D03*
X1092941D03*
X1088083Y816995D03*
Y810302D03*
X1101641Y830381D03*
X1092941D03*
X1088083Y833727D03*
Y827034D03*
X1101641Y850459D03*
X1092941D03*
X1101641Y843766D03*
X1092941D03*
X1101641Y837074D03*
X1092941D03*
X1088083Y847113D03*
Y840420D03*
X1101641Y867192D03*
X1092941D03*
X1101641Y857152D03*
X1092941D03*
X1088083Y863845D03*
Y853806D03*
X1101641Y880577D03*
X1092941D03*
X1101641Y873885D03*
X1092941D03*
X1088083Y883924D03*
Y877231D03*
Y870538D03*
X1101641Y893963D03*
X1092941D03*
X1101641Y887270D03*
X1092941D03*
X1088083Y900656D03*
Y890617D03*
X1101641Y917389D03*
X1092941D03*
X1101641Y910696D03*
X1092941D03*
X1101641Y904003D03*
X1092941D03*
X1088083Y914042D03*
Y907349D03*
X1101641Y930774D03*
X1092941D03*
X1101641Y924081D03*
X1092941D03*
X1088083Y927428D03*
Y920735D03*
X1101641Y947507D03*
X1092941D03*
X1101641Y940814D03*
X1092941D03*
X1088083Y944160D03*
Y937467D03*
X1101641Y964239D03*
X1092941D03*
X1101641Y954200D03*
X1092941D03*
X1088083Y960892D03*
Y950853D03*
X1101641Y977625D03*
X1092941D03*
X1101641Y970932D03*
X1092941D03*
X1088083Y980971D03*
Y974278D03*
Y967585D03*
X1101641Y991011D03*
X1092941D03*
X1101641Y984318D03*
X1092941D03*
X1088083Y987664D03*
X1101641Y1031168D03*
X1092941D03*
X1101641Y1024475D03*
X1092941D03*
X1101641Y1017782D03*
X1092941D03*
X1088083Y1027822D03*
Y1017782D03*
X1101641Y1044554D03*
X1092941D03*
X1101641Y1037861D03*
X1092941D03*
X1088083Y1047900D03*
Y1041207D03*
Y1034515D03*
X1101641Y1057940D03*
X1092941D03*
X1101641Y1051247D03*
X1092941D03*
X1088083Y1061286D03*
Y1054593D03*
X1101641Y1078018D03*
X1092941D03*
X1101641Y1071326D03*
X1092941D03*
X1101641Y1064633D03*
X1092941D03*
X1088083Y1074672D03*
Y1067979D03*
X1101641Y1094751D03*
X1092941D03*
X1101641Y1088058D03*
X1092941D03*
X1088083Y1091404D03*
Y1084711D03*
X1101641Y1108137D03*
X1092941D03*
X1101641Y1101444D03*
X1092941D03*
X1088083Y1111483D03*
Y1104790D03*
Y1098097D03*
X1101641Y1124869D03*
X1092941D03*
X1101641Y1114829D03*
X1092941D03*
X1088083Y1128215D03*
Y1121522D03*
X1101641Y1144948D03*
X1092941D03*
X1101641Y1138255D03*
X1092941D03*
X1101641Y1131562D03*
X1092941D03*
X1088083Y1141601D03*
Y1134908D03*
X1092941Y1161680D03*
X1101641D03*
Y1151641D03*
X1092941D03*
X1088083Y1158333D03*
Y1148294D03*
X1101641Y1175066D03*
X1092941D03*
X1101641Y1168373D03*
X1092941D03*
X1088083Y1171719D03*
Y1165026D03*
X1101641Y1181759D03*
X1092941D03*
Y1188452D03*
X1101641D03*
X1088083Y1185105D03*
Y1178412D03*
X1092941Y1205184D03*
X1101641D03*
X1092941Y1198491D03*
X1101641D03*
X1088083Y1208530D03*
Y1201837D03*
Y1195144D03*
X1101641Y1225263D03*
X1092941D03*
X1101641Y1218570D03*
X1092941D03*
Y1211877D03*
X1101641D03*
X1088083Y1221916D03*
Y1215223D03*
X1101641Y1241995D03*
X1092941D03*
X1101641Y1235302D03*
X1092941D03*
X1088083Y1238648D03*
Y1231955D03*
X1101554Y1257102D03*
X1101641Y1248688D03*
X1092941D03*
X1088083Y1245341D03*
X1098788Y1273344D03*
X1095988D03*
X1109083Y766798D03*
X1117783D03*
Y780184D03*
X1109083D03*
X1117783Y773491D03*
X1109083D03*
X1117783Y803609D03*
X1109083D03*
X1117783Y796916D03*
X1109083D03*
Y790223D03*
X1117783D03*
Y816995D03*
X1109083D03*
X1117783Y810302D03*
X1109083D03*
X1117783Y833727D03*
X1109083D03*
X1117783Y827034D03*
X1109083D03*
X1117783Y847113D03*
X1109083D03*
X1117783Y840420D03*
X1109083D03*
X1117783Y863845D03*
X1109083D03*
X1117783Y853806D03*
X1109083D03*
X1117783Y883924D03*
X1109083D03*
X1117783Y877231D03*
X1109083D03*
X1117783Y870538D03*
X1109083D03*
X1117783Y900656D03*
X1109083D03*
X1117783Y890617D03*
X1109083D03*
X1117783Y914042D03*
X1109083D03*
X1117783Y907349D03*
X1109083D03*
X1117783Y927428D03*
X1109083D03*
X1117783Y920735D03*
X1109083D03*
X1117783Y944160D03*
X1109083D03*
X1117783Y937467D03*
X1109083D03*
X1117783Y960892D03*
X1109083D03*
X1117783Y950853D03*
X1109083D03*
X1117783Y980971D03*
X1109083D03*
X1117783Y974278D03*
X1109083D03*
X1117783Y967585D03*
X1109083D03*
X1117783Y987664D03*
X1109083D03*
X1117783Y1027822D03*
X1109083D03*
X1117783Y1017782D03*
X1109083D03*
X1117783Y1047900D03*
X1109083D03*
X1117783Y1041207D03*
X1109083D03*
X1117783Y1034515D03*
X1109083D03*
X1117783Y1061286D03*
X1109083D03*
X1117783Y1054593D03*
X1109083D03*
X1117783Y1074672D03*
X1109083D03*
X1117783Y1067979D03*
X1109083D03*
X1117783Y1091404D03*
X1109083D03*
X1117783Y1084711D03*
X1109083D03*
X1117783Y1111483D03*
X1109083D03*
X1117783Y1104790D03*
X1109083D03*
X1117783Y1098097D03*
X1109083D03*
X1117783Y1128215D03*
X1109083D03*
X1117783Y1121522D03*
X1109083D03*
X1117783Y1141601D03*
X1109083D03*
X1117783Y1134908D03*
X1109083D03*
X1117783Y1158333D03*
X1109083D03*
X1117783Y1148294D03*
X1109083D03*
X1117783Y1171719D03*
X1109083D03*
X1117783Y1165026D03*
X1109083D03*
X1117783Y1185105D03*
X1109083D03*
X1117783Y1178412D03*
X1109083D03*
X1117783Y1208530D03*
X1109083D03*
X1117783Y1201837D03*
X1109083D03*
X1117783Y1195144D03*
X1109083D03*
X1117783Y1221916D03*
X1109083D03*
X1117783Y1215223D03*
X1109083D03*
X1117783Y1238648D03*
X1109083D03*
X1117783Y1231955D03*
X1109083D03*
X1117783Y1245341D03*
X1109083D03*
X1111988Y1273344D03*
X1114788D03*
X1131341Y770144D03*
X1122641D03*
X1131341Y783530D03*
X1122641D03*
X1131341Y776837D03*
X1122641D03*
X1131341Y800263D03*
X1122641D03*
X1131341Y793570D03*
X1122641D03*
X1131341Y820341D03*
X1122641D03*
X1131341Y813648D03*
X1122641D03*
X1131341Y806955D03*
X1122641D03*
X1131341Y830381D03*
X1122641D03*
X1131341Y850459D03*
X1122641D03*
X1131341Y843766D03*
X1122641D03*
X1131341Y837074D03*
X1122641D03*
X1131341Y867192D03*
X1122641D03*
X1131341Y857152D03*
X1122641D03*
X1131341Y880577D03*
X1122641D03*
X1131341Y873885D03*
X1122641D03*
X1131341Y893963D03*
X1122641D03*
X1131341Y887270D03*
X1122641D03*
X1131341Y917389D03*
X1122641D03*
X1131341Y910696D03*
X1122641D03*
X1131341Y904003D03*
X1122641D03*
X1131341Y930774D03*
X1122641D03*
X1131341Y924081D03*
X1122641D03*
Y947507D03*
X1131341D03*
Y940814D03*
X1122641D03*
X1131341Y964239D03*
X1122641D03*
X1131341Y954200D03*
X1122641D03*
X1131341Y977625D03*
X1122641D03*
X1131341Y970932D03*
X1122641D03*
X1131341Y991011D03*
X1122641D03*
X1131341Y984318D03*
X1122641D03*
X1131341Y1031168D03*
X1122641D03*
X1131341Y1024475D03*
X1122641D03*
X1131341Y1017782D03*
X1122641D03*
X1131341Y1044554D03*
X1122641D03*
X1131341Y1037861D03*
X1122641D03*
X1131341Y1057940D03*
X1122641D03*
X1131341Y1051247D03*
X1122641D03*
X1131341Y1078018D03*
X1122641D03*
X1131341Y1071326D03*
X1122641D03*
X1131341Y1064633D03*
X1122641D03*
X1131341Y1094751D03*
X1122641D03*
X1131341Y1088058D03*
X1122641D03*
X1131341Y1108137D03*
X1122641D03*
X1131341Y1101444D03*
X1122641D03*
X1131341Y1124869D03*
X1122641D03*
X1131341Y1114829D03*
X1122641D03*
X1131341Y1144948D03*
X1122641D03*
X1131341Y1138255D03*
X1122641D03*
X1131341Y1131562D03*
X1122641D03*
X1131341Y1161680D03*
X1122641D03*
X1131341Y1151641D03*
X1122641D03*
X1131341Y1175066D03*
X1122641D03*
X1131341Y1168373D03*
X1122641D03*
X1131341Y1188452D03*
X1122641D03*
X1131341Y1181759D03*
X1122641D03*
X1131341Y1205184D03*
X1122641D03*
X1131341Y1198491D03*
X1122641D03*
X1131341Y1225263D03*
X1122641D03*
X1131341Y1218570D03*
X1122641D03*
X1131341Y1211877D03*
X1122641D03*
X1131341Y1241995D03*
X1122641D03*
X1131341Y1235302D03*
X1122641D03*
X1131434Y1257291D03*
X1122641Y1248688D03*
X1131341D03*
X1126188Y1273344D03*
X1128988D03*
X1152341Y770144D03*
X1147483Y766798D03*
X1138783D03*
X1152341Y783530D03*
Y776837D03*
X1147483Y780184D03*
X1138783D03*
Y773491D03*
X1147483D03*
X1152341Y800263D03*
X1147483Y803609D03*
X1138783D03*
X1152341Y793570D03*
X1147483Y796916D03*
X1138783D03*
X1147483Y790223D03*
X1138783D03*
X1152341Y820341D03*
X1147483Y816995D03*
X1138783D03*
X1152341Y813648D03*
Y806955D03*
X1147483Y810302D03*
X1138783D03*
X1147483Y833727D03*
X1138783D03*
X1152341Y830381D03*
X1147483Y827034D03*
X1138783D03*
X1152341Y850459D03*
Y843766D03*
Y837074D03*
X1147483Y847113D03*
X1138783D03*
X1147483Y840420D03*
X1138783D03*
X1152341Y867192D03*
Y857152D03*
X1147483Y863845D03*
X1138783D03*
X1147483Y853806D03*
X1138783D03*
X1152341Y880577D03*
Y873885D03*
X1147483Y883924D03*
X1138783D03*
X1147483Y877231D03*
X1138783D03*
X1147483Y870538D03*
X1138783D03*
X1152341Y893963D03*
Y887270D03*
X1138783Y900656D03*
X1147483D03*
X1138783Y890617D03*
X1147483D03*
X1152341Y917389D03*
Y910696D03*
Y904003D03*
X1147483Y914042D03*
X1138783D03*
X1147483Y907349D03*
X1138783D03*
X1152341Y930774D03*
Y924081D03*
X1147483Y927428D03*
X1138783D03*
X1147483Y920735D03*
X1138783D03*
X1152341Y947507D03*
Y940814D03*
X1147483Y944160D03*
X1138783D03*
X1147483Y937467D03*
X1138783D03*
X1152341Y964239D03*
Y954200D03*
X1147483Y960892D03*
X1138783D03*
X1147483Y950853D03*
X1138783D03*
X1152341Y977625D03*
Y970932D03*
X1147483Y980971D03*
X1138783D03*
X1147483Y974278D03*
X1138783D03*
X1147483Y967585D03*
X1138783D03*
X1152341Y991011D03*
Y984318D03*
X1147483Y987664D03*
X1138783D03*
X1152341Y1031168D03*
Y1024475D03*
Y1017782D03*
X1147483Y1027822D03*
X1138783D03*
X1147483Y1017782D03*
X1138783D03*
X1152341Y1044554D03*
Y1037861D03*
X1138783Y1047900D03*
X1147483D03*
Y1041207D03*
X1138783D03*
X1147483Y1034515D03*
X1138783D03*
X1152341Y1057940D03*
Y1051247D03*
X1147483Y1061286D03*
X1138783D03*
X1147483Y1054593D03*
X1138783D03*
X1152341Y1078018D03*
Y1071326D03*
Y1064633D03*
X1147483Y1074672D03*
X1138783D03*
X1147483Y1067979D03*
X1138783D03*
X1152341Y1094751D03*
Y1088058D03*
X1147483Y1091404D03*
X1138783D03*
X1147483Y1084711D03*
X1138783D03*
X1152341Y1108137D03*
Y1101444D03*
X1147483Y1111483D03*
X1138783D03*
X1147483Y1104790D03*
X1138783D03*
X1147483Y1098097D03*
X1138783D03*
X1152341Y1124869D03*
Y1114829D03*
X1147483Y1128215D03*
X1138783D03*
X1147483Y1121522D03*
X1138783D03*
X1152341Y1144948D03*
Y1138255D03*
Y1131562D03*
X1147483Y1141601D03*
X1138783D03*
X1147483Y1134908D03*
X1138783D03*
X1152341Y1161680D03*
Y1151641D03*
X1147483Y1158333D03*
X1138783D03*
Y1148294D03*
X1147483D03*
X1152341Y1175066D03*
Y1168373D03*
X1147483Y1171719D03*
X1138783D03*
X1147483Y1165026D03*
X1138783D03*
X1152341Y1188452D03*
Y1181759D03*
X1147483Y1185105D03*
X1138783D03*
X1147483Y1178412D03*
X1138783D03*
X1152341Y1205184D03*
Y1198491D03*
X1147483Y1208530D03*
X1138783D03*
X1147483Y1201837D03*
X1138783D03*
X1147483Y1195144D03*
X1138783D03*
X1152341Y1225263D03*
Y1218570D03*
Y1211877D03*
X1147483Y1221916D03*
X1138783D03*
X1147483Y1215223D03*
X1138783D03*
X1152341Y1241995D03*
Y1235302D03*
X1147483Y1238648D03*
X1138783D03*
X1147483Y1231955D03*
X1138783D03*
X1152341Y1248688D03*
X1147483Y1245341D03*
X1138783D03*
X1152381Y1269684D03*
X1147681D03*
X1138201Y1270277D03*
X1168483Y766798D03*
X1161041Y770144D03*
X1168483Y780184D03*
Y773491D03*
X1161041Y783530D03*
Y776837D03*
X1168483Y803609D03*
Y796916D03*
Y790223D03*
X1161041Y800263D03*
Y793570D03*
X1168483Y816995D03*
Y810302D03*
X1161041Y820341D03*
Y813648D03*
Y806955D03*
X1168483Y833727D03*
X1167633Y827034D03*
X1161041Y830381D03*
X1168483Y847113D03*
Y840420D03*
X1161041Y850459D03*
Y843766D03*
Y837074D03*
X1167633Y863845D03*
X1161041Y867192D03*
X1168483Y853806D03*
X1161041Y857152D03*
X1168483Y883924D03*
Y877231D03*
Y870538D03*
X1161041Y880577D03*
Y873885D03*
X1168483Y900656D03*
Y890617D03*
X1161041Y893963D03*
Y887270D03*
X1168483Y914042D03*
Y907349D03*
X1161041Y917389D03*
Y910696D03*
Y904003D03*
X1167633Y927428D03*
X1168483Y920735D03*
X1161041Y930774D03*
Y924081D03*
X1168483Y937467D03*
Y944160D03*
X1161041Y947507D03*
Y940814D03*
X1168483Y960892D03*
Y950853D03*
X1161041Y964239D03*
Y954200D03*
X1168483Y974278D03*
Y980971D03*
Y967585D03*
X1161041Y977625D03*
Y970932D03*
X1168483Y987664D03*
X1161041Y991011D03*
Y984318D03*
X1168483Y1027822D03*
Y1017782D03*
X1161041Y1031168D03*
Y1024475D03*
Y1017782D03*
X1168483Y1047900D03*
Y1041207D03*
Y1034515D03*
X1161041Y1044554D03*
Y1037861D03*
X1168483Y1054593D03*
Y1061286D03*
X1161041Y1057940D03*
Y1051247D03*
X1168483Y1074672D03*
Y1067979D03*
X1161041Y1078018D03*
Y1071326D03*
Y1064633D03*
X1168483Y1091404D03*
X1167633Y1084711D03*
X1161041Y1094751D03*
Y1088058D03*
X1168483Y1111483D03*
Y1104790D03*
Y1098097D03*
X1161041Y1108137D03*
Y1101444D03*
X1168483Y1128215D03*
Y1121522D03*
X1161041Y1124869D03*
Y1114829D03*
X1168483Y1141601D03*
Y1134908D03*
X1161041Y1144948D03*
Y1138255D03*
Y1131562D03*
X1167633Y1158333D03*
X1168483Y1148294D03*
X1161041Y1161680D03*
Y1151641D03*
X1168483Y1171719D03*
Y1165026D03*
X1161041Y1175066D03*
Y1168373D03*
X1168483Y1185105D03*
Y1178412D03*
X1161041Y1188452D03*
Y1181759D03*
X1168483Y1208530D03*
Y1201837D03*
Y1195144D03*
X1161041Y1205184D03*
Y1198491D03*
X1168483Y1221916D03*
Y1215223D03*
X1161041Y1225263D03*
Y1218570D03*
Y1211877D03*
X1168483Y1238648D03*
X1167633Y1231955D03*
X1161041Y1241995D03*
Y1235302D03*
X1161065Y1258871D03*
X1168483Y1245341D03*
X1161041Y1248688D03*
X1161781Y1269684D03*
X1182041Y770144D03*
X1177183Y766798D03*
X1182041Y783530D03*
Y776837D03*
X1177183Y780184D03*
Y773491D03*
X1182041Y800263D03*
Y793570D03*
X1177183Y803609D03*
Y796916D03*
Y790223D03*
X1182041Y813648D03*
Y806955D03*
X1181191Y820341D03*
X1177183Y816995D03*
Y810302D03*
X1181191Y830381D03*
X1177183Y833727D03*
Y827034D03*
X1182041Y850459D03*
Y837074D03*
Y843766D03*
X1177183Y847113D03*
Y840420D03*
X1181191Y867192D03*
X1177183Y863845D03*
X1181191Y857152D03*
X1177183Y853806D03*
X1182041Y873885D03*
Y880577D03*
X1177183Y883924D03*
Y877231D03*
Y870538D03*
X1182041Y893963D03*
Y887270D03*
X1177183Y900656D03*
Y890617D03*
X1182041Y917389D03*
Y910696D03*
Y904003D03*
X1177183Y914042D03*
Y907349D03*
X1181191Y930774D03*
Y924081D03*
X1177183Y927428D03*
Y920735D03*
X1182041Y940814D03*
Y947507D03*
X1177183Y937467D03*
Y944160D03*
X1182041Y964239D03*
Y954200D03*
X1177183Y960892D03*
Y950853D03*
X1182041Y970932D03*
Y977625D03*
X1177183Y974278D03*
Y980971D03*
Y967585D03*
X1182041Y991011D03*
Y984318D03*
X1177183Y987664D03*
X1182041Y1031168D03*
Y1017782D03*
Y1024475D03*
X1177183Y1027822D03*
Y1017782D03*
X1182041Y1044554D03*
Y1037861D03*
X1177183Y1047900D03*
Y1041207D03*
Y1034515D03*
X1182041Y1057940D03*
Y1051247D03*
X1177183Y1054593D03*
Y1061286D03*
X1181191Y1078018D03*
X1182041Y1071326D03*
Y1064633D03*
X1177183Y1074672D03*
Y1067979D03*
X1182041Y1094751D03*
X1181191Y1088058D03*
X1177183Y1091404D03*
Y1084711D03*
X1182041Y1101444D03*
Y1108137D03*
X1177183Y1111483D03*
Y1104790D03*
Y1098097D03*
X1182041Y1114829D03*
Y1124869D03*
X1177183Y1128215D03*
Y1121522D03*
X1182041Y1144948D03*
Y1138255D03*
Y1131562D03*
X1177183Y1141601D03*
Y1134908D03*
X1181191Y1161680D03*
Y1151641D03*
X1177183Y1158333D03*
Y1148294D03*
X1182041Y1168373D03*
Y1175066D03*
X1177183Y1171719D03*
Y1165026D03*
X1182041Y1188452D03*
Y1181759D03*
X1177183Y1185105D03*
Y1178412D03*
X1182041Y1205184D03*
Y1198491D03*
X1177183Y1208530D03*
Y1201837D03*
Y1195144D03*
X1181191Y1225263D03*
X1182041Y1211877D03*
Y1218570D03*
X1177183Y1221916D03*
Y1215223D03*
X1182041Y1241995D03*
X1181191Y1235302D03*
X1177183Y1238648D03*
Y1231955D03*
X1182041Y1248688D03*
X1177183Y1245341D03*
X1176867Y1270029D03*
X1198183Y766798D03*
X1190741Y770144D03*
X1198183Y780184D03*
Y773491D03*
X1190741Y783530D03*
Y776837D03*
X1198183Y803609D03*
Y796916D03*
Y790223D03*
X1190741Y800263D03*
Y793570D03*
X1197333Y816995D03*
X1198183Y810302D03*
X1190741Y813648D03*
Y806955D03*
X1191591Y820341D03*
X1198183Y833727D03*
X1197333Y827034D03*
X1191591Y830381D03*
X1198183Y847113D03*
Y840420D03*
X1190741Y850459D03*
Y837074D03*
Y843766D03*
X1197333Y863845D03*
X1191591Y867192D03*
X1198183Y853806D03*
X1191591Y857152D03*
X1198183Y877231D03*
X1197333Y870538D03*
X1198183Y883924D03*
X1190741Y873885D03*
Y880577D03*
X1198183Y900656D03*
Y890617D03*
X1190741Y893963D03*
Y887270D03*
X1198183Y914042D03*
Y907349D03*
X1190741Y917389D03*
Y910696D03*
Y904003D03*
X1197383Y927428D03*
X1198183Y920735D03*
X1191591Y930774D03*
Y924081D03*
X1198183Y944160D03*
X1197333Y937467D03*
X1190741Y940814D03*
Y947507D03*
X1198183Y960892D03*
Y950853D03*
X1190741Y964239D03*
Y954200D03*
X1198183Y980971D03*
Y974278D03*
Y967585D03*
X1190741Y970932D03*
Y977625D03*
X1198183Y987664D03*
X1190741Y991011D03*
Y984318D03*
X1198183Y1027822D03*
Y1017782D03*
X1190741Y1031168D03*
Y1017782D03*
Y1024475D03*
X1198183Y1047900D03*
Y1041207D03*
Y1034515D03*
X1190741Y1044554D03*
Y1037861D03*
X1198183Y1054593D03*
Y1061286D03*
X1190741Y1057940D03*
Y1051247D03*
X1197333Y1074672D03*
X1198183Y1067979D03*
X1191591Y1078018D03*
X1190741Y1071326D03*
Y1064633D03*
X1198183Y1091404D03*
X1197333Y1084711D03*
X1190741Y1094751D03*
X1191591Y1088058D03*
X1198183Y1111483D03*
Y1098097D03*
Y1104790D03*
X1190741Y1101444D03*
Y1108137D03*
X1198183Y1128215D03*
Y1121522D03*
X1190741Y1114829D03*
Y1124869D03*
X1198183Y1141601D03*
X1197333Y1134908D03*
X1190741Y1144948D03*
Y1138255D03*
Y1131562D03*
X1198183Y1158333D03*
X1197333Y1148294D03*
X1191591Y1161680D03*
Y1151641D03*
X1198183Y1165026D03*
Y1171719D03*
X1190741Y1168373D03*
Y1175066D03*
X1198183Y1185105D03*
Y1178412D03*
X1190741Y1188452D03*
Y1181759D03*
X1198183Y1208530D03*
Y1201837D03*
Y1195144D03*
X1190741Y1205184D03*
Y1198491D03*
X1198183Y1221916D03*
Y1215223D03*
X1191591Y1225263D03*
X1190741Y1211877D03*
Y1218570D03*
X1197333Y1238648D03*
Y1231955D03*
X1190741Y1241995D03*
X1191591Y1235302D03*
X1198183Y1245341D03*
X1190966Y1258711D03*
X1190741Y1248688D03*
X1191538Y1270004D03*
X1194572Y1578182D03*
Y1590094D03*
X1199872Y1614292D03*
Y1602380D03*
X1211741Y770144D03*
X1206883Y766798D03*
X1211741Y783530D03*
Y776837D03*
X1206883Y780184D03*
Y773491D03*
X1211741Y800263D03*
Y793570D03*
X1206883Y803609D03*
Y796916D03*
Y790223D03*
X1210891Y820341D03*
Y813648D03*
X1211741Y806955D03*
X1207148Y817554D03*
X1206883Y810302D03*
X1211741Y830381D03*
X1206883Y833727D03*
X1207733Y827034D03*
X1211741Y850459D03*
Y837074D03*
Y843766D03*
X1206883Y847113D03*
Y840420D03*
X1210891Y867492D03*
X1207733Y863845D03*
X1210891Y857152D03*
X1206883Y853806D03*
X1211741Y874185D03*
Y880577D03*
X1206883Y877231D03*
X1207201Y871084D03*
X1206883Y883924D03*
X1211741Y893963D03*
Y887270D03*
X1206883Y900656D03*
Y890617D03*
X1211741Y917389D03*
Y910696D03*
Y904003D03*
X1206883Y914042D03*
Y907349D03*
X1211741Y930774D03*
Y924081D03*
X1207683Y927428D03*
X1206883Y920735D03*
X1211741Y947507D03*
X1211001Y940814D03*
X1206883Y944660D03*
X1207733Y937467D03*
X1211741Y964239D03*
Y954200D03*
X1206883Y960892D03*
Y950853D03*
X1211741Y977625D03*
Y970932D03*
X1206883Y980971D03*
Y974278D03*
Y967585D03*
X1211741Y991011D03*
X1206883Y987664D03*
X1211741Y984318D03*
Y1031168D03*
X1206883Y1027822D03*
Y1017782D03*
X1211741D03*
Y1024475D03*
Y1044554D03*
Y1037861D03*
X1206883Y1047900D03*
Y1041207D03*
Y1034515D03*
X1211741Y1051247D03*
Y1057940D03*
X1206883Y1054593D03*
Y1061286D03*
X1210891Y1078018D03*
X1211741Y1064633D03*
Y1071326D03*
X1207733Y1074672D03*
X1206883Y1067979D03*
X1211741Y1094751D03*
X1210891Y1088058D03*
X1206883Y1091404D03*
Y1084711D03*
X1211741Y1108137D03*
Y1101444D03*
X1206883Y1111483D03*
Y1098097D03*
Y1104790D03*
X1210891Y1124869D03*
X1211741Y1114829D03*
X1206883Y1128215D03*
Y1121522D03*
X1211741Y1144948D03*
Y1138255D03*
X1210891Y1131562D03*
X1206883Y1141601D03*
X1207733Y1134908D03*
X1211741Y1151641D03*
Y1161680D03*
X1206883Y1158333D03*
X1207733Y1148294D03*
X1211741Y1175066D03*
Y1168373D03*
X1206883Y1165026D03*
Y1171719D03*
X1211741Y1188452D03*
Y1181759D03*
X1206883Y1185105D03*
Y1178412D03*
X1211741Y1205184D03*
Y1198491D03*
X1206883Y1208530D03*
Y1201837D03*
Y1195144D03*
X1210891Y1225263D03*
X1211741Y1218570D03*
Y1211877D03*
X1206883Y1221916D03*
Y1215223D03*
X1211741Y1241995D03*
X1211328Y1234977D03*
X1207733Y1238648D03*
Y1231955D03*
X1206883Y1245341D03*
X1211741Y1248688D03*
X1204608Y1273119D03*
X1202043Y1273123D03*
X1202372Y1578182D03*
X1214432D03*
X1206632D03*
X1202372Y1590094D03*
X1214432D03*
X1206632D03*
X1207672Y1602380D03*
Y1614292D03*
X1211932D03*
Y1602380D03*
X1227883Y766798D03*
X1220441Y770144D03*
X1227883Y780184D03*
Y773491D03*
X1220441Y783530D03*
Y776837D03*
X1227883Y803609D03*
Y796916D03*
Y790223D03*
X1220441Y800263D03*
Y793570D03*
X1227033Y816995D03*
X1227883Y810302D03*
X1221291Y820341D03*
Y813648D03*
X1220441Y806955D03*
X1227883Y833727D03*
X1227033Y827034D03*
X1220441Y830381D03*
X1227883Y847113D03*
Y840420D03*
X1220441Y850459D03*
Y837074D03*
Y843766D03*
X1227033Y863845D03*
X1221291Y867192D03*
X1227033Y853806D03*
X1221291Y857152D03*
X1227883Y870538D03*
Y883924D03*
Y877231D03*
X1220441Y873885D03*
Y880577D03*
X1227033Y900656D03*
X1227883Y890617D03*
X1220441Y893963D03*
Y887270D03*
X1227883Y914042D03*
Y907349D03*
X1220441Y917389D03*
Y910696D03*
Y904003D03*
X1227033Y927428D03*
X1227883Y920735D03*
X1221291Y930774D03*
X1220441Y924081D03*
X1227883Y944160D03*
X1227033Y937467D03*
X1220441Y947507D03*
X1221291Y940814D03*
X1227883Y960892D03*
Y950853D03*
X1220441Y964239D03*
Y954200D03*
X1227883Y974278D03*
Y967585D03*
X1220441Y977625D03*
Y970932D03*
X1227883Y980971D03*
Y987664D03*
X1220441Y991011D03*
Y984318D03*
X1227883Y1027822D03*
X1220441Y1031168D03*
X1227883Y1017782D03*
X1220441D03*
Y1024475D03*
X1227883Y1047900D03*
Y1041207D03*
Y1034515D03*
X1220441Y1044554D03*
Y1037861D03*
X1227883Y1061286D03*
Y1054593D03*
X1220441Y1051247D03*
Y1057940D03*
X1227033Y1074672D03*
Y1067979D03*
X1221291Y1078018D03*
X1220441Y1064633D03*
Y1071326D03*
X1227883Y1091404D03*
Y1084711D03*
X1220441Y1094751D03*
X1221291Y1088058D03*
X1227883Y1104790D03*
X1227033Y1111483D03*
X1227883Y1098097D03*
X1220441Y1108137D03*
Y1101444D03*
X1227883Y1128215D03*
X1227033Y1121522D03*
X1221291Y1124869D03*
X1220441Y1114829D03*
X1227883Y1134908D03*
Y1141601D03*
X1220441Y1144948D03*
Y1138255D03*
X1221291Y1131562D03*
X1227883Y1158333D03*
Y1148294D03*
X1220441Y1151641D03*
Y1161680D03*
X1227883Y1171719D03*
Y1165026D03*
X1220441Y1175066D03*
Y1168373D03*
X1227883Y1185105D03*
Y1178412D03*
X1220441Y1188452D03*
Y1181759D03*
X1227883Y1208530D03*
Y1201837D03*
X1227033Y1195144D03*
X1220441Y1205184D03*
Y1198491D03*
X1227033Y1221916D03*
X1227883Y1215223D03*
X1221291Y1225263D03*
X1220441Y1218570D03*
Y1211877D03*
X1227883Y1238648D03*
X1227033Y1231955D03*
X1220441Y1241995D03*
X1221291Y1235302D03*
X1220441Y1248688D03*
X1227883Y1245341D03*
X1220601Y1269684D03*
X1220931Y1260093D03*
X1233327Y1274515D03*
X1231377Y1275855D03*
X1218692Y1578182D03*
X1226492D03*
X1230752D03*
X1218692Y1590094D03*
X1226492D03*
X1230752D03*
X1219732Y1614292D03*
Y1602380D03*
X1231792Y1614292D03*
Y1602380D03*
X1223992D03*
Y1614292D03*
X1236583Y766798D03*
Y780184D03*
Y773491D03*
Y803609D03*
Y796916D03*
Y790223D03*
X1237433Y816995D03*
X1236583Y810302D03*
Y833727D03*
X1237433Y827034D03*
X1236583Y847113D03*
Y840420D03*
X1237433Y863845D03*
Y853806D03*
X1236583Y870538D03*
Y883924D03*
Y877231D03*
Y900656D03*
Y890617D03*
Y914042D03*
Y907349D03*
X1237433Y927428D03*
X1236583Y920735D03*
Y944160D03*
X1237433Y937467D03*
X1236583Y960892D03*
Y950853D03*
Y974278D03*
Y967585D03*
Y980971D03*
Y987664D03*
Y1027822D03*
Y1017782D03*
Y1047900D03*
Y1041207D03*
Y1034515D03*
Y1061286D03*
Y1054593D03*
X1237433Y1074672D03*
Y1067979D03*
X1236583Y1091404D03*
Y1084711D03*
Y1104790D03*
X1237433Y1111483D03*
X1236583Y1098097D03*
Y1128215D03*
X1237433Y1121522D03*
X1236583Y1134908D03*
Y1141601D03*
Y1158333D03*
Y1148294D03*
Y1171719D03*
Y1165026D03*
Y1185105D03*
Y1178412D03*
Y1208530D03*
Y1201837D03*
Y1195144D03*
X1237433Y1221916D03*
X1236583Y1215223D03*
Y1238648D03*
X1237433Y1231955D03*
X1236583Y1245341D03*
X1238552Y1578182D03*
X1242812D03*
X1238552Y1590094D03*
X1242812D03*
X1236052Y1602380D03*
Y1614292D03*
X1243852D03*
Y1602380D03*
X1248112D03*
Y1614292D03*
X1241142Y1675383D03*
Y1679920D03*
X1249016Y1679320D03*
X1241142Y1684454D03*
Y1689556D03*
Y1694093D03*
Y1698627D03*
X1249016Y1688391D03*
Y1693493D03*
Y1698030D03*
Y1683857D03*
X1241142Y1703729D03*
Y1708266D03*
Y1712800D03*
X1249016Y1707666D03*
Y1712203D03*
Y1702564D03*
X1241142Y1726974D03*
Y1722440D03*
Y1717903D03*
X1249016Y1730911D03*
Y1726377D03*
Y1721840D03*
Y1716737D03*
X1250612Y1578182D03*
X1262672D03*
X1254872D03*
X1250612Y1590094D03*
X1262672D03*
X1254872D03*
X1255912Y1614292D03*
Y1602380D03*
X1260172D03*
Y1614292D03*
X1256890Y1675383D03*
Y1679920D03*
X1264764Y1679320D03*
X1256890Y1684454D03*
Y1689556D03*
Y1694093D03*
Y1698627D03*
X1264764Y1688391D03*
Y1693493D03*
Y1698030D03*
Y1683857D03*
X1256890Y1703729D03*
Y1708266D03*
Y1712800D03*
X1264764Y1707666D03*
Y1712203D03*
Y1702564D03*
X1256890Y1726974D03*
Y1722440D03*
Y1717903D03*
X1264764Y1730911D03*
Y1726377D03*
Y1721840D03*
Y1716737D03*
X1266932Y1578182D03*
X1274732D03*
X1278992D03*
X1266932Y1590094D03*
X1274732D03*
X1278992D03*
X1267972Y1614292D03*
Y1602380D03*
X1272232D03*
Y1614292D03*
X1280032D03*
Y1602380D03*
X1272638Y1675383D03*
Y1679920D03*
X1280512Y1679320D03*
X1272638Y1684454D03*
Y1689556D03*
Y1694093D03*
Y1698627D03*
X1280512Y1688391D03*
Y1693493D03*
Y1698030D03*
Y1683857D03*
X1272638Y1703729D03*
Y1708266D03*
Y1712800D03*
X1280512Y1707666D03*
Y1712203D03*
Y1702564D03*
X1272638Y1726974D03*
Y1722440D03*
Y1717903D03*
X1280512Y1730911D03*
Y1726377D03*
Y1721840D03*
Y1716737D03*
X1286792Y1578182D03*
X1298852D03*
X1291052D03*
X1286792Y1590094D03*
X1298852D03*
X1291052D03*
X1284292Y1602380D03*
Y1614292D03*
X1292092D03*
Y1602380D03*
X1296352D03*
Y1614292D03*
X1296260Y1679320D03*
X1288386Y1675383D03*
Y1679920D03*
X1296260Y1688391D03*
Y1693493D03*
Y1698030D03*
Y1683857D03*
X1288386Y1684454D03*
Y1689556D03*
Y1694093D03*
Y1698627D03*
X1296260Y1707666D03*
Y1712203D03*
Y1702564D03*
X1288386Y1703729D03*
Y1708266D03*
Y1712800D03*
X1296260Y1730911D03*
Y1726377D03*
Y1721840D03*
Y1716737D03*
X1288386Y1726974D03*
Y1722440D03*
Y1717903D03*
X1314353Y1124651D03*
X1303112Y1578182D03*
X1310912D03*
X1315172D03*
X1303112Y1590094D03*
X1310912D03*
X1315172D03*
X1304152Y1602380D03*
Y1614292D03*
X1308412Y1602380D03*
Y1614292D03*
X1308071Y1675383D03*
Y1679920D03*
Y1684454D03*
Y1689556D03*
Y1694093D03*
Y1698627D03*
Y1703729D03*
Y1708266D03*
Y1712800D03*
Y1726974D03*
Y1722440D03*
Y1717903D03*
X1328721Y854584D03*
X1323171Y870606D03*
Y889832D03*
X1319849Y1091513D03*
X1318053Y1124651D03*
X1321753Y1131060D03*
X1322972Y1578182D03*
X1327232D03*
X1322972Y1590094D03*
X1327232D03*
X1316212Y1614292D03*
Y1602380D03*
X1328272D03*
Y1614292D03*
X1320472Y1602380D03*
Y1614292D03*
X1323819Y1675383D03*
Y1679920D03*
X1315945Y1679320D03*
X1323819Y1684454D03*
Y1689556D03*
Y1694093D03*
Y1698627D03*
X1315945Y1688391D03*
Y1693493D03*
Y1698030D03*
Y1683857D03*
X1323819Y1703729D03*
Y1708266D03*
Y1712800D03*
X1315945Y1707666D03*
Y1712203D03*
Y1702564D03*
X1323819Y1726974D03*
Y1722440D03*
Y1717903D03*
X1315945Y1730911D03*
Y1726377D03*
Y1721840D03*
Y1716737D03*
X1336121Y880219D03*
Y899445D03*
X1347220D03*
X1336121Y918670D03*
X1341671Y941100D03*
X1336121Y937896D03*
X1347220D03*
X1345804Y1006093D03*
X1342104Y1076587D03*
X1335032Y1578182D03*
X1347092D03*
X1339292D03*
X1335032Y1590094D03*
X1347092D03*
X1339292D03*
X1340332Y1602380D03*
Y1614292D03*
X1332532Y1602380D03*
Y1614292D03*
X1344592Y1602380D03*
Y1614292D03*
X1339567Y1675383D03*
Y1679920D03*
X1331693Y1679320D03*
X1347441D03*
X1339567Y1684454D03*
Y1689556D03*
Y1694093D03*
Y1698627D03*
X1331693Y1688391D03*
Y1693493D03*
Y1698030D03*
Y1683857D03*
X1347441Y1688391D03*
Y1693493D03*
Y1698030D03*
Y1683857D03*
X1339567Y1703729D03*
Y1708266D03*
Y1712800D03*
X1331693Y1707666D03*
Y1712203D03*
Y1702564D03*
X1347441Y1707666D03*
Y1712203D03*
Y1702564D03*
X1339567Y1726974D03*
Y1722440D03*
Y1717903D03*
X1331693Y1730911D03*
Y1726377D03*
Y1721840D03*
Y1716737D03*
X1347441Y1730911D03*
Y1726377D03*
Y1721840D03*
Y1716737D03*
X1354620Y931488D03*
X1355053Y1060565D03*
X1351352Y1578182D03*
X1359152D03*
X1363412D03*
X1351352Y1590094D03*
X1359152D03*
X1363412D03*
X1352392Y1602380D03*
Y1614292D03*
X1356652Y1602380D03*
Y1614292D03*
X1363189Y1679320D03*
X1355315Y1675383D03*
Y1679920D03*
X1363189Y1688391D03*
Y1693493D03*
Y1698030D03*
Y1683857D03*
X1355315Y1684454D03*
Y1689556D03*
Y1694093D03*
Y1698627D03*
X1363189Y1707666D03*
Y1712203D03*
Y1702564D03*
X1355315Y1703729D03*
Y1708266D03*
Y1712800D03*
X1363189Y1730911D03*
Y1726377D03*
Y1721840D03*
Y1716737D03*
X1355315Y1726974D03*
Y1722440D03*
Y1717903D03*
X1373120Y899445D03*
Y931488D03*
Y937896D03*
X1371212Y1578088D03*
X1375472Y1578182D03*
X1371212Y1590094D03*
X1375472D03*
X1364452Y1602380D03*
Y1614292D03*
X1376512Y1602286D03*
Y1614292D03*
X1368712Y1602380D03*
Y1614292D03*
X1393716Y985579D03*
X1391326D03*
Y1014539D03*
X1393716D03*
X1393903Y1115039D03*
X1392053Y1118243D03*
X1390203Y1121447D03*
X1388353Y1124651D03*
Y1118243D03*
X1390204Y1134264D03*
X1388354Y1131060D03*
X1383272Y1578182D03*
Y1590094D03*
X1380772Y1602380D03*
Y1614292D03*
X1388572D03*
Y1602380D03*
X1411971Y851380D03*
Y864197D03*
Y877014D03*
Y889832D03*
Y902649D03*
X1404571Y921875D03*
X1410121Y944304D03*
Y957122D03*
Y950713D03*
Y963530D03*
Y976347D03*
Y969939D03*
Y982756D03*
X1410553Y1009297D03*
Y1002888D03*
Y1028523D03*
Y1022114D03*
Y1015705D03*
X1405004Y1044544D03*
X1410553Y1034931D03*
X1406854Y1047749D03*
X1399453D03*
X1408703Y1050952D03*
X1401304Y1057361D03*
X1410553Y1060565D03*
Y1054157D03*
X1408703Y1076587D03*
X1406853Y1073383D03*
X1403153D03*
Y1066974D03*
X1401304Y1076587D03*
X1399453Y1066974D03*
X1410553Y1073383D03*
Y1066974D03*
X1403154Y1079791D03*
X1410553D03*
X1408703Y1089404D03*
Y1082995D03*
X1405003D03*
X1401304Y1089404D03*
X1410553Y1092608D03*
Y1086200D03*
X1408703Y1095813D03*
X1405003D03*
X1403153Y1099017D03*
X1401303Y1102221D03*
X1399453Y1105426D03*
X1397604Y1108630D03*
X1410553Y1105426D03*
X1399453Y1111834D03*
X1410553D03*
X1399453Y1124651D03*
Y1118243D03*
X1397604Y1115039D03*
X1410553Y1124651D03*
Y1118243D03*
X1399454Y1137469D03*
X1399453Y1131060D03*
X1410554Y1137769D03*
X1410553Y1131060D03*
X1426771Y851380D03*
Y877014D03*
X1413820Y912262D03*
X1423070Y941100D03*
X1423071Y947509D03*
Y960326D03*
Y953917D03*
Y966735D03*
Y979552D03*
Y973143D03*
X1423503Y1006093D03*
Y999684D03*
Y1012501D03*
Y1025318D03*
Y1018910D03*
Y1031727D03*
X1429053Y1041340D03*
X1423503Y1038136D03*
X1429053Y1092608D03*
X1427204Y1089404D03*
X1427203Y1095812D03*
X1429053Y1099017D03*
X1423503Y1108630D03*
Y1102221D03*
Y1121447D03*
Y1115039D03*
Y1127856D03*
Y1134264D03*
X1432320Y912262D03*
X1437871Y921875D03*
X1438402Y942151D03*
X1440702D03*
X1443002D03*
X1430564Y949138D03*
X1440015Y956539D03*
X1430564Y951438D03*
X1442413Y956539D03*
X1430534Y963828D03*
Y966128D03*
X1440015Y971139D03*
X1442413Y971099D03*
X1430404Y981208D03*
Y978908D03*
X1440015Y985579D03*
X1430604Y995298D03*
Y992998D03*
X1442413Y985579D03*
X1440015Y1014539D03*
Y1000059D03*
X1430584Y1009408D03*
Y1007108D03*
X1442413Y1014539D03*
Y1000059D03*
X1436454Y1105426D03*
X1434604Y1102221D03*
X1432753Y1099017D03*
X1440154Y1105426D03*
X1438304Y1108630D03*
X1440154Y1111834D03*
X1434604Y1121447D03*
Y1115039D03*
X1443854Y1124651D03*
X1443853Y1118243D03*
X1442004Y1121447D03*
Y1115039D03*
X1434604Y1127856D03*
Y1134264D03*
X1450820Y899445D03*
Y912262D03*
X1445703Y1115039D03*
X1447553Y1118243D03*
X1445704Y1127856D03*
X1445703Y1140973D03*
X1447554Y1137469D03*
Y1131060D03*
X1460095Y1578182D03*
Y1590094D03*
X1465620Y912262D03*
X1471604Y1108630D03*
X1469753Y1111834D03*
X1472155Y1578182D03*
X1467895D03*
X1472155Y1590094D03*
X1467895D03*
X1477455Y1602380D03*
Y1614292D03*
X1473195D03*
Y1602380D03*
X1465395D03*
Y1614292D03*
X1484120Y937896D03*
X1485971Y947509D03*
X1491953Y1086200D03*
X1492015Y1578182D03*
X1484215D03*
X1479955D03*
X1492015Y1590094D03*
X1484215D03*
X1479955D03*
X1489515Y1614292D03*
Y1602380D03*
X1485255D03*
Y1614292D03*
X1508335Y1578182D03*
X1496275D03*
X1504075D03*
X1508335Y1590094D03*
X1496275D03*
X1504075D03*
X1501575Y1614292D03*
Y1602380D03*
X1509375D03*
Y1614292D03*
X1497315Y1602380D03*
Y1614292D03*
X1505315Y1675383D03*
Y1679920D03*
Y1684454D03*
Y1689556D03*
Y1694093D03*
Y1698627D03*
Y1703729D03*
Y1708266D03*
Y1712800D03*
Y1726974D03*
Y1722440D03*
Y1717903D03*
X1511871Y928283D03*
X1519271D03*
X1515571D03*
X1524820Y925079D03*
X1513720D03*
X1524820Y944304D03*
X1513720D03*
X1520395Y1578182D03*
X1516135D03*
X1520395Y1590094D03*
X1516135D03*
X1525695Y1614292D03*
Y1602380D03*
X1521435D03*
Y1614292D03*
X1513635D03*
Y1602380D03*
X1521063Y1675383D03*
Y1679920D03*
X1513189Y1679320D03*
X1521063Y1684454D03*
Y1689556D03*
Y1694093D03*
Y1698627D03*
X1513189Y1688391D03*
Y1693493D03*
Y1698030D03*
Y1683857D03*
X1521063Y1703729D03*
Y1708266D03*
Y1712800D03*
X1513189Y1707666D03*
Y1712203D03*
Y1702564D03*
X1521063Y1726974D03*
Y1722440D03*
Y1717903D03*
X1513189Y1730911D03*
Y1726377D03*
Y1721840D03*
Y1716737D03*
X1540255Y1578182D03*
X1532455D03*
X1528195D03*
X1540255Y1590094D03*
X1532455D03*
X1528195D03*
X1537755Y1614292D03*
Y1602380D03*
X1533495D03*
Y1614292D03*
X1536811Y1675383D03*
Y1679920D03*
X1528937Y1679320D03*
X1536811Y1684454D03*
Y1689556D03*
Y1694093D03*
Y1698627D03*
X1528937Y1688391D03*
Y1693493D03*
Y1698030D03*
Y1683857D03*
X1536811Y1703729D03*
Y1708266D03*
Y1712800D03*
X1528937Y1707666D03*
Y1712203D03*
Y1702564D03*
X1536811Y1726974D03*
Y1722440D03*
Y1717903D03*
X1528937Y1730911D03*
Y1726377D03*
Y1721840D03*
Y1716737D03*
X1556575Y1578182D03*
X1544515D03*
X1552315D03*
X1556575Y1590094D03*
X1544515D03*
X1552315D03*
X1549815Y1614292D03*
Y1602380D03*
X1557615D03*
Y1614292D03*
X1545555Y1602380D03*
Y1614292D03*
X1552559Y1675383D03*
Y1679920D03*
X1544685Y1679320D03*
X1552559Y1684454D03*
Y1689556D03*
Y1694093D03*
Y1698627D03*
X1544685Y1688391D03*
Y1693493D03*
Y1698030D03*
Y1683857D03*
X1552559Y1703729D03*
Y1708266D03*
Y1712800D03*
X1544685Y1707666D03*
Y1712203D03*
Y1702564D03*
X1552559Y1726974D03*
Y1722440D03*
Y1717903D03*
X1544685Y1730911D03*
Y1726377D03*
Y1721840D03*
Y1716737D03*
X1568635Y1578182D03*
X1564375D03*
X1568635Y1590094D03*
X1564375D03*
X1573935Y1614292D03*
Y1602380D03*
X1569675Y1614292D03*
Y1602380D03*
X1561875Y1614292D03*
Y1602380D03*
X1560433Y1679320D03*
X1572244Y1675383D03*
Y1679920D03*
X1560433Y1688391D03*
Y1693493D03*
Y1698030D03*
Y1683857D03*
X1572244Y1684454D03*
Y1689556D03*
Y1694093D03*
Y1698627D03*
X1560433Y1707666D03*
Y1712203D03*
Y1702564D03*
X1572244Y1703729D03*
Y1708266D03*
Y1712800D03*
X1560433Y1730911D03*
Y1726377D03*
Y1721840D03*
Y1716737D03*
X1572244Y1726974D03*
Y1722440D03*
Y1717903D03*
X1588495Y1578182D03*
X1580695D03*
X1576435D03*
X1588495Y1590094D03*
X1580695D03*
X1576435D03*
X1585995Y1614292D03*
Y1602380D03*
X1581735D03*
Y1614292D03*
X1587992Y1675383D03*
Y1679920D03*
X1580118Y1679320D03*
X1587992Y1684454D03*
Y1689556D03*
Y1694093D03*
Y1698627D03*
X1580118Y1688391D03*
Y1693493D03*
Y1698030D03*
Y1683857D03*
X1587992Y1703729D03*
Y1708266D03*
Y1712800D03*
X1580118Y1707666D03*
Y1712203D03*
Y1702564D03*
X1587992Y1726974D03*
Y1722440D03*
Y1717903D03*
X1580118Y1730911D03*
Y1726377D03*
Y1721840D03*
Y1716737D03*
X1597041Y770144D03*
X1605741D03*
Y776837D03*
X1597041D03*
X1605741Y783530D03*
X1597041D03*
X1605741Y793570D03*
X1597041D03*
X1596988Y800263D03*
X1605741D03*
X1595774Y806955D03*
X1606934D03*
X1596218Y813648D03*
X1606735D03*
X1597041Y820341D03*
X1605741D03*
X1597041Y830381D03*
X1605741D03*
Y837074D03*
X1597041D03*
Y843766D03*
X1605741D03*
X1596147Y850459D03*
X1606896D03*
X1596200Y857152D03*
X1606623D03*
X1597041Y867192D03*
X1605741D03*
X1597041Y873885D03*
X1605741D03*
X1597041Y880577D03*
X1605741D03*
X1597041Y887270D03*
X1605741D03*
X1606898Y893963D03*
X1597041D03*
X1605741Y904003D03*
X1597041D03*
Y917389D03*
X1605741D03*
X1597041Y910696D03*
X1605741D03*
X1597041Y924081D03*
X1605741D03*
X1606541Y930697D03*
X1596047Y930774D03*
X1596106Y940814D03*
X1606919D03*
X1605741Y947507D03*
X1597041D03*
X1605741Y954200D03*
X1597041D03*
Y964239D03*
X1605741D03*
X1597041Y977625D03*
X1605741D03*
Y970932D03*
X1597041D03*
Y984318D03*
X1605741D03*
X1597041Y991011D03*
X1605741D03*
X1597041Y1024475D03*
X1605741D03*
X1597041Y1017782D03*
X1605741D03*
X1597041Y1031168D03*
X1605741D03*
X1597041Y1037861D03*
X1605741D03*
X1597041Y1044554D03*
X1605741D03*
Y1051247D03*
X1597041D03*
Y1057940D03*
X1605741D03*
X1597041Y1064633D03*
X1605741D03*
X1606541Y1071326D03*
X1596141D03*
X1597041Y1078018D03*
X1605741D03*
Y1094751D03*
X1597041D03*
Y1088058D03*
X1605741D03*
Y1101444D03*
X1597041D03*
Y1108137D03*
X1605741D03*
X1606541Y1114829D03*
X1596241D03*
X1596511Y1124969D03*
X1606505Y1124674D03*
X1605741Y1138255D03*
X1597041D03*
X1605741Y1144948D03*
X1597041D03*
Y1131562D03*
X1605741D03*
Y1151641D03*
X1597041D03*
X1596653Y1161680D03*
X1605975Y1161581D03*
X1605741Y1168373D03*
X1597041D03*
X1605741Y1175066D03*
X1597041D03*
X1605741Y1181759D03*
X1597041D03*
X1606765Y1188452D03*
X1597041D03*
Y1198491D03*
X1605741D03*
Y1205184D03*
X1597041D03*
Y1211877D03*
X1605741D03*
X1597041Y1218570D03*
X1605741D03*
X1597041Y1225263D03*
X1605741D03*
X1607064Y1235302D03*
X1596178D03*
X1605741Y1241995D03*
X1597041D03*
Y1248688D03*
X1605741D03*
X1603788Y1273144D03*
X1601388D03*
X1604815Y1578182D03*
X1592755D03*
X1600555D03*
X1604815Y1590094D03*
X1592755D03*
X1600555D03*
X1598055Y1614292D03*
Y1602380D03*
X1605855Y1614292D03*
Y1602380D03*
X1593795Y1614292D03*
Y1602380D03*
X1603740Y1675383D03*
Y1679920D03*
X1595866Y1679320D03*
X1603740Y1684454D03*
Y1689556D03*
Y1694093D03*
Y1698627D03*
X1595866Y1688391D03*
Y1693493D03*
Y1698030D03*
Y1683857D03*
X1603740Y1703729D03*
Y1708266D03*
Y1712800D03*
X1595866Y1707666D03*
Y1712203D03*
Y1702564D03*
X1603740Y1726974D03*
Y1722440D03*
Y1717903D03*
X1595866Y1730911D03*
Y1726377D03*
Y1721840D03*
Y1716737D03*
X1613183Y766798D03*
X1621883D03*
Y773491D03*
X1613183D03*
X1621883Y780184D03*
X1613183D03*
X1621883Y790223D03*
X1613183D03*
Y796916D03*
X1621883D03*
X1613183Y803609D03*
X1621883D03*
X1622916Y816995D03*
X1613183D03*
X1612363Y810302D03*
X1622986D03*
X1613183Y827034D03*
X1621883D03*
Y833727D03*
X1613183D03*
Y840420D03*
X1621883D03*
X1613183Y847113D03*
X1621943D03*
X1622060Y863845D03*
X1612408D03*
X1612474Y853955D03*
X1622961Y853806D03*
X1621883Y883924D03*
X1613183D03*
Y870538D03*
X1621883D03*
X1613183Y877231D03*
X1621883D03*
X1613183Y890617D03*
X1621883D03*
X1613183Y900656D03*
X1621883D03*
Y907349D03*
X1613183D03*
Y914042D03*
X1621883D03*
Y920735D03*
X1613183D03*
X1622535Y927526D03*
X1612168Y927428D03*
X1622845Y937467D03*
X1612312D03*
X1621883Y944160D03*
X1613183D03*
X1621883Y950853D03*
X1613183D03*
X1621883Y960892D03*
X1613183D03*
Y974278D03*
X1621883D03*
X1613183Y980971D03*
X1621883D03*
X1613183Y967585D03*
X1621883D03*
X1613183Y987664D03*
X1621883D03*
Y1017782D03*
X1613183D03*
Y1027822D03*
X1621883D03*
X1613183Y1034515D03*
X1621883D03*
X1613183Y1041207D03*
X1621883D03*
X1613183Y1047900D03*
X1621883D03*
Y1054593D03*
X1613183D03*
Y1061286D03*
X1621883D03*
Y1067979D03*
X1612983D03*
X1612283Y1074672D03*
X1622683D03*
X1621883Y1084711D03*
X1612383D03*
X1613183Y1091404D03*
X1621883D03*
Y1104790D03*
X1613183D03*
X1621883Y1098097D03*
X1613183D03*
X1621883Y1111483D03*
X1613183D03*
Y1128915D03*
X1621883Y1128215D03*
X1613183Y1121522D03*
X1621883D03*
Y1141601D03*
X1613183D03*
X1622726Y1135108D03*
X1611886Y1134908D03*
X1621883Y1158333D03*
X1613183D03*
X1621883Y1148294D03*
X1613183D03*
X1621883Y1165026D03*
X1613183D03*
Y1171719D03*
X1621883D03*
Y1178412D03*
X1613183D03*
X1621883Y1185105D03*
X1613183D03*
Y1195144D03*
X1621883D03*
Y1201837D03*
X1613183D03*
X1621883Y1208530D03*
X1613183D03*
X1621883Y1215223D03*
X1613183D03*
X1612147Y1221916D03*
X1622712D03*
X1612137Y1231862D03*
X1622681Y1231955D03*
X1621883Y1238648D03*
X1613183D03*
X1610150Y1257172D03*
X1621883Y1245341D03*
X1613183D03*
X1618888Y1273344D03*
X1616088D03*
X1616875Y1578182D03*
X1612615D03*
X1616875Y1590094D03*
X1612615D03*
X1622175Y1614292D03*
Y1602380D03*
X1617915Y1614292D03*
Y1602380D03*
X1610115Y1614292D03*
Y1602380D03*
X1619488Y1675383D03*
Y1679920D03*
X1611614Y1679320D03*
X1619488Y1684454D03*
Y1689556D03*
Y1694093D03*
Y1698627D03*
X1611614Y1688391D03*
Y1693493D03*
Y1698030D03*
Y1683857D03*
X1619488Y1703729D03*
Y1708266D03*
Y1712800D03*
X1611614Y1707666D03*
Y1712203D03*
Y1702564D03*
X1619488Y1726974D03*
Y1722440D03*
Y1717903D03*
X1611614Y1730911D03*
Y1726377D03*
Y1721840D03*
Y1716737D03*
X1626741Y770144D03*
X1635441D03*
X1626741Y776837D03*
X1635441D03*
X1626741Y783530D03*
X1635441D03*
X1626741Y793570D03*
X1635441D03*
Y800263D03*
X1626741D03*
X1636341Y820341D03*
X1626741D03*
X1636574Y813648D03*
X1626741D03*
X1635441Y806955D03*
X1626741D03*
X1635441Y830381D03*
X1626741D03*
X1635441Y837074D03*
X1626741D03*
Y843766D03*
X1635441D03*
Y850459D03*
X1626741D03*
X1625705Y867192D03*
X1636441D03*
X1635441Y857152D03*
X1626741D03*
Y880577D03*
X1635441D03*
Y873885D03*
X1626741D03*
Y887270D03*
X1635441D03*
X1626741Y893963D03*
X1635441D03*
X1626741Y904003D03*
X1635441D03*
Y910696D03*
X1626741D03*
X1635441Y917389D03*
X1626741D03*
X1636316Y930774D03*
X1625803D03*
X1636646Y924081D03*
X1626741D03*
X1635441Y940814D03*
X1626741D03*
X1635441Y947507D03*
X1626741D03*
X1635441Y954200D03*
X1626741D03*
Y964239D03*
X1635441D03*
Y977625D03*
X1626741D03*
X1635441Y970932D03*
X1626741D03*
X1635441Y984318D03*
X1626741D03*
Y991011D03*
X1635441D03*
Y1024475D03*
X1626741D03*
X1635441Y1017782D03*
X1626741D03*
X1635441Y1031168D03*
X1626741D03*
X1635441Y1037861D03*
X1626741D03*
X1635441Y1044554D03*
X1626741D03*
Y1057940D03*
X1635441D03*
Y1051247D03*
X1626741D03*
X1635441Y1064633D03*
X1626741D03*
X1635441Y1071326D03*
X1626741D03*
X1636241Y1078018D03*
X1625941D03*
Y1088058D03*
X1636241D03*
X1635441Y1094751D03*
X1626741D03*
Y1101444D03*
X1635441D03*
X1626741Y1108137D03*
X1635441D03*
X1626074Y1124640D03*
X1636341Y1124869D03*
X1635441Y1114829D03*
X1626741D03*
X1635441Y1144948D03*
X1626741D03*
X1635441Y1138255D03*
X1626741D03*
X1635441Y1130762D03*
X1626741D03*
Y1161680D03*
X1635441D03*
Y1151641D03*
X1626741D03*
Y1168373D03*
X1635441D03*
X1626741Y1175066D03*
X1635441D03*
X1626741Y1181759D03*
X1635441D03*
X1626741Y1188452D03*
X1635441D03*
X1626741Y1198491D03*
X1635441D03*
X1626741Y1205184D03*
X1635441D03*
Y1211877D03*
X1626741D03*
X1635441Y1218570D03*
X1626741D03*
X1636212Y1225263D03*
X1626055D03*
X1636376Y1235302D03*
X1625843D03*
X1635441Y1241995D03*
X1626741D03*
X1635688Y1257664D03*
X1626741Y1248688D03*
X1635441D03*
X1629788Y1273344D03*
X1632588D03*
X1625729Y1266766D03*
X1636735Y1578088D03*
X1628935Y1578182D03*
X1624675D03*
X1636735Y1590094D03*
X1628935D03*
X1624675D03*
X1634235Y1614292D03*
Y1602380D03*
X1629975Y1614292D03*
Y1602380D03*
X1627362Y1679320D03*
Y1688391D03*
Y1693493D03*
Y1698030D03*
Y1683857D03*
Y1707666D03*
Y1712203D03*
Y1702564D03*
Y1730911D03*
Y1726377D03*
Y1721840D03*
Y1716737D03*
X1651583Y766798D03*
X1642883D03*
X1656441Y770144D03*
Y776837D03*
X1642883Y773491D03*
X1651583D03*
X1642883Y780184D03*
X1651583D03*
X1656441Y783530D03*
Y793570D03*
X1642883Y790223D03*
X1651583D03*
X1642883Y796916D03*
X1651583D03*
X1656441Y800263D03*
X1651583Y803609D03*
X1642883D03*
X1656441Y806955D03*
Y813648D03*
Y820341D03*
X1651583Y810302D03*
X1642883D03*
X1652545Y816995D03*
X1641945D03*
X1656441Y830381D03*
X1652767Y827034D03*
X1642018D03*
X1651583Y833727D03*
X1642883D03*
X1656441Y837074D03*
Y843766D03*
X1642883Y840420D03*
X1651583D03*
X1656441Y850459D03*
X1651583Y847113D03*
X1642883D03*
X1642058Y863845D03*
X1652742D03*
X1656441Y857152D03*
Y867192D03*
X1652559Y853806D03*
X1642032D03*
X1656441Y873885D03*
Y880577D03*
X1642883Y883924D03*
X1651583D03*
Y870538D03*
X1642883D03*
X1651583Y877231D03*
X1642883D03*
X1656441Y887270D03*
Y893963D03*
X1642883Y890617D03*
X1651583D03*
X1642883Y900656D03*
X1651583D03*
X1656441Y904003D03*
Y910696D03*
X1642883Y907349D03*
X1651583D03*
X1656441Y917389D03*
X1651583Y914042D03*
X1642883D03*
X1656441Y924081D03*
Y930774D03*
X1652630Y927428D03*
X1642038D03*
X1651583Y920735D03*
X1642883D03*
X1656441Y940814D03*
Y947507D03*
X1652501Y937467D03*
X1642065D03*
X1651583Y944160D03*
X1642883D03*
X1656441Y954200D03*
X1642883Y950853D03*
X1651583D03*
Y960892D03*
X1642883D03*
X1656441Y964239D03*
Y977625D03*
Y970932D03*
X1651583Y967585D03*
X1642883D03*
X1651583Y974278D03*
X1642883D03*
X1651583Y980971D03*
X1642883D03*
X1656441Y984318D03*
Y991011D03*
X1651583Y987664D03*
X1642883D03*
X1651583Y1017782D03*
X1642883D03*
X1656441D03*
Y1024475D03*
X1651583Y1027822D03*
X1642883D03*
X1656441Y1031168D03*
Y1044554D03*
Y1037861D03*
X1651583Y1034515D03*
X1642883D03*
X1651583Y1041207D03*
X1642883D03*
X1651583Y1047900D03*
X1642883D03*
Y1061286D03*
X1651583D03*
X1656441Y1051247D03*
Y1057940D03*
X1651583Y1054593D03*
X1642883D03*
X1656441Y1064633D03*
Y1071326D03*
Y1078018D03*
X1652483Y1074672D03*
X1641983D03*
X1651583Y1067979D03*
X1642883D03*
X1656441Y1088058D03*
Y1094751D03*
X1652383Y1084711D03*
X1642083D03*
X1651583Y1091404D03*
X1642883D03*
X1656441Y1101444D03*
Y1108137D03*
X1642883Y1098097D03*
X1651583D03*
X1642883Y1104790D03*
X1651583D03*
X1642883Y1111483D03*
X1651583D03*
X1656441Y1114829D03*
Y1124869D03*
X1642883Y1121522D03*
X1651583D03*
X1642883Y1128215D03*
X1651583D03*
X1656441Y1131562D03*
Y1138255D03*
X1642883Y1134908D03*
X1651583D03*
X1642883Y1141601D03*
X1651583D03*
X1656441Y1144948D03*
Y1151641D03*
Y1161680D03*
X1652383Y1158333D03*
X1642083D03*
X1652794Y1148294D03*
X1641744D03*
X1656441Y1168373D03*
Y1175066D03*
X1642883Y1171719D03*
X1651583D03*
Y1165026D03*
X1642883D03*
X1656441Y1181759D03*
Y1188452D03*
X1651583Y1178412D03*
X1642883D03*
X1651583Y1185105D03*
X1642883D03*
X1656441Y1198491D03*
Y1205184D03*
X1642883Y1195144D03*
X1651583D03*
X1642883Y1201837D03*
X1651583D03*
X1642883Y1208530D03*
X1651583D03*
X1656441Y1211877D03*
X1652590Y1221916D03*
X1641793D03*
X1656441Y1225263D03*
Y1218570D03*
X1651583Y1215223D03*
X1642883D03*
X1656441Y1235302D03*
Y1241995D03*
X1652604Y1231955D03*
X1642054D03*
X1651583Y1238648D03*
X1642883D03*
X1656441Y1248688D03*
X1651583Y1245341D03*
X1642883D03*
X1648588Y1273344D03*
X1645788D03*
X1640995Y1578182D03*
X1648795D03*
X1640995Y1590094D03*
X1648795D03*
X1646295Y1614292D03*
Y1602380D03*
X1654095Y1614292D03*
Y1602380D03*
X1642035Y1614292D03*
Y1602286D03*
X1665141Y770144D03*
X1672583Y766798D03*
X1665141Y776837D03*
Y783530D03*
X1672583Y773491D03*
Y780184D03*
X1665141Y793570D03*
Y800263D03*
X1672583Y790223D03*
Y796916D03*
Y803609D03*
X1665141Y806955D03*
Y813648D03*
X1666030Y820341D03*
X1672583Y810302D03*
Y816995D03*
X1665141Y830381D03*
X1672583Y827034D03*
Y833727D03*
X1665141Y837074D03*
Y843766D03*
X1672583Y840420D03*
X1665141Y850459D03*
X1672583Y847113D03*
X1666038Y857152D03*
X1665141Y867192D03*
X1672583Y853806D03*
Y863845D03*
X1665141Y873885D03*
Y880577D03*
X1672583Y870538D03*
Y877231D03*
Y883924D03*
X1665141Y887270D03*
Y893963D03*
X1672583Y890617D03*
Y900656D03*
X1665141Y904003D03*
Y910696D03*
Y917389D03*
X1672583Y907349D03*
Y914042D03*
X1665141Y924081D03*
X1666246Y930774D03*
X1672583Y920735D03*
Y927428D03*
X1665141Y940814D03*
Y947507D03*
X1672583Y937467D03*
Y944160D03*
X1665141Y954200D03*
Y964239D03*
X1672583Y950853D03*
Y960892D03*
X1665141Y977625D03*
Y970932D03*
X1672583Y967585D03*
Y974278D03*
Y980971D03*
X1665141Y984318D03*
Y991011D03*
X1672583Y987664D03*
X1665141Y1017782D03*
Y1024475D03*
Y1031168D03*
X1672583Y1017782D03*
Y1027822D03*
X1665141Y1044554D03*
Y1037861D03*
X1672583Y1034515D03*
Y1041207D03*
Y1047900D03*
X1665141Y1057940D03*
X1672583Y1061286D03*
Y1054593D03*
X1665141Y1064633D03*
Y1071326D03*
Y1077118D03*
X1672583Y1067979D03*
Y1074672D03*
X1665141Y1088058D03*
Y1094751D03*
X1672583Y1084711D03*
Y1091404D03*
X1665141Y1101444D03*
Y1108137D03*
X1672583Y1098097D03*
Y1104790D03*
Y1111483D03*
X1665141Y1114829D03*
Y1124869D03*
X1672583Y1121522D03*
Y1128215D03*
X1665141Y1131562D03*
Y1138255D03*
Y1144948D03*
X1672583Y1134908D03*
Y1141601D03*
X1666141Y1151641D03*
X1665141Y1161680D03*
X1672583Y1148294D03*
Y1158333D03*
X1665141Y1168373D03*
Y1175066D03*
X1672583Y1165026D03*
Y1171719D03*
X1665141Y1181759D03*
Y1188452D03*
X1672583Y1178412D03*
Y1185105D03*
X1665141Y1198491D03*
Y1205184D03*
X1672583Y1195144D03*
Y1201837D03*
Y1208530D03*
X1665141Y1211877D03*
X1665941Y1225263D03*
X1665141Y1218570D03*
X1672583Y1215223D03*
Y1221916D03*
X1665141Y1235302D03*
Y1241995D03*
X1672583Y1231955D03*
Y1238648D03*
X1665141Y1248688D03*
X1672583Y1245341D03*
X1665688Y1257964D03*
X1659488Y1273344D03*
X1662288D03*
X1681283Y766798D03*
X1686141Y770144D03*
X1681283Y773491D03*
Y780184D03*
X1686141Y776837D03*
Y783530D03*
X1681283Y790223D03*
Y796916D03*
Y803609D03*
X1686141Y793570D03*
Y800263D03*
X1681283Y810302D03*
Y816995D03*
X1686141Y806955D03*
Y813648D03*
Y820341D03*
X1681283Y827034D03*
Y833727D03*
X1686141Y830381D03*
X1681283Y840420D03*
X1686141Y837074D03*
Y843766D03*
Y850459D03*
X1681283Y847113D03*
X1686141Y857152D03*
Y867192D03*
X1681283Y853806D03*
Y863845D03*
X1686141Y873885D03*
Y880577D03*
X1681283Y870538D03*
Y877231D03*
Y883924D03*
X1686141Y887270D03*
Y893963D03*
X1681283Y890617D03*
Y900656D03*
X1686141Y904003D03*
Y910696D03*
Y917389D03*
X1681283Y907349D03*
Y914042D03*
X1686141Y924081D03*
Y930774D03*
X1681283Y920735D03*
Y927428D03*
X1686141Y940814D03*
Y947507D03*
X1681283Y937467D03*
Y944160D03*
X1686141Y954200D03*
Y964239D03*
X1681283Y950853D03*
Y960892D03*
X1686141Y970932D03*
Y977625D03*
X1681283Y967585D03*
Y974278D03*
Y980971D03*
X1686141Y984318D03*
Y991011D03*
X1681283Y987664D03*
X1686141Y1017782D03*
Y1024475D03*
Y1031168D03*
X1681283Y1017782D03*
Y1027822D03*
X1686141Y1037861D03*
Y1044554D03*
X1681283Y1034515D03*
Y1041207D03*
Y1047900D03*
X1686141Y1051247D03*
Y1057940D03*
X1681283Y1061286D03*
Y1054593D03*
X1686141Y1064633D03*
Y1071326D03*
Y1078018D03*
X1681283Y1067979D03*
Y1074672D03*
X1686141Y1088058D03*
Y1094751D03*
X1681283Y1084711D03*
Y1091404D03*
X1686141Y1101444D03*
Y1108137D03*
X1681283Y1098097D03*
Y1104790D03*
Y1111483D03*
X1686141Y1114829D03*
Y1124869D03*
X1681283Y1121522D03*
Y1128215D03*
X1686141Y1131562D03*
Y1138255D03*
Y1144948D03*
X1681283Y1134908D03*
Y1141601D03*
X1686141Y1151641D03*
Y1161680D03*
X1681283Y1148294D03*
Y1158333D03*
X1686141Y1168373D03*
Y1175066D03*
X1681283Y1165026D03*
Y1171719D03*
X1686141Y1181759D03*
Y1188452D03*
X1681283Y1178412D03*
Y1185105D03*
X1686141Y1198491D03*
Y1205184D03*
X1681283Y1195144D03*
Y1201837D03*
Y1208530D03*
X1686141Y1211877D03*
Y1218570D03*
Y1225263D03*
X1681283Y1215223D03*
Y1221916D03*
Y1231955D03*
Y1238648D03*
X1686141Y1235302D03*
Y1241995D03*
X1681283Y1245341D03*
X1686141Y1248688D03*
X1675488Y1273344D03*
X1678288D03*
X1689188D03*
X1694841Y770144D03*
X1702283Y766798D03*
X1694841Y776837D03*
Y783530D03*
X1702283Y773491D03*
Y780184D03*
X1694841Y793570D03*
Y800263D03*
X1702283Y790223D03*
Y796916D03*
Y803609D03*
X1694841Y806955D03*
Y813648D03*
Y820341D03*
X1702283Y810302D03*
Y816995D03*
X1694841Y830381D03*
X1702283Y827034D03*
Y833727D03*
X1694841Y837074D03*
Y843766D03*
Y850459D03*
X1702283Y840420D03*
Y847113D03*
X1694841Y857152D03*
Y867192D03*
X1702283Y853806D03*
Y863845D03*
X1694841Y873885D03*
Y880577D03*
X1702283Y870538D03*
Y877231D03*
Y883924D03*
X1694841Y887270D03*
Y893963D03*
X1702283Y890617D03*
Y900656D03*
X1694841Y904003D03*
Y910696D03*
Y917389D03*
X1702283Y907349D03*
Y914042D03*
X1694841Y924081D03*
Y930774D03*
X1702283Y920735D03*
Y927428D03*
X1694841Y940814D03*
Y947507D03*
X1702283Y937467D03*
Y944160D03*
X1694841Y954200D03*
Y964239D03*
X1702283Y950853D03*
Y960892D03*
X1694841Y970932D03*
Y977625D03*
X1702283Y967585D03*
Y974278D03*
Y980971D03*
X1694841Y984318D03*
Y991011D03*
X1702283Y987664D03*
X1694841Y1017782D03*
Y1024475D03*
Y1031168D03*
X1702283Y1017782D03*
Y1027822D03*
X1694841Y1037861D03*
Y1044554D03*
X1702283Y1034515D03*
Y1041207D03*
Y1047900D03*
X1694841Y1051247D03*
Y1057940D03*
X1702283Y1054593D03*
Y1061286D03*
X1694841Y1064633D03*
Y1071326D03*
Y1078018D03*
X1702283Y1067979D03*
Y1074672D03*
X1694841Y1088058D03*
Y1094751D03*
X1702283Y1084711D03*
Y1091404D03*
X1694841Y1101444D03*
Y1108137D03*
X1702283Y1098097D03*
Y1104790D03*
Y1111483D03*
X1694841Y1114829D03*
Y1124869D03*
X1702283Y1121522D03*
Y1128215D03*
X1694841Y1131562D03*
Y1138255D03*
Y1144948D03*
X1702283Y1134908D03*
Y1141601D03*
X1694841Y1151641D03*
Y1161680D03*
X1702283Y1148294D03*
Y1158333D03*
X1694841Y1168373D03*
Y1175066D03*
X1702283Y1165026D03*
Y1171719D03*
X1694841Y1181759D03*
Y1188452D03*
X1702283Y1178412D03*
Y1185105D03*
X1694841Y1198491D03*
Y1205184D03*
X1702283Y1195144D03*
Y1201837D03*
Y1208530D03*
X1694841Y1211877D03*
Y1218570D03*
Y1225263D03*
X1702283Y1215223D03*
Y1221916D03*
X1694841Y1235302D03*
Y1241995D03*
X1702283Y1231955D03*
Y1238648D03*
X1694841Y1248688D03*
X1695188Y1257064D03*
X1702283Y1245341D03*
X1691988Y1273344D03*
X1705188D03*
X1710983Y766798D03*
X1715841Y770144D03*
X1710983Y773491D03*
Y780184D03*
X1715841Y783530D03*
Y776837D03*
X1710983Y790223D03*
Y796916D03*
Y803609D03*
X1715841Y793570D03*
Y800263D03*
X1710983Y810302D03*
Y816995D03*
X1715841Y806955D03*
Y813648D03*
Y820341D03*
X1710983Y827034D03*
Y833727D03*
X1715841Y830381D03*
X1710983Y840420D03*
Y847113D03*
X1715841Y837074D03*
Y843766D03*
Y850459D03*
X1710983Y853806D03*
Y863845D03*
X1715841Y857152D03*
Y867192D03*
X1710983Y870538D03*
Y877231D03*
Y883924D03*
X1715841Y873885D03*
Y880577D03*
X1710983Y890617D03*
Y900656D03*
X1715841Y893963D03*
Y887270D03*
X1710983Y907349D03*
Y914042D03*
X1715841Y904003D03*
Y910696D03*
Y917389D03*
X1710983Y920735D03*
Y927428D03*
X1715841Y924081D03*
Y930774D03*
X1710983Y937467D03*
Y944160D03*
X1715841Y940814D03*
Y947507D03*
X1710983Y950853D03*
Y960892D03*
X1715841Y954200D03*
Y964239D03*
X1710983Y967585D03*
Y974278D03*
Y980971D03*
X1715841Y970932D03*
Y977625D03*
X1710983Y987664D03*
X1715841Y984318D03*
Y991011D03*
X1710983Y1017782D03*
Y1027822D03*
X1715841Y1017782D03*
Y1024475D03*
Y1031168D03*
X1710983Y1034515D03*
Y1041207D03*
Y1047900D03*
X1715841Y1037861D03*
Y1044554D03*
X1710983Y1054593D03*
Y1061286D03*
X1715841Y1051247D03*
Y1057940D03*
X1710983Y1067979D03*
Y1074672D03*
X1715841Y1071326D03*
Y1064633D03*
Y1078018D03*
X1710983Y1084711D03*
Y1091404D03*
X1715841Y1088058D03*
Y1094751D03*
X1710983Y1098097D03*
Y1104790D03*
Y1111483D03*
X1715841Y1101444D03*
Y1108137D03*
X1710983Y1121522D03*
Y1128215D03*
X1715841Y1114829D03*
Y1124869D03*
X1710983Y1134908D03*
Y1141601D03*
X1715841Y1131562D03*
Y1138255D03*
Y1144948D03*
X1710983Y1148294D03*
Y1158333D03*
X1715841Y1151641D03*
Y1161680D03*
X1710983Y1165026D03*
Y1171719D03*
X1715841Y1168373D03*
Y1175066D03*
X1710983Y1178412D03*
Y1185105D03*
X1715841Y1181759D03*
Y1188452D03*
X1710983Y1195144D03*
Y1201837D03*
Y1208530D03*
X1715841Y1198491D03*
Y1205184D03*
X1710983Y1215223D03*
Y1221916D03*
X1715841Y1211877D03*
Y1218570D03*
Y1225263D03*
X1710983Y1231955D03*
Y1238648D03*
X1715841Y1235302D03*
Y1241995D03*
X1710983Y1245341D03*
X1715841Y1248688D03*
X1707514Y1273444D03*
X1718888Y1273344D03*
X1721688D03*
X1731983Y766798D03*
X1724541Y770144D03*
X1731983Y773491D03*
Y780184D03*
X1724541Y783530D03*
Y776837D03*
Y793570D03*
Y800263D03*
X1731983Y790223D03*
Y796916D03*
Y803609D03*
X1724541Y806955D03*
Y813648D03*
Y820341D03*
X1731983Y810302D03*
Y816995D03*
X1724541Y830381D03*
X1731983Y827034D03*
Y833727D03*
X1724541Y837074D03*
Y843766D03*
Y850459D03*
X1731983Y840420D03*
Y847113D03*
X1724541Y857152D03*
Y867192D03*
X1731983Y853806D03*
Y863845D03*
X1724541Y873885D03*
Y880577D03*
X1731983Y870538D03*
Y877231D03*
Y883924D03*
X1724541Y893963D03*
Y887270D03*
X1731983Y890617D03*
Y900656D03*
X1724541Y904003D03*
Y910696D03*
Y917389D03*
X1731983Y907349D03*
Y914042D03*
X1724541Y924081D03*
Y930774D03*
X1731983Y920735D03*
Y927428D03*
X1724541Y940814D03*
Y947507D03*
X1731983Y937467D03*
Y944160D03*
X1724541Y954200D03*
Y964239D03*
X1731983Y950853D03*
Y960892D03*
X1724541Y970932D03*
Y977625D03*
X1731983Y967585D03*
Y974278D03*
Y980971D03*
X1724541Y984318D03*
Y991011D03*
X1731983Y987664D03*
X1724541Y1017782D03*
Y1024475D03*
Y1031168D03*
X1731983Y1017782D03*
Y1027822D03*
X1724541Y1037861D03*
Y1044554D03*
X1731983Y1034515D03*
Y1041207D03*
Y1047900D03*
X1724541Y1057940D03*
X1731983Y1054593D03*
Y1061286D03*
X1724541Y1071326D03*
Y1064633D03*
Y1078018D03*
X1731983Y1074672D03*
Y1067979D03*
X1724541Y1088058D03*
Y1094751D03*
X1731983Y1084711D03*
Y1091404D03*
X1724541Y1101444D03*
Y1108137D03*
X1731983Y1098097D03*
Y1104790D03*
Y1111483D03*
X1724541Y1114829D03*
Y1124869D03*
X1731983Y1121522D03*
Y1128215D03*
X1724541Y1131562D03*
Y1138255D03*
Y1144948D03*
X1731983Y1134908D03*
Y1141601D03*
X1724541Y1151641D03*
Y1161680D03*
X1731983Y1148294D03*
Y1158333D03*
X1724541Y1168373D03*
Y1175066D03*
X1731983Y1165026D03*
Y1171719D03*
X1724541Y1181759D03*
Y1188452D03*
X1731983Y1178412D03*
Y1185105D03*
X1724541Y1198491D03*
Y1205184D03*
X1731983Y1195144D03*
Y1201837D03*
Y1208530D03*
X1724541Y1211877D03*
Y1218570D03*
Y1225263D03*
X1731983Y1215223D03*
Y1221916D03*
X1724541Y1235302D03*
Y1241995D03*
X1731983Y1231955D03*
Y1238648D03*
X1724541Y1248688D03*
X1724588Y1257164D03*
X1731983Y1245341D03*
X1734888Y1273344D03*
X1737688D03*
X1740683Y766798D03*
X1745541Y770144D03*
X1754241D03*
X1740683Y773491D03*
Y780184D03*
X1745541Y776837D03*
X1754241D03*
X1745541Y783530D03*
X1754241D03*
X1740683Y790223D03*
Y796916D03*
Y803609D03*
X1745541Y793570D03*
X1754241D03*
X1745541Y800263D03*
X1754241D03*
X1740683Y810302D03*
Y816995D03*
X1745541Y806955D03*
X1754241D03*
X1745541Y813648D03*
X1754241D03*
X1745541Y820341D03*
X1754241D03*
X1740683Y827034D03*
Y833727D03*
X1745541Y830381D03*
X1754241D03*
X1740683Y840420D03*
Y847113D03*
X1754241Y843766D03*
X1745541D03*
Y837074D03*
X1754241D03*
X1745541Y850459D03*
X1754241D03*
X1740683Y853806D03*
Y863845D03*
X1745541Y857152D03*
X1754241D03*
Y867192D03*
X1745541D03*
X1740683Y870538D03*
Y877231D03*
Y883924D03*
X1745541Y873885D03*
X1754241D03*
X1745541Y880577D03*
X1754241D03*
X1740683Y890617D03*
Y900656D03*
X1754241Y893963D03*
X1745541D03*
Y887270D03*
X1754241D03*
X1740683Y907349D03*
Y914042D03*
X1754241Y904003D03*
X1745541D03*
X1754241Y910696D03*
X1745541D03*
X1754241Y917389D03*
X1745541D03*
X1740683Y920735D03*
Y927428D03*
X1754241Y924081D03*
X1745541D03*
X1754241Y930774D03*
X1745541D03*
X1740683Y937467D03*
Y944160D03*
X1754241Y940814D03*
X1745541D03*
X1754241Y947507D03*
X1745541D03*
X1740683Y950853D03*
Y960892D03*
X1754241Y954200D03*
X1745541D03*
X1754241Y964239D03*
X1745541D03*
X1740683Y967585D03*
Y974278D03*
Y980971D03*
X1754241Y970932D03*
X1745541D03*
X1754241Y977625D03*
X1745541D03*
X1740683Y987664D03*
X1754241Y984318D03*
X1745541D03*
X1754241Y991011D03*
X1745541D03*
X1740683Y1017782D03*
Y1027822D03*
X1754241Y1017782D03*
X1745541D03*
Y1024475D03*
X1754241D03*
X1745541Y1031168D03*
X1754241D03*
X1740683Y1034515D03*
Y1041207D03*
Y1047900D03*
X1754241Y1044554D03*
X1745541D03*
Y1037861D03*
X1754241D03*
X1740683Y1054593D03*
Y1061286D03*
X1745541Y1051247D03*
X1754241D03*
X1745541Y1057940D03*
X1754241D03*
X1740683Y1074672D03*
Y1067979D03*
X1754241Y1071326D03*
X1745541D03*
Y1064633D03*
X1754241D03*
Y1078018D03*
X1745541D03*
X1740683Y1084711D03*
Y1091404D03*
X1754241Y1088058D03*
X1745541D03*
X1754241Y1094751D03*
X1745541D03*
X1740683Y1098097D03*
Y1104790D03*
Y1111483D03*
X1754241Y1101444D03*
X1745541D03*
X1754241Y1108137D03*
X1745541D03*
X1740683Y1121522D03*
Y1128215D03*
X1754241Y1114829D03*
X1745541D03*
X1754241Y1124869D03*
X1745541D03*
X1740683Y1134908D03*
Y1141601D03*
X1754241Y1131562D03*
X1745541D03*
X1754241Y1138255D03*
X1745541D03*
X1754241Y1144948D03*
X1745541D03*
X1740683Y1148294D03*
Y1158333D03*
X1754241Y1151641D03*
X1745541D03*
X1754241Y1161680D03*
X1745541D03*
X1740683Y1165026D03*
Y1171719D03*
X1745541Y1175066D03*
X1754241D03*
Y1168373D03*
X1745541D03*
X1740683Y1178412D03*
Y1185105D03*
X1745541Y1181759D03*
X1754241D03*
Y1188452D03*
X1745541D03*
X1740683Y1195144D03*
Y1201837D03*
Y1208530D03*
X1754241Y1198491D03*
X1745541D03*
X1754241Y1205184D03*
X1745541D03*
X1740683Y1215223D03*
Y1221916D03*
X1754241Y1211877D03*
X1745541D03*
X1754241Y1218570D03*
X1745541D03*
X1754241Y1225263D03*
X1745541D03*
X1740683Y1231955D03*
Y1238648D03*
X1754241Y1235302D03*
X1745541D03*
X1754241Y1241995D03*
X1745541D03*
X1740683Y1245341D03*
X1754241Y1248688D03*
X1745541D03*
X1754488Y1257264D03*
X1751388Y1273344D03*
X1748588D03*
X1749088Y1310474D03*
X1746288D03*
X1770383Y766798D03*
X1761683D03*
X1770383Y773491D03*
X1761683D03*
Y780184D03*
X1770383D03*
X1761683Y790223D03*
X1770383D03*
X1761683Y796916D03*
X1770383D03*
X1761683Y803609D03*
X1770383D03*
X1761683Y810302D03*
X1770383D03*
X1761683Y816995D03*
X1770383D03*
X1761683Y827034D03*
X1770383D03*
X1761683Y833727D03*
X1770383D03*
X1761683Y840420D03*
X1770383D03*
X1761683Y847113D03*
X1770383D03*
X1761683Y853806D03*
X1770383D03*
X1761683Y863845D03*
X1770383D03*
X1761683Y870538D03*
X1770383D03*
X1761683Y877231D03*
X1770383D03*
X1761683Y883924D03*
X1770383D03*
X1761683Y890617D03*
X1770383D03*
X1761683Y900656D03*
X1770383D03*
X1761683Y907349D03*
X1770383D03*
X1761683Y914042D03*
X1770383D03*
Y927428D03*
X1761683D03*
Y920735D03*
X1770383D03*
X1761683Y937467D03*
X1770383D03*
X1761683Y944160D03*
X1770383D03*
X1761683Y950853D03*
X1770383D03*
X1761683Y960892D03*
X1770383D03*
X1761683Y967585D03*
X1770383D03*
X1761683Y974278D03*
X1770383D03*
X1761683Y980971D03*
X1770383D03*
X1761683Y987664D03*
X1770383D03*
X1761683Y1017782D03*
X1770383D03*
X1761683Y1027822D03*
X1770383D03*
X1761683Y1034515D03*
X1770383D03*
X1761683Y1041207D03*
X1770383D03*
X1761683Y1047900D03*
X1770383D03*
X1761683Y1054593D03*
X1770383D03*
X1761683Y1061286D03*
X1770383D03*
X1761683Y1067979D03*
X1770383D03*
X1761683Y1074672D03*
X1770383D03*
X1761683Y1084711D03*
X1770383D03*
X1761683Y1091404D03*
X1770383D03*
Y1098097D03*
X1761683D03*
Y1104790D03*
X1770383D03*
X1761683Y1111483D03*
X1770383D03*
X1761683Y1121522D03*
X1770383D03*
X1761683Y1128215D03*
X1770383D03*
X1761683Y1134908D03*
X1770383D03*
X1761683Y1141601D03*
X1770383D03*
X1761683Y1148294D03*
X1770383D03*
X1761683Y1158333D03*
X1770383D03*
X1761683Y1165026D03*
X1770383D03*
X1761683Y1171719D03*
X1770383D03*
X1761683Y1178412D03*
X1770383D03*
X1761683Y1185105D03*
X1770383D03*
X1761683Y1195144D03*
X1770383D03*
X1761683Y1201837D03*
X1770383D03*
X1761683Y1208530D03*
X1770383D03*
X1761683Y1215223D03*
X1770383D03*
X1761683Y1221916D03*
X1770383D03*
X1761683Y1231955D03*
X1770383D03*
X1761683Y1238648D03*
X1770383D03*
X1761683Y1245341D03*
X1770383D03*
X1767388Y1273344D03*
X1764588D03*
X1775241Y770144D03*
X1783941D03*
X1775241Y776837D03*
X1783941D03*
X1775241Y783530D03*
X1783941D03*
X1775241Y793570D03*
X1783941D03*
X1775241Y800263D03*
X1783941D03*
X1775241Y806955D03*
X1783941D03*
X1775241Y813648D03*
X1783941D03*
X1775241Y820341D03*
X1783941D03*
Y830381D03*
X1775241D03*
Y837074D03*
X1783941D03*
X1775241Y843766D03*
X1783941D03*
X1775241Y850459D03*
X1783941D03*
X1775241Y857152D03*
X1783941D03*
X1775241Y867192D03*
X1783941D03*
X1775241Y873885D03*
X1783941D03*
X1775241Y880577D03*
X1783941D03*
X1775241Y887270D03*
X1783941D03*
X1775241Y893963D03*
X1783941D03*
X1775241Y904003D03*
X1783941D03*
X1775241Y910696D03*
X1783941D03*
X1775241Y917389D03*
X1783941D03*
X1775241Y924081D03*
X1783941D03*
X1775241Y930774D03*
X1783941D03*
X1775241Y940814D03*
X1783941D03*
X1775241Y947507D03*
X1783941D03*
X1775241Y954200D03*
X1783941D03*
X1775241Y964239D03*
X1783941D03*
X1775241Y970932D03*
X1783941D03*
X1775241Y977625D03*
X1783941D03*
X1775241Y984318D03*
X1783941D03*
X1775241Y991011D03*
X1783941D03*
X1775241Y1017782D03*
X1783941D03*
X1775241Y1024475D03*
X1783941D03*
X1775241Y1031168D03*
X1783941D03*
X1775241Y1037861D03*
X1783941D03*
X1775241Y1044554D03*
X1783941D03*
X1775241Y1051247D03*
X1783941D03*
X1775241Y1057940D03*
X1783941D03*
X1775241Y1064633D03*
X1783941D03*
X1775241Y1071326D03*
X1783941D03*
X1775241Y1078018D03*
X1783941D03*
X1775241Y1088058D03*
X1783941D03*
X1775241Y1094751D03*
X1783941D03*
X1775241Y1101444D03*
X1783941D03*
X1775241Y1108137D03*
X1783941D03*
X1775241Y1114829D03*
X1783941D03*
X1775241Y1124869D03*
X1783941D03*
X1775241Y1131562D03*
X1783941D03*
X1775241Y1138255D03*
X1783941D03*
X1775241Y1144948D03*
X1783941D03*
Y1151641D03*
X1775241D03*
Y1161680D03*
X1783941D03*
X1775241Y1168373D03*
X1783941D03*
X1775241Y1175066D03*
X1783941D03*
X1775241Y1181759D03*
X1783941D03*
X1775241Y1188452D03*
X1783941D03*
X1775241Y1198491D03*
X1783941D03*
X1775241Y1205184D03*
X1783941D03*
X1775241Y1211877D03*
X1783941D03*
X1775241Y1218570D03*
X1783941D03*
X1775241Y1225263D03*
X1783941D03*
X1775241Y1235302D03*
X1783941D03*
X1775241Y1241995D03*
X1783941D03*
X1784188Y1257664D03*
X1775241Y1248688D03*
X1783941D03*
X1781088Y1273344D03*
X1778288D03*
X1791383Y766798D03*
X1800083D03*
X1791383Y773491D03*
X1800083D03*
X1791383Y780184D03*
X1800083D03*
X1791383Y790223D03*
X1800083D03*
X1791383Y796916D03*
X1800083D03*
X1791383Y803609D03*
X1800083D03*
X1791383Y810302D03*
X1800083D03*
X1791383Y816995D03*
X1800083D03*
X1791383Y827034D03*
X1800083D03*
Y833727D03*
X1791383D03*
Y840420D03*
X1800083D03*
X1791383Y847113D03*
X1800083D03*
X1791383Y853806D03*
X1800083D03*
X1791383Y863845D03*
X1800083D03*
X1791383Y870538D03*
X1800083D03*
X1791383Y877231D03*
X1800083D03*
X1791383Y883924D03*
X1800083D03*
X1791383Y890617D03*
X1800083D03*
X1791383Y900656D03*
X1800083D03*
X1791383Y907349D03*
X1800083D03*
X1791383Y914042D03*
X1800083D03*
X1791383Y920735D03*
X1800083D03*
X1791383Y927428D03*
X1800083D03*
X1791383Y937467D03*
X1800083D03*
X1791383Y944160D03*
X1800083D03*
Y950853D03*
X1791383D03*
Y960892D03*
X1800083D03*
X1791383Y967585D03*
X1800083D03*
X1791383Y974278D03*
X1800083D03*
X1791383Y980971D03*
X1800083D03*
X1791383Y987664D03*
X1800083D03*
X1791383Y1017782D03*
X1800083D03*
X1791383Y1027822D03*
X1800083D03*
X1791383Y1034515D03*
X1800083D03*
X1791383Y1041207D03*
X1800083D03*
X1791383Y1047900D03*
X1800083D03*
X1791383Y1054593D03*
X1800083D03*
X1791383Y1061286D03*
X1800083D03*
X1791383Y1067979D03*
X1800083D03*
X1791383Y1074672D03*
X1800083D03*
X1791383Y1084711D03*
X1800083D03*
X1791383Y1091404D03*
X1800083D03*
X1791383Y1098097D03*
X1800083D03*
X1791383Y1104790D03*
X1800083D03*
X1791383Y1111483D03*
X1800083D03*
X1791383Y1121522D03*
X1800083D03*
X1791383Y1128215D03*
X1800083D03*
Y1134908D03*
X1791383D03*
Y1141601D03*
X1800083D03*
X1791383Y1148294D03*
X1800083D03*
X1791383Y1158333D03*
X1800083D03*
X1791383Y1165026D03*
X1800083D03*
X1791383Y1171719D03*
X1800083D03*
X1791383Y1178412D03*
X1800083D03*
X1791383Y1185105D03*
X1800083D03*
X1791383Y1195144D03*
X1800083D03*
X1791383Y1201837D03*
X1800083D03*
X1791383Y1208530D03*
X1800083D03*
X1791383Y1215223D03*
X1800083D03*
X1791383Y1221916D03*
X1800083D03*
X1791383Y1231955D03*
X1800083D03*
X1791383Y1238648D03*
X1800083D03*
X1791383Y1245341D03*
X1800083D03*
X1797088Y1273344D03*
X1794288D03*
X1804941Y770144D03*
X1813641D03*
X1804941Y776837D03*
X1813641D03*
X1804941Y783530D03*
X1813641D03*
X1804941Y793570D03*
X1813641D03*
X1804941Y800263D03*
X1813641D03*
X1804941Y806955D03*
X1813641D03*
X1804941Y813648D03*
X1813641D03*
X1804941Y820341D03*
X1813641D03*
X1804941Y830381D03*
X1813641D03*
X1804941Y843766D03*
X1813641D03*
X1804941Y837074D03*
X1813641D03*
X1804941Y850459D03*
X1813641D03*
X1804941Y857152D03*
X1813641D03*
Y867192D03*
X1804941D03*
Y873885D03*
X1813641D03*
X1804941Y880577D03*
X1813641D03*
X1804941Y887270D03*
X1813641D03*
X1804941Y893963D03*
X1813641D03*
X1804941Y904003D03*
X1813641D03*
X1804941Y910696D03*
X1813641D03*
X1804941Y917389D03*
X1813641D03*
X1804941Y924081D03*
X1813641D03*
X1804941Y930774D03*
X1813641D03*
X1804941Y940814D03*
X1813641D03*
X1804941Y947507D03*
X1813641D03*
X1804941Y954200D03*
X1813641D03*
X1804941Y964239D03*
X1813641D03*
X1804941Y970932D03*
X1813641D03*
X1804941Y977625D03*
X1813641D03*
X1804941Y984318D03*
X1813641D03*
X1804941Y991011D03*
X1813641D03*
X1804941Y1017782D03*
X1813641D03*
X1804941Y1024475D03*
X1813641D03*
X1804941Y1031168D03*
X1813641D03*
X1804941Y1037861D03*
X1813641D03*
X1804941Y1044554D03*
X1813641D03*
Y1057940D03*
X1804941D03*
Y1051247D03*
X1813641D03*
X1804941Y1064633D03*
X1813641D03*
Y1071326D03*
X1804941D03*
X1813641Y1078018D03*
X1804941D03*
X1813641Y1088058D03*
X1804941D03*
X1813641Y1094751D03*
X1804941D03*
X1813641Y1101444D03*
X1804941D03*
X1813641Y1108137D03*
X1804941D03*
X1813641Y1114829D03*
X1804941D03*
X1813641Y1124869D03*
X1804941D03*
X1813641Y1131562D03*
X1804941D03*
X1813641Y1138255D03*
X1804941D03*
X1813641Y1144948D03*
X1804941D03*
X1813641Y1151641D03*
X1804941D03*
X1813641Y1161680D03*
X1804941D03*
X1813641Y1168373D03*
X1804941D03*
X1813641Y1175066D03*
X1804941D03*
X1813641Y1181759D03*
X1804941D03*
X1813641Y1188452D03*
X1804941D03*
X1813641Y1198491D03*
X1804941D03*
X1813641Y1205184D03*
X1804941D03*
X1813641Y1211877D03*
X1804941D03*
X1813641Y1218570D03*
X1804941D03*
X1813641Y1225263D03*
X1804941D03*
X1813641Y1235302D03*
X1804941D03*
X1813641Y1241995D03*
X1804941D03*
X1813641Y1248688D03*
X1804941D03*
X1819054Y1253986D03*
X1818188Y1273044D03*
X1810788Y1273344D03*
X1807988D03*
X1815388Y1273044D03*
X1829783Y766798D03*
X1821083D03*
X1829783Y773491D03*
X1821083D03*
X1829783Y780184D03*
X1821083D03*
X1829783Y790223D03*
X1821083D03*
X1829783Y796916D03*
X1821083D03*
X1829783Y803609D03*
X1821083D03*
X1829783Y810302D03*
X1821083D03*
X1829783Y816995D03*
X1821083D03*
X1829783Y827034D03*
X1821083D03*
X1829783Y833727D03*
X1821083D03*
Y847113D03*
X1829783D03*
Y840420D03*
X1821083D03*
X1829783Y853806D03*
X1821083D03*
X1829783Y863845D03*
X1821083D03*
X1829783Y870538D03*
X1821083D03*
X1829783Y877231D03*
X1821083D03*
X1829783Y883924D03*
X1821083D03*
X1829783Y890617D03*
X1821083D03*
X1829783Y900656D03*
X1821083D03*
X1829783Y907349D03*
X1821083D03*
X1829783Y914042D03*
X1821083D03*
X1829783Y920735D03*
X1821083D03*
X1829783Y927428D03*
X1821083D03*
X1829783Y937467D03*
X1821083D03*
X1829783Y944160D03*
X1821083D03*
X1829783Y950853D03*
X1821083D03*
X1829783Y960892D03*
X1821083D03*
X1829783Y967585D03*
X1821083D03*
X1829783Y974278D03*
X1821083D03*
X1829783Y980971D03*
X1821083D03*
X1829783Y987664D03*
X1821083D03*
X1829783Y1017782D03*
X1821083D03*
X1829783Y1027822D03*
X1821083D03*
X1829783Y1034515D03*
X1821083D03*
X1829783Y1041207D03*
X1821083D03*
X1829783Y1047900D03*
X1821083D03*
X1829783Y1054593D03*
X1821083D03*
X1829783Y1061286D03*
X1821083D03*
X1829783Y1067979D03*
X1821083D03*
Y1074672D03*
X1829783D03*
X1821083Y1084711D03*
X1829783D03*
X1821083Y1091404D03*
X1829783D03*
X1821083Y1098097D03*
X1829783D03*
X1821083Y1104790D03*
X1829783D03*
X1821083Y1111483D03*
X1829783D03*
X1821083Y1121522D03*
X1829783D03*
X1821083Y1128215D03*
X1829783D03*
X1821083Y1134908D03*
X1829783D03*
X1821083Y1141601D03*
X1829783D03*
X1821083Y1148294D03*
X1829783D03*
X1821083Y1158333D03*
X1829783D03*
X1821083Y1165026D03*
X1829783D03*
X1821083Y1171719D03*
X1829783D03*
X1821083Y1178412D03*
X1829783D03*
X1821083Y1185105D03*
X1829783D03*
X1821083Y1195144D03*
X1829783D03*
X1821083Y1201837D03*
X1829783D03*
X1821083Y1208530D03*
X1829783D03*
X1821083Y1215223D03*
X1829783D03*
X1821083Y1221916D03*
X1829783D03*
X1821083Y1231955D03*
X1829783D03*
X1821083Y1238648D03*
X1829783D03*
Y1245341D03*
X1821083D03*
G54D58*
X841240Y1420330D03*
X1016240D03*
G54D64*
X986642Y-27947D03*
X986627Y-25432D03*
Y-21558D03*
X986642Y-17918D03*
X986627Y-15403D03*
Y-11529D03*
X986642Y-7889D03*
X986627Y-5374D03*
Y4655D03*
X986642Y2140D03*
X986627Y14684D03*
X986642Y12169D03*
X986627Y8529D03*
X986642Y22698D03*
X989910Y22684D03*
X986627Y19058D03*
Y25213D03*
X989895Y25199D03*
X1296019Y-35472D03*
Y-31598D03*
X1296034Y-37987D03*
Y-27958D03*
X1296019Y-25443D03*
Y-21569D03*
X1296034Y-17929D03*
X1296019Y-15414D03*
Y-11540D03*
X1296034Y-7900D03*
X1296019Y-5385D03*
Y4644D03*
X1296034Y2129D03*
X1296019Y-1511D03*
Y14673D03*
X1296034Y12158D03*
X1296019Y8518D03*
X1296034Y22687D03*
X1296019Y19047D03*
Y25202D03*
X1299302Y22673D03*
X1299287Y25188D03*
X1488393Y-27958D03*
X1488378Y-25443D03*
X1488393Y-37987D03*
X1488378Y-35472D03*
Y-31598D03*
X1488393Y-17929D03*
X1488378Y-15414D03*
Y-11540D03*
Y-21569D03*
X1488393Y2129D03*
X1488378Y4644D03*
X1488393Y-7900D03*
X1488378Y-5385D03*
Y-1511D03*
Y14673D03*
X1488393Y12158D03*
Y22687D03*
X1491661Y22673D03*
X1488378Y8518D03*
Y19047D03*
Y25202D03*
X1491646Y25188D03*
G54D72*
X1879155Y344948D03*
Y592848D03*
X1900275Y-19342D03*
X1889155Y344948D03*
Y592848D03*
X1900275Y716808D03*
X1910275Y-19342D03*
Y716808D03*
X1931395Y592868D03*
X1921395D03*
X1952395Y-19152D03*
X1942395D03*
X1963362Y593010D03*
X1984482Y-19180D03*
X1973362Y593010D03*
X1994482Y-19180D03*
X2015452Y593020D03*
X2005452D03*
X2026452Y-19000D03*
X2036452D03*
X2047419Y593162D03*
X2057419D03*
G54D25*
X57646Y12480D03*
X137272D03*
X186622D03*
X266858D03*
X315598D03*
X502528Y33268D03*
X582154D03*
X631504D03*
X711740D03*
X760480D03*
X1532055Y12480D03*
X1611681D03*
X1661031D03*
X1741267D03*
X1790007D03*
G54D65*
X1077638Y133866D03*
G54D47*
X460000Y278543D03*
G54D70*
X1771457Y1634646D03*
G54D59*
X900196Y175197D03*
X944684Y155216D03*
G54D79*
X1903086Y1318228D03*
X1902402Y1683256D03*
X1950484Y1683497D03*
X1993147Y1682875D03*
G54D77*
X1880836Y1317164D03*
X1881165Y1682207D03*
X1929695Y1683220D03*
X1971555Y1683130D03*
%LPC*%
G75*
G54D80*
G01X-6350Y-464479D02*
Y-539479D01*
X493650D01*
Y-464479D01*
X-6350D01*
G01X5650Y-529479D02*
Y-534479D01*
G01X4193Y-529479D02*
X7107D01*
G01X12017Y-534479D02*
X9483D01*
Y-529479D01*
X12017D01*
G01X11003Y-531896D02*
X9483D01*
G01X14583Y-529479D02*
Y-534479D01*
X17117D01*
G01X20950Y-534646D02*
X20823Y-534562D01*
Y-534396D01*
X20950Y-534312D01*
X21077Y-534396D01*
Y-534562D01*
X20950Y-534646D01*
G01Y-532396D02*
X20823Y-532312D01*
Y-532146D01*
X20950Y-532062D01*
X21077Y-532146D01*
Y-532312D01*
X20950Y-532396D01*
G01X25733Y-536146D02*
X25100Y-535312D01*
X24783Y-534479D01*
Y-531146D01*
X25100Y-530312D01*
X25733Y-529479D01*
G01X31150D02*
X30643Y-529646D01*
X30263Y-530062D01*
X30010Y-530562D01*
X29820Y-531229D01*
X29757Y-531979D01*
X29820Y-532729D01*
X30010Y-533396D01*
X30263Y-533896D01*
X30643Y-534312D01*
X31150Y-534479D01*
X31657Y-534312D01*
X32037Y-533896D01*
X32290Y-533396D01*
X32480Y-532729D01*
X32543Y-531979D01*
X32480Y-531229D01*
X32290Y-530562D01*
X32037Y-530062D01*
X31657Y-529646D01*
X31150Y-529479D01*
G01X34857Y-533479D02*
X35237Y-534062D01*
X35743Y-534396D01*
X36313Y-534479D01*
X36820Y-534396D01*
X37327Y-533979D01*
X37643Y-533479D01*
X37707Y-532979D01*
X37580Y-532396D01*
X37137Y-531979D01*
X36693Y-531812D01*
X36123D01*
G01X36693D02*
X37073Y-531562D01*
X37390Y-531146D01*
X37517Y-530646D01*
X37390Y-530146D01*
X37073Y-529729D01*
X36503Y-529479D01*
X35933Y-529562D01*
X35363Y-529896D01*
G01X41667Y-536146D02*
X42300Y-535312D01*
X42617Y-534479D01*
Y-531146D01*
X42300Y-530312D01*
X41667Y-529479D01*
G01X45057Y-533479D02*
X45437Y-534062D01*
X45943Y-534396D01*
X46513Y-534479D01*
X47020Y-534396D01*
X47527Y-533979D01*
X47843Y-533479D01*
X47907Y-532979D01*
X47780Y-532396D01*
X47337Y-531979D01*
X46893Y-531812D01*
X46323D01*
G01X46893D02*
X47273Y-531562D01*
X47590Y-531146D01*
X47717Y-530646D01*
X47590Y-530146D01*
X47273Y-529729D01*
X46703Y-529479D01*
X46133Y-529562D01*
X45563Y-529896D01*
G01X50347Y-530312D02*
X50727Y-529812D01*
X51170Y-529562D01*
X51677Y-529479D01*
X52310Y-529646D01*
X52753Y-530062D01*
X52880Y-530562D01*
X52817Y-531062D01*
X52563Y-531479D01*
X51297Y-532312D01*
X50727Y-532896D01*
X50347Y-533729D01*
X50220Y-534479D01*
X52880D01*
G01X56523D02*
X56650Y-533396D01*
X56840Y-532479D01*
X57093Y-531646D01*
X57410Y-530729D01*
X57917Y-529479D01*
X55383D01*
G01X60927Y-532812D02*
X62573D01*
G01X65647Y-530312D02*
X66027Y-529812D01*
X66470Y-529562D01*
X66977Y-529479D01*
X67610Y-529646D01*
X68053Y-530062D01*
X68180Y-530562D01*
X68117Y-531062D01*
X67863Y-531479D01*
X66597Y-532312D01*
X66027Y-532896D01*
X65647Y-533729D01*
X65520Y-534479D01*
X68180D01*
G01X70557Y-533479D02*
X70937Y-534062D01*
X71443Y-534396D01*
X72013Y-534479D01*
X72520Y-534396D01*
X73027Y-533979D01*
X73343Y-533479D01*
X73407Y-532979D01*
X73280Y-532396D01*
X72837Y-531979D01*
X72393Y-531812D01*
X71823D01*
G01X72393D02*
X72773Y-531562D01*
X73090Y-531146D01*
X73217Y-530646D01*
X73090Y-530146D01*
X72773Y-529729D01*
X72203Y-529479D01*
X71633Y-529562D01*
X71063Y-529896D01*
G01X77810Y-534479D02*
Y-529479D01*
X75467Y-533062D01*
X78633D01*
G01X80757Y-533729D02*
X81137Y-534146D01*
X81580Y-534396D01*
X82150Y-534479D01*
X82720Y-534312D01*
X83163Y-533979D01*
X83480Y-533396D01*
X83543Y-532729D01*
X83417Y-532062D01*
X83100Y-531646D01*
X82657Y-531312D01*
X82213Y-531229D01*
X81770Y-531312D01*
X81200Y-531646D01*
X81390Y-529479D01*
X83100D01*
G01X91147Y-534479D02*
Y-529479D01*
X93553D01*
G01X92667Y-531896D02*
X91147D01*
G01X95867Y-534479D02*
X97450Y-529479D01*
X99033Y-534479D01*
G01X98463Y-532729D02*
X96437D01*
G01X101220Y-534479D02*
X103880Y-529479D01*
G01X101220D02*
X103880Y-534479D01*
G01X107650Y-534646D02*
X107523Y-534562D01*
Y-534396D01*
X107650Y-534312D01*
X107777Y-534396D01*
Y-534562D01*
X107650Y-534646D01*
G01Y-532396D02*
X107523Y-532312D01*
Y-532146D01*
X107650Y-532062D01*
X107777Y-532146D01*
Y-532312D01*
X107650Y-532396D01*
G01X112433Y-536146D02*
X111800Y-535312D01*
X111483Y-534479D01*
Y-531146D01*
X111800Y-530312D01*
X112433Y-529479D01*
G01X117850D02*
X117343Y-529646D01*
X116963Y-530062D01*
X116710Y-530562D01*
X116520Y-531229D01*
X116457Y-531979D01*
X116520Y-532729D01*
X116710Y-533396D01*
X116963Y-533896D01*
X117343Y-534312D01*
X117850Y-534479D01*
X118357Y-534312D01*
X118737Y-533896D01*
X118990Y-533396D01*
X119180Y-532729D01*
X119243Y-531979D01*
X119180Y-531229D01*
X118990Y-530562D01*
X118737Y-530062D01*
X118357Y-529646D01*
X117850Y-529479D01*
G01X121557Y-533479D02*
X121937Y-534062D01*
X122443Y-534396D01*
X123013Y-534479D01*
X123520Y-534396D01*
X124027Y-533979D01*
X124343Y-533479D01*
X124407Y-532979D01*
X124280Y-532396D01*
X123837Y-531979D01*
X123393Y-531812D01*
X122823D01*
G01X123393D02*
X123773Y-531562D01*
X124090Y-531146D01*
X124217Y-530646D01*
X124090Y-530146D01*
X123773Y-529729D01*
X123203Y-529479D01*
X122633Y-529562D01*
X122063Y-529896D01*
G01X128367Y-536146D02*
X129000Y-535312D01*
X129317Y-534479D01*
Y-531146D01*
X129000Y-530312D01*
X128367Y-529479D01*
G01X131757Y-533479D02*
X132137Y-534062D01*
X132643Y-534396D01*
X133213Y-534479D01*
X133720Y-534396D01*
X134227Y-533979D01*
X134543Y-533479D01*
X134607Y-532979D01*
X134480Y-532396D01*
X134037Y-531979D01*
X133593Y-531812D01*
X133023D01*
G01X133593D02*
X133973Y-531562D01*
X134290Y-531146D01*
X134417Y-530646D01*
X134290Y-530146D01*
X133973Y-529729D01*
X133403Y-529479D01*
X132833Y-529562D01*
X132263Y-529896D01*
G01X137173Y-533896D02*
X137617Y-534312D01*
X138123Y-534479D01*
X138630Y-534312D01*
X139073Y-533812D01*
X139390Y-533062D01*
X139517Y-532312D01*
Y-531396D01*
X139390Y-530646D01*
X139073Y-529979D01*
X138693Y-529646D01*
X138250Y-529479D01*
X137743Y-529646D01*
X137363Y-529979D01*
X137110Y-530479D01*
X136983Y-531146D01*
X137110Y-531729D01*
X137427Y-532312D01*
X137807Y-532646D01*
X138250Y-532729D01*
X138757Y-532562D01*
X139137Y-532146D01*
X139517Y-531396D01*
G01X143223Y-534479D02*
X143350Y-533396D01*
X143540Y-532479D01*
X143793Y-531646D01*
X144110Y-530729D01*
X144617Y-529479D01*
X142083D01*
G01X147627Y-532812D02*
X149273D01*
G01X152157Y-533479D02*
X152537Y-534062D01*
X153043Y-534396D01*
X153613Y-534479D01*
X154120Y-534396D01*
X154627Y-533979D01*
X154943Y-533479D01*
X155007Y-532979D01*
X154880Y-532396D01*
X154437Y-531979D01*
X153993Y-531812D01*
X153423D01*
G01X153993D02*
X154373Y-531562D01*
X154690Y-531146D01*
X154817Y-530646D01*
X154690Y-530146D01*
X154373Y-529729D01*
X153803Y-529479D01*
X153233Y-529562D01*
X152663Y-529896D01*
G01X157447Y-532396D02*
X157890Y-531812D01*
X158270Y-531479D01*
X158777Y-531312D01*
X159220Y-531479D01*
X159537Y-531812D01*
X159790Y-532312D01*
X159853Y-532896D01*
X159790Y-533396D01*
X159537Y-533896D01*
X159157Y-534312D01*
X158713Y-534479D01*
X158207Y-534312D01*
X157763Y-533812D01*
X157510Y-533062D01*
X157447Y-532229D01*
X157573Y-531146D01*
X157763Y-530562D01*
X158080Y-529979D01*
X158523Y-529562D01*
X158967Y-529479D01*
X159410Y-529646D01*
X159727Y-530062D01*
G01X163750Y-534479D02*
Y-529479D01*
X162990Y-530479D01*
G01Y-534479D02*
X164510D01*
G01X169610D02*
Y-529479D01*
X167267Y-533062D01*
X170433D01*
G01X188650Y-464479D02*
Y-539479D01*
G01Y-514479D02*
X291650D01*
Y-489479D01*
G01X188650D02*
X291650D01*
G01Y-464479D02*
Y-539479D01*
G01X293650Y-464479D02*
Y-539479D01*
G01X299157Y-524479D02*
Y-519479D01*
X300423D01*
X300930Y-519729D01*
X301310Y-520062D01*
X301627Y-520562D01*
X301880Y-521146D01*
X301943Y-521979D01*
X301880Y-522812D01*
X301627Y-523396D01*
X301310Y-523896D01*
X300930Y-524229D01*
X300423Y-524479D01*
X299157D01*
G01X304067D02*
X305650Y-519479D01*
X307233Y-524479D01*
G01X306663Y-522729D02*
X304637D01*
G01X310750Y-519479D02*
Y-524479D01*
G01X309293Y-519479D02*
X312207D01*
G01X317117Y-524479D02*
X314583D01*
Y-519479D01*
X317117D01*
G01X316103Y-521896D02*
X314583D01*
G01X320950Y-524646D02*
X320823Y-524562D01*
Y-524396D01*
X320950Y-524312D01*
X321077Y-524396D01*
Y-524562D01*
X320950Y-524646D01*
G01Y-522396D02*
X320823Y-522312D01*
Y-522146D01*
X320950Y-522062D01*
X321077Y-522146D01*
Y-522312D01*
X320950Y-522396D01*
G01X299283Y-499479D02*
Y-494479D01*
X300803D01*
X301310Y-494729D01*
X301690Y-495312D01*
X301817Y-495979D01*
X301690Y-496646D01*
X301373Y-497146D01*
X300803Y-497396D01*
X299283D01*
G01X304510Y-499646D02*
X306790Y-494479D01*
G01X309293Y-499479D02*
Y-494479D01*
X312207Y-499479D01*
Y-494479D01*
G01X315850Y-499646D02*
X315723Y-499562D01*
Y-499396D01*
X315850Y-499312D01*
X315977Y-499396D01*
Y-499562D01*
X315850Y-499646D01*
G01Y-497396D02*
X315723Y-497312D01*
Y-497146D01*
X315850Y-497062D01*
X315977Y-497146D01*
Y-497312D01*
X315850Y-497396D01*
G01X293650Y-514479D02*
X493650D01*
G01X293650Y-489479D02*
X493650D01*
G01X299283Y-474479D02*
Y-469479D01*
X300803D01*
X301310Y-469729D01*
X301690Y-470312D01*
X301817Y-470979D01*
X301690Y-471646D01*
X301373Y-472146D01*
X300803Y-472396D01*
X299283D01*
G01X304383Y-474479D02*
Y-469479D01*
X305967D01*
X306473Y-469729D01*
X306790Y-470062D01*
X306917Y-470729D01*
X306790Y-471396D01*
X306410Y-471812D01*
X305967Y-472062D01*
X304383D01*
G01X305967D02*
X306917Y-474479D01*
G01X310750D02*
X310243Y-474396D01*
X309800Y-474062D01*
X309420Y-473562D01*
X309167Y-472979D01*
X309040Y-472312D01*
Y-471646D01*
X309167Y-470979D01*
X309420Y-470396D01*
X309800Y-469896D01*
X310243Y-469562D01*
X310750Y-469479D01*
X311257Y-469562D01*
X311700Y-469896D01*
X312080Y-470396D01*
X312333Y-470979D01*
X312460Y-471646D01*
Y-472312D01*
X312333Y-472979D01*
X312080Y-473562D01*
X311700Y-474062D01*
X311257Y-474396D01*
X310750Y-474479D01*
G01X314583Y-473479D02*
X314900Y-473979D01*
X315280Y-474312D01*
X315723Y-474479D01*
X316230Y-474312D01*
X316610Y-473979D01*
X316990Y-473479D01*
X317117Y-472812D01*
Y-469479D01*
G01X322217Y-474479D02*
X319683D01*
Y-469479D01*
X322217D01*
G01X321203Y-471896D02*
X319683D01*
G01X327443Y-469896D02*
X327063Y-469646D01*
X326620Y-469479D01*
X326113D01*
X325543Y-469729D01*
X325100Y-470146D01*
X324783Y-470646D01*
X324530Y-471479D01*
X324467Y-472229D01*
X324593Y-472979D01*
X324783Y-473479D01*
X325163Y-473979D01*
X325607Y-474312D01*
X326050Y-474479D01*
X326493D01*
X326937Y-474312D01*
X327317Y-474062D01*
X327633Y-473729D01*
G01X331150Y-469479D02*
Y-474479D01*
G01X329693Y-469479D02*
X332607D01*
G01X336250Y-474646D02*
X336123Y-474562D01*
Y-474396D01*
X336250Y-474312D01*
X336377Y-474396D01*
Y-474562D01*
X336250Y-474646D01*
G01Y-472396D02*
X336123Y-472312D01*
Y-472146D01*
X336250Y-472062D01*
X336377Y-472146D01*
Y-472312D01*
X336250Y-472396D01*
G01X408650Y-514479D02*
Y-539479D01*
G01X411283Y-516979D02*
Y-521979D01*
X413817D01*
G01X416890Y-516979D02*
X418410D01*
G01X417650D02*
Y-521979D01*
G01X416890D02*
X418410D01*
G01X423257Y-519312D02*
X423510Y-519062D01*
X423700Y-518646D01*
X423827Y-518062D01*
X423700Y-517562D01*
X423447Y-517229D01*
X423003Y-516979D01*
X421293D01*
Y-521979D01*
X423383D01*
X423827Y-521646D01*
X424080Y-521146D01*
X424207Y-520562D01*
X424080Y-519979D01*
X423700Y-519479D01*
X423257Y-519312D01*
X421293D01*
G01X427850Y-522146D02*
X427723Y-522062D01*
Y-521896D01*
X427850Y-521812D01*
X427977Y-521896D01*
Y-522062D01*
X427850Y-522146D01*
G01Y-519896D02*
X427723Y-519812D01*
Y-519646D01*
X427850Y-519562D01*
X427977Y-519646D01*
Y-519812D01*
X427850Y-519896D01*
G01X451650Y-514479D02*
Y-539479D01*
G01Y-489479D02*
Y-514479D01*
G01X456663Y-541646D02*
X456770Y-541521D01*
X456850Y-541312D01*
X456903Y-541021D01*
X456850Y-540771D01*
X456743Y-540604D01*
X456557Y-540479D01*
X455837D01*
Y-542979D01*
X456717D01*
X456903Y-542812D01*
X457010Y-542562D01*
X457063Y-542271D01*
X457010Y-541979D01*
X456850Y-541729D01*
X456663Y-541646D01*
X455837D01*
G01X459130Y-542979D02*
Y-541312D01*
G01Y-541604D02*
X459023Y-541437D01*
X458863Y-541354D01*
X458677Y-541312D01*
X458490Y-541396D01*
X458330Y-541562D01*
X458223Y-541812D01*
X458170Y-542146D01*
X458223Y-542479D01*
X458330Y-542729D01*
X458490Y-542896D01*
X458677Y-542979D01*
X458863Y-542937D01*
X459023Y-542812D01*
X459130Y-542646D01*
G01X460450Y-542687D02*
X460583Y-542854D01*
X460770Y-542979D01*
X460930D01*
X461090Y-542896D01*
X461197Y-542771D01*
X461250Y-542604D01*
X461223Y-542354D01*
X461117Y-542229D01*
X460637Y-541979D01*
X460530Y-541687D01*
X460583Y-541479D01*
X460690Y-541354D01*
X460850Y-541312D01*
X461010Y-541354D01*
X461170Y-541479D01*
G01X462650Y-541854D02*
X463503D01*
X463423Y-541562D01*
X463290Y-541396D01*
X463103Y-541312D01*
X462917Y-541354D01*
X462757Y-541479D01*
X462650Y-541771D01*
X462597Y-542021D01*
Y-542271D01*
X462650Y-542521D01*
X462783Y-542771D01*
X462943Y-542937D01*
X463130Y-542979D01*
X463317Y-542896D01*
X463503Y-542646D01*
G01X464770Y-542979D02*
Y-540479D01*
G01Y-541729D02*
X464903Y-541479D01*
X465063Y-541354D01*
X465223Y-541312D01*
X465463Y-541396D01*
X465623Y-541562D01*
X465730Y-541854D01*
Y-542187D01*
X465677Y-542521D01*
X465570Y-542771D01*
X465383Y-542937D01*
X465223Y-542979D01*
X465063Y-542937D01*
X464903Y-542812D01*
X464770Y-542604D01*
G01X467450Y-542979D02*
X467290Y-542937D01*
X467130Y-542771D01*
X467023Y-542479D01*
X466970Y-542146D01*
X467023Y-541812D01*
X467130Y-541521D01*
X467290Y-541354D01*
X467450Y-541312D01*
X467610Y-541354D01*
X467770Y-541521D01*
X467877Y-541812D01*
X467903Y-542146D01*
X467877Y-542479D01*
X467770Y-542771D01*
X467610Y-542937D01*
X467450Y-542979D01*
G01X470130D02*
Y-541312D01*
G01Y-541604D02*
X470023Y-541437D01*
X469863Y-541354D01*
X469677Y-541312D01*
X469490Y-541396D01*
X469330Y-541562D01*
X469223Y-541812D01*
X469170Y-542146D01*
X469223Y-542479D01*
X469330Y-542729D01*
X469490Y-542896D01*
X469677Y-542979D01*
X469863Y-542937D01*
X470023Y-542812D01*
X470130Y-542646D01*
G01X471477Y-542979D02*
Y-541312D01*
G01Y-541646D02*
X471610Y-541479D01*
X471743Y-541354D01*
X471930Y-541312D01*
X472063Y-541354D01*
X472223Y-541479D01*
G01X474530Y-540479D02*
Y-542979D01*
G01Y-542604D02*
X474423Y-542812D01*
X474263Y-542937D01*
X474077Y-542979D01*
X473863Y-542896D01*
X473703Y-542687D01*
X473597Y-542437D01*
X473570Y-542146D01*
X473597Y-541854D01*
X473703Y-541604D01*
X473863Y-541396D01*
X474077Y-541312D01*
X474263Y-541354D01*
X474397Y-541437D01*
X474530Y-541604D01*
G01X477917Y-542979D02*
Y-540479D01*
X478583D01*
X478797Y-540604D01*
X478930Y-540771D01*
X478983Y-541104D01*
X478930Y-541437D01*
X478770Y-541646D01*
X478583Y-541771D01*
X477917D01*
G01X478583D02*
X478983Y-542979D01*
G01X480250Y-541854D02*
X481103D01*
X481023Y-541562D01*
X480890Y-541396D01*
X480703Y-541312D01*
X480517Y-541354D01*
X480357Y-541479D01*
X480250Y-541771D01*
X480197Y-542021D01*
Y-542271D01*
X480250Y-542521D01*
X480383Y-542771D01*
X480543Y-542937D01*
X480730Y-542979D01*
X480917Y-542896D01*
X481103Y-542646D01*
G01X482370Y-541312D02*
X482850Y-542979D01*
X483330Y-541312D01*
G01X485050Y-543062D02*
X484997Y-543021D01*
Y-542937D01*
X485050Y-542896D01*
X485103Y-542937D01*
Y-543021D01*
X485050Y-543062D01*
G01X487250Y-542979D02*
X487437Y-542937D01*
X487650Y-542812D01*
X487783Y-542604D01*
X487837Y-542312D01*
X487783Y-542021D01*
X487623Y-541771D01*
X487383Y-541646D01*
X487117D01*
X486957Y-541562D01*
X486823Y-541354D01*
X486770Y-541062D01*
X486850Y-540771D01*
X487037Y-540562D01*
X487250Y-540479D01*
X487463Y-540562D01*
X487650Y-540771D01*
X487730Y-541062D01*
X487677Y-541354D01*
X487543Y-541562D01*
X487383Y-541646D01*
X487117D01*
X486877Y-541771D01*
X486717Y-542021D01*
X486663Y-542312D01*
X486717Y-542604D01*
X486850Y-542812D01*
X487063Y-542937D01*
X487250Y-542979D01*
G01X489663Y-541646D02*
X489770Y-541521D01*
X489850Y-541312D01*
X489903Y-541021D01*
X489850Y-540771D01*
X489743Y-540604D01*
X489557Y-540479D01*
X488837D01*
Y-542979D01*
X489717D01*
X489903Y-542812D01*
X490010Y-542562D01*
X490063Y-542271D01*
X490010Y-541979D01*
X489850Y-541729D01*
X489663Y-541646D01*
X488837D01*
G01X455550Y-516979D02*
Y-521979D01*
G01X454093Y-516979D02*
X457007D01*
G01X460650Y-521979D02*
X460270Y-521896D01*
X459890Y-521562D01*
X459637Y-520979D01*
X459510Y-520312D01*
X459637Y-519646D01*
X459890Y-519062D01*
X460270Y-518729D01*
X460650Y-518646D01*
X461030Y-518729D01*
X461410Y-519062D01*
X461663Y-519646D01*
X461727Y-520312D01*
X461663Y-520979D01*
X461410Y-521562D01*
X461030Y-521896D01*
X460650Y-521979D01*
G01X465750D02*
X465370Y-521896D01*
X464990Y-521562D01*
X464737Y-520979D01*
X464610Y-520312D01*
X464737Y-519646D01*
X464990Y-519062D01*
X465370Y-518729D01*
X465750Y-518646D01*
X466130Y-518729D01*
X466510Y-519062D01*
X466763Y-519646D01*
X466827Y-520312D01*
X466763Y-520979D01*
X466510Y-521562D01*
X466130Y-521896D01*
X465750Y-521979D01*
G01X470850D02*
Y-516979D01*
G01X475950Y-522146D02*
X475823Y-522062D01*
Y-521896D01*
X475950Y-521812D01*
X476077Y-521896D01*
Y-522062D01*
X475950Y-522146D01*
G01Y-519896D02*
X475823Y-519812D01*
Y-519646D01*
X475950Y-519562D01*
X476077Y-519646D01*
Y-519812D01*
X475950Y-519896D01*
G01X454283Y-496979D02*
Y-491979D01*
X455867D01*
X456373Y-492229D01*
X456690Y-492562D01*
X456817Y-493229D01*
X456690Y-493896D01*
X456310Y-494312D01*
X455867Y-494562D01*
X454283D01*
G01X455867D02*
X456817Y-496979D01*
G01X461917D02*
X459383D01*
Y-491979D01*
X461917D01*
G01X460903Y-494396D02*
X459383D01*
G01X464167Y-491979D02*
X465750Y-496979D01*
X467333Y-491979D01*
G01X470850Y-497146D02*
X470723Y-497062D01*
Y-496896D01*
X470850Y-496812D01*
X470977Y-496896D01*
Y-497062D01*
X470850Y-497146D01*
G01Y-494896D02*
X470723Y-494812D01*
Y-494646D01*
X470850Y-494562D01*
X470977Y-494646D01*
Y-494812D01*
X470850Y-494896D01*
G01X-984580Y-698988D02*
Y4193602D01*
X5868320D01*
Y-698988D01*
X-984580D01*
G01X7723Y-521204D02*
X7253Y-520889D01*
X6705Y-520679D01*
X6078D01*
X5373Y-520994D01*
X4825Y-521519D01*
X4433Y-522149D01*
X4120Y-523199D01*
X4042Y-524144D01*
X4198Y-525089D01*
X4433Y-525719D01*
X4903Y-526349D01*
X5452Y-526769D01*
X6000Y-526979D01*
X6548D01*
X7097Y-526769D01*
X7567Y-526454D01*
X7958Y-526034D01*
G01X11360Y-520679D02*
X13240D01*
G01X12300D02*
Y-526979D01*
G01X11360D02*
X13240D01*
G01X18600Y-520679D02*
Y-526979D01*
G01X16798Y-520679D02*
X20402D01*
G01X24900Y-526979D02*
Y-524144D01*
X23333Y-520679D01*
G01X26467D02*
X24900Y-524144D01*
G01X35777Y-525719D02*
X36247Y-526454D01*
X36873Y-526874D01*
X37578Y-526979D01*
X38205Y-526874D01*
X38832Y-526349D01*
X39223Y-525719D01*
X39302Y-525089D01*
X39145Y-524354D01*
X38597Y-523829D01*
X38048Y-523619D01*
X37343D01*
G01X38048D02*
X38518Y-523304D01*
X38910Y-522779D01*
X39067Y-522149D01*
X38910Y-521519D01*
X38518Y-520994D01*
X37813Y-520679D01*
X37108Y-520784D01*
X36403Y-521204D01*
G01X42077Y-525719D02*
X42547Y-526454D01*
X43173Y-526874D01*
X43878Y-526979D01*
X44505Y-526874D01*
X45132Y-526349D01*
X45523Y-525719D01*
X45602Y-525089D01*
X45445Y-524354D01*
X44897Y-523829D01*
X44348Y-523619D01*
X43643D01*
G01X44348D02*
X44818Y-523304D01*
X45210Y-522779D01*
X45367Y-522149D01*
X45210Y-521519D01*
X44818Y-520994D01*
X44113Y-520679D01*
X43408Y-520784D01*
X42703Y-521204D01*
G01X48377Y-525719D02*
X48847Y-526454D01*
X49473Y-526874D01*
X50178Y-526979D01*
X50805Y-526874D01*
X51432Y-526349D01*
X51823Y-525719D01*
X51902Y-525089D01*
X51745Y-524354D01*
X51197Y-523829D01*
X50648Y-523619D01*
X49943D01*
G01X50648D02*
X51118Y-523304D01*
X51510Y-522779D01*
X51667Y-522149D01*
X51510Y-521519D01*
X51118Y-520994D01*
X50413Y-520679D01*
X49708Y-520784D01*
X49003Y-521204D01*
G01X56243Y-526979D02*
X56400Y-525614D01*
X56635Y-524459D01*
X56948Y-523409D01*
X57340Y-522254D01*
X57967Y-520679D01*
X54833D01*
G01X62543Y-526979D02*
X62700Y-525614D01*
X62935Y-524459D01*
X63248Y-523409D01*
X63640Y-522254D01*
X64267Y-520679D01*
X61133D01*
G01X68843Y-528134D02*
X69157Y-526769D01*
G01X75300Y-520679D02*
Y-526979D01*
G01X73498Y-520679D02*
X77102D01*
G01X79642Y-526979D02*
X81600Y-520679D01*
X83558Y-526979D01*
G01X82853Y-524774D02*
X80347D01*
G01X86960Y-520679D02*
X88840D01*
G01X87900D02*
Y-526979D01*
G01X86960D02*
X88840D01*
G01X91850Y-520679D02*
X92947Y-526979D01*
X94200Y-520679D01*
X95453Y-526979D01*
X96550Y-520679D01*
G01X98542Y-526979D02*
X100500Y-520679D01*
X102458Y-526979D01*
G01X101753Y-524774D02*
X99247D01*
G01X104998Y-526979D02*
Y-520679D01*
X108602Y-526979D01*
Y-520679D01*
G01X119008Y-529079D02*
X118225Y-528029D01*
X117833Y-526979D01*
Y-522779D01*
X118225Y-521729D01*
X119008Y-520679D01*
G01X130433Y-526979D02*
Y-520679D01*
X132392D01*
X133018Y-520994D01*
X133410Y-521414D01*
X133567Y-522254D01*
X133410Y-523094D01*
X132940Y-523619D01*
X132392Y-523934D01*
X130433D01*
G01X132392D02*
X133567Y-526979D01*
G01X138300Y-527189D02*
X138143Y-527084D01*
Y-526874D01*
X138300Y-526769D01*
X138457Y-526874D01*
Y-527084D01*
X138300Y-527189D01*
G01X144600Y-526979D02*
X143973Y-526874D01*
X143425Y-526454D01*
X142955Y-525824D01*
X142642Y-525089D01*
X142485Y-524249D01*
Y-523409D01*
X142642Y-522569D01*
X142955Y-521834D01*
X143425Y-521204D01*
X143973Y-520784D01*
X144600Y-520679D01*
X145227Y-520784D01*
X145775Y-521204D01*
X146245Y-521834D01*
X146558Y-522569D01*
X146715Y-523409D01*
Y-524249D01*
X146558Y-525089D01*
X146245Y-525824D01*
X145775Y-526454D01*
X145227Y-526874D01*
X144600Y-526979D01*
G01X150900Y-527189D02*
X150743Y-527084D01*
Y-526874D01*
X150900Y-526769D01*
X151057Y-526874D01*
Y-527084D01*
X150900Y-527189D01*
G01X158923Y-521204D02*
X158453Y-520889D01*
X157905Y-520679D01*
X157278D01*
X156573Y-520994D01*
X156025Y-521519D01*
X155633Y-522149D01*
X155320Y-523199D01*
X155242Y-524144D01*
X155398Y-525089D01*
X155633Y-525719D01*
X156103Y-526349D01*
X156652Y-526769D01*
X157200Y-526979D01*
X157748D01*
X158297Y-526769D01*
X158767Y-526454D01*
X159158Y-526034D01*
G01X163500Y-527189D02*
X163343Y-527084D01*
Y-526874D01*
X163500Y-526769D01*
X163657Y-526874D01*
Y-527084D01*
X163500Y-527189D01*
G01X170192Y-529079D02*
X170975Y-528029D01*
X171367Y-526979D01*
Y-522779D01*
X170975Y-521729D01*
X170192Y-520679D01*
G01X6470Y-513829D02*
X8037D01*
Y-515719D01*
X7567Y-516349D01*
X7018Y-516769D01*
X6235Y-516979D01*
X5452Y-516769D01*
X4903Y-516349D01*
X4433Y-515719D01*
X4120Y-514984D01*
X3963Y-514144D01*
Y-513409D01*
X4120Y-512779D01*
X4433Y-512044D01*
X4903Y-511414D01*
X5373Y-510994D01*
X6000Y-510679D01*
X6548D01*
X7175Y-510889D01*
X7645Y-511309D01*
G01X10577Y-510679D02*
Y-515194D01*
X10890Y-516139D01*
X11517Y-516769D01*
X12300Y-516979D01*
X13083Y-516769D01*
X13710Y-516139D01*
X14023Y-515194D01*
Y-510679D01*
G01X17660D02*
X19540D01*
G01X18600D02*
Y-516979D01*
G01X17660D02*
X19540D01*
G01X23255Y-516139D02*
X23882Y-516664D01*
X24587Y-516979D01*
X25213D01*
X25840Y-516664D01*
X26310Y-516139D01*
X26545Y-515404D01*
X26388Y-514669D01*
X25997Y-514039D01*
X25292Y-513619D01*
X24352Y-513409D01*
X23803Y-512989D01*
X23568Y-512254D01*
X23725Y-511519D01*
X24117Y-510994D01*
X24665Y-510679D01*
X25213D01*
X25762Y-510889D01*
X26232Y-511414D01*
G01X29555Y-516979D02*
Y-510679D01*
G01X32845D02*
Y-516979D01*
G01Y-513829D02*
X29555D01*
G01X35542Y-516979D02*
X37500Y-510679D01*
X39458Y-516979D01*
G01X38753Y-514774D02*
X36247D01*
G01X41998Y-516979D02*
Y-510679D01*
X45602Y-516979D01*
Y-510679D01*
G01X54677Y-516979D02*
Y-510679D01*
X56243D01*
X56870Y-510994D01*
X57340Y-511414D01*
X57732Y-512044D01*
X58045Y-512779D01*
X58123Y-513829D01*
X58045Y-514879D01*
X57732Y-515614D01*
X57340Y-516244D01*
X56870Y-516664D01*
X56243Y-516979D01*
X54677D01*
G01X61760Y-510679D02*
X63640D01*
G01X62700D02*
Y-516979D01*
G01X61760D02*
X63640D01*
G01X67355Y-516139D02*
X67982Y-516664D01*
X68687Y-516979D01*
X69313D01*
X69940Y-516664D01*
X70410Y-516139D01*
X70645Y-515404D01*
X70488Y-514669D01*
X70097Y-514039D01*
X69392Y-513619D01*
X68452Y-513409D01*
X67903Y-512989D01*
X67668Y-512254D01*
X67825Y-511519D01*
X68217Y-510994D01*
X68765Y-510679D01*
X69313D01*
X69862Y-510889D01*
X70332Y-511414D01*
G01X75300Y-510679D02*
Y-516979D01*
G01X73498Y-510679D02*
X77102D01*
G01X81600Y-517189D02*
X81443Y-517084D01*
Y-516874D01*
X81600Y-516769D01*
X81757Y-516874D01*
Y-517084D01*
X81600Y-517189D01*
G01X87743Y-518134D02*
X88057Y-516769D01*
G01X94200Y-510679D02*
Y-516979D01*
G01X92398Y-510679D02*
X96002D01*
G01X98542Y-516979D02*
X100500Y-510679D01*
X102458Y-516979D01*
G01X101753Y-514774D02*
X99247D01*
G01X106800Y-516979D02*
X106173Y-516874D01*
X105625Y-516454D01*
X105155Y-515824D01*
X104842Y-515089D01*
X104685Y-514249D01*
Y-513409D01*
X104842Y-512569D01*
X105155Y-511834D01*
X105625Y-511204D01*
X106173Y-510784D01*
X106800Y-510679D01*
X107427Y-510784D01*
X107975Y-511204D01*
X108445Y-511834D01*
X108758Y-512569D01*
X108915Y-513409D01*
Y-514249D01*
X108758Y-515089D01*
X108445Y-515824D01*
X107975Y-516454D01*
X107427Y-516874D01*
X106800Y-516979D01*
G01X113100D02*
Y-514144D01*
X111533Y-510679D01*
G01X114667D02*
X113100Y-514144D01*
G01X117677Y-510679D02*
Y-515194D01*
X117990Y-516139D01*
X118617Y-516769D01*
X119400Y-516979D01*
X120183Y-516769D01*
X120810Y-516139D01*
X121123Y-515194D01*
Y-510679D01*
G01X123742Y-516979D02*
X125700Y-510679D01*
X127658Y-516979D01*
G01X126953Y-514774D02*
X124447D01*
G01X130198Y-516979D02*
Y-510679D01*
X133802Y-516979D01*
Y-510679D01*
G01X4198Y-506979D02*
Y-500679D01*
X7802Y-506979D01*
Y-500679D01*
G01X12300Y-506979D02*
X11673Y-506874D01*
X11125Y-506454D01*
X10655Y-505824D01*
X10342Y-505089D01*
X10185Y-504249D01*
Y-503409D01*
X10342Y-502569D01*
X10655Y-501834D01*
X11125Y-501204D01*
X11673Y-500784D01*
X12300Y-500679D01*
X12927Y-500784D01*
X13475Y-501204D01*
X13945Y-501834D01*
X14258Y-502569D01*
X14415Y-503409D01*
Y-504249D01*
X14258Y-505089D01*
X13945Y-505824D01*
X13475Y-506454D01*
X12927Y-506874D01*
X12300Y-506979D01*
G01X18600Y-507189D02*
X18443Y-507084D01*
Y-506874D01*
X18600Y-506769D01*
X18757Y-506874D01*
Y-507084D01*
X18600Y-507189D01*
G01X23412Y-501729D02*
X23882Y-501099D01*
X24430Y-500784D01*
X25057Y-500679D01*
X25840Y-500889D01*
X26388Y-501414D01*
X26545Y-502044D01*
X26467Y-502674D01*
X26153Y-503199D01*
X24587Y-504249D01*
X23882Y-504984D01*
X23412Y-506034D01*
X23255Y-506979D01*
X26545D01*
G01X31200D02*
Y-500679D01*
X30260Y-501939D01*
G01Y-506979D02*
X32140D01*
G01X37500D02*
Y-500679D01*
X36560Y-501939D01*
G01Y-506979D02*
X38440D01*
G01X43643Y-508134D02*
X43957Y-506769D01*
G01X47750Y-500679D02*
X48847Y-506979D01*
X50100Y-500679D01*
X51353Y-506979D01*
X52450Y-500679D01*
G01X57967Y-506979D02*
X54833D01*
Y-500679D01*
X57967D01*
G01X56713Y-503724D02*
X54833D01*
G01X60898Y-506979D02*
Y-500679D01*
X64502Y-506979D01*
Y-500679D01*
G01X67355Y-506979D02*
Y-500679D01*
G01X70645D02*
Y-506979D01*
G01Y-503829D02*
X67355D01*
G01X73577Y-500679D02*
Y-505194D01*
X73890Y-506139D01*
X74517Y-506769D01*
X75300Y-506979D01*
X76083Y-506769D01*
X76710Y-506139D01*
X77023Y-505194D01*
Y-500679D01*
G01X79642Y-506979D02*
X81600Y-500679D01*
X83558Y-506979D01*
G01X82853Y-504774D02*
X80347D01*
G01X92712Y-501729D02*
X93182Y-501099D01*
X93730Y-500784D01*
X94357Y-500679D01*
X95140Y-500889D01*
X95688Y-501414D01*
X95845Y-502044D01*
X95767Y-502674D01*
X95453Y-503199D01*
X93887Y-504249D01*
X93182Y-504984D01*
X92712Y-506034D01*
X92555Y-506979D01*
X95845D01*
G01X98698D02*
Y-500679D01*
X102302Y-506979D01*
Y-500679D01*
G01X105077Y-506979D02*
Y-500679D01*
X106643D01*
X107270Y-500994D01*
X107740Y-501414D01*
X108132Y-502044D01*
X108445Y-502779D01*
X108523Y-503829D01*
X108445Y-504879D01*
X108132Y-505614D01*
X107740Y-506244D01*
X107270Y-506664D01*
X106643Y-506979D01*
X105077D01*
G01X117833D02*
Y-500679D01*
X119792D01*
X120418Y-500994D01*
X120810Y-501414D01*
X120967Y-502254D01*
X120810Y-503094D01*
X120340Y-503619D01*
X119792Y-503934D01*
X117833D01*
G01X119792D02*
X120967Y-506979D01*
G01X123977D02*
Y-500679D01*
X125543D01*
X126170Y-500994D01*
X126640Y-501414D01*
X127032Y-502044D01*
X127345Y-502779D01*
X127423Y-503829D01*
X127345Y-504879D01*
X127032Y-505614D01*
X126640Y-506244D01*
X126170Y-506664D01*
X125543Y-506979D01*
X123977D01*
G01X132000Y-507189D02*
X131843Y-507084D01*
Y-506874D01*
X132000Y-506769D01*
X132157Y-506874D01*
Y-507084D01*
X132000Y-507189D01*
G01X28300Y-494279D02*
X25780Y-493862D01*
X23575Y-492196D01*
X21685Y-489696D01*
X20425Y-486779D01*
X19795Y-483446D01*
Y-480112D01*
X20425Y-476779D01*
X21685Y-473862D01*
X23575Y-471363D01*
X25780Y-469696D01*
X28300Y-469279D01*
X30820Y-469696D01*
X33025Y-471363D01*
X34915Y-473862D01*
X36175Y-476779D01*
X36805Y-480112D01*
Y-483446D01*
X36175Y-486779D01*
X34915Y-489696D01*
X33025Y-492196D01*
X30820Y-493862D01*
X28300Y-494279D01*
G01X30820Y-487612D02*
X34600Y-494279D01*
G01X48145Y-477613D02*
Y-489279D01*
X49405Y-492196D01*
X51295Y-493862D01*
X53500Y-494279D01*
X55705Y-493862D01*
X57595Y-492196D01*
X58855Y-489279D01*
G01Y-494279D02*
Y-477613D01*
G01X84370Y-494279D02*
Y-477613D01*
G01Y-480529D02*
X83110Y-478863D01*
X81220Y-478029D01*
X79015Y-477613D01*
X76810Y-478446D01*
X74920Y-480112D01*
X73660Y-482613D01*
X73030Y-485946D01*
X73660Y-489279D01*
X74920Y-491780D01*
X76810Y-493446D01*
X79015Y-494279D01*
X81220Y-493862D01*
X83110Y-492613D01*
X84370Y-490946D01*
G01X98545Y-494279D02*
Y-477613D01*
G01Y-481779D02*
X99805Y-479696D01*
X101695Y-478029D01*
X104215Y-477613D01*
X106420Y-478029D01*
X108310Y-479696D01*
X109255Y-482613D01*
Y-494279D01*
G01X129100Y-469279D02*
Y-494279D01*
G01X124690Y-477613D02*
X133510D01*
G01X159970Y-494279D02*
Y-477613D01*
G01Y-480529D02*
X158710Y-478863D01*
X156820Y-478029D01*
X154615Y-477613D01*
X152410Y-478446D01*
X150520Y-480112D01*
X149260Y-482613D01*
X148630Y-485946D01*
X149260Y-489279D01*
X150520Y-491780D01*
X152410Y-493446D01*
X154615Y-494279D01*
X156820Y-493862D01*
X158710Y-492613D01*
X159970Y-490946D01*
G01X199650Y-473979D02*
Y-481979D01*
X203650D01*
G01X211450D02*
Y-476646D01*
G01Y-477579D02*
X211050Y-477046D01*
X210450Y-476779D01*
X209750Y-476646D01*
X209050Y-476912D01*
X208450Y-477446D01*
X208050Y-478246D01*
X207850Y-479312D01*
X208050Y-480379D01*
X208450Y-481179D01*
X209050Y-481712D01*
X209750Y-481979D01*
X210450Y-481846D01*
X211050Y-481446D01*
X211450Y-480913D01*
G01X215550Y-484379D02*
X216150Y-484646D01*
X216950Y-484379D01*
X217450Y-483846D01*
X217850Y-483179D01*
X218450Y-481046D01*
X219750Y-476646D01*
G01X216550D02*
X218450Y-481046D01*
G01X224150Y-478379D02*
X227350D01*
X227050Y-477446D01*
X226550Y-476912D01*
X225850Y-476646D01*
X225150Y-476779D01*
X224550Y-477179D01*
X224150Y-478112D01*
X223950Y-478913D01*
Y-479712D01*
X224150Y-480512D01*
X224650Y-481312D01*
X225250Y-481846D01*
X225950Y-481979D01*
X226650Y-481712D01*
X227350Y-480913D01*
G01X232250Y-481979D02*
Y-476646D01*
G01Y-477712D02*
X232750Y-477179D01*
X233250Y-476779D01*
X233950Y-476646D01*
X234450Y-476779D01*
X235050Y-477179D01*
G01X223350Y-531979D02*
Y-523979D01*
X227950Y-531979D01*
Y-523979D01*
G01X233650Y-526646D02*
Y-531979D01*
G01Y-524512D02*
X233450Y-524379D01*
Y-524112D01*
X233650Y-523979D01*
X233850Y-524112D01*
Y-524379D01*
X233650Y-524512D01*
G01X239950Y-531979D02*
Y-526646D01*
G01Y-527979D02*
X240350Y-527312D01*
X240950Y-526779D01*
X241750Y-526646D01*
X242450Y-526779D01*
X243050Y-527312D01*
X243350Y-528246D01*
Y-531979D01*
G01X251450D02*
Y-526646D01*
G01Y-527579D02*
X251050Y-527046D01*
X250450Y-526779D01*
X249750Y-526646D01*
X249050Y-526912D01*
X248450Y-527446D01*
X248050Y-528246D01*
X247850Y-529312D01*
X248050Y-530379D01*
X248450Y-531179D01*
X249050Y-531712D01*
X249750Y-531979D01*
X250450Y-531846D01*
X251050Y-531446D01*
X251450Y-530913D01*
G01X220979Y-503836D02*
X222979D01*
Y-506236D01*
X222379Y-507036D01*
X221679Y-507569D01*
X220679Y-507836D01*
X219679Y-507569D01*
X218979Y-507036D01*
X218379Y-506236D01*
X217979Y-505303D01*
X217779Y-504236D01*
Y-503303D01*
X217979Y-502503D01*
X218379Y-501569D01*
X218979Y-500769D01*
X219579Y-500236D01*
X220379Y-499836D01*
X221079D01*
X221879Y-500103D01*
X222479Y-500636D01*
G01X226079Y-507836D02*
Y-499836D01*
X230679Y-507836D01*
Y-499836D01*
G01X234179Y-507836D02*
Y-499836D01*
X236179D01*
X236979Y-500236D01*
X237579Y-500769D01*
X238079Y-501569D01*
X238479Y-502503D01*
X238579Y-503836D01*
X238479Y-505169D01*
X238079Y-506103D01*
X237579Y-506903D01*
X236979Y-507436D01*
X236179Y-507836D01*
X234179D01*
G01X242179Y-506636D02*
X242779Y-507303D01*
X243479Y-507703D01*
X244379Y-507836D01*
X245279Y-507569D01*
X245979Y-507036D01*
X246479Y-506103D01*
X246579Y-505036D01*
X246379Y-503969D01*
X245879Y-503303D01*
X245179Y-502769D01*
X244479Y-502636D01*
X243779Y-502769D01*
X242879Y-503303D01*
X243179Y-499836D01*
X245879D01*
G01X255179Y-484136D02*
Y-476136D01*
X253979Y-477736D01*
G01Y-484136D02*
X256379D01*
G01X260979Y-482536D02*
X261579Y-483469D01*
X262379Y-484003D01*
X263279Y-484136D01*
X264079Y-484003D01*
X264879Y-483336D01*
X265379Y-482536D01*
X265479Y-481736D01*
X265279Y-480803D01*
X264579Y-480136D01*
X263879Y-479869D01*
X262979D01*
G01X263879D02*
X264479Y-479469D01*
X264979Y-478803D01*
X265179Y-478003D01*
X264979Y-477203D01*
X264479Y-476536D01*
X263579Y-476136D01*
X262679Y-476269D01*
X261779Y-476803D01*
G01X326250Y-525312D02*
X326850Y-524512D01*
X327550Y-524112D01*
X328350Y-523979D01*
X329350Y-524246D01*
X330050Y-524912D01*
X330250Y-525712D01*
X330150Y-526513D01*
X329750Y-527179D01*
X327750Y-528512D01*
X326850Y-529446D01*
X326250Y-530779D01*
X326050Y-531979D01*
X330250D01*
G01X336150Y-523979D02*
X335350Y-524246D01*
X334750Y-524912D01*
X334350Y-525712D01*
X334050Y-526779D01*
X333950Y-527979D01*
X334050Y-529179D01*
X334350Y-530246D01*
X334750Y-531046D01*
X335350Y-531712D01*
X336150Y-531979D01*
X336950Y-531712D01*
X337550Y-531046D01*
X337950Y-530246D01*
X338250Y-529179D01*
X338350Y-527979D01*
X338250Y-526779D01*
X337950Y-525712D01*
X337550Y-524912D01*
X336950Y-524246D01*
X336150Y-523979D01*
G01X342250Y-525312D02*
X342850Y-524512D01*
X343550Y-524112D01*
X344350Y-523979D01*
X345350Y-524246D01*
X346050Y-524912D01*
X346250Y-525712D01*
X346150Y-526513D01*
X345750Y-527179D01*
X343750Y-528512D01*
X342850Y-529446D01*
X342250Y-530779D01*
X342050Y-531979D01*
X346250D01*
G01X349950Y-530379D02*
X350550Y-531312D01*
X351350Y-531846D01*
X352250Y-531979D01*
X353050Y-531846D01*
X353850Y-531179D01*
X354350Y-530379D01*
X354450Y-529579D01*
X354250Y-528646D01*
X353550Y-527979D01*
X352850Y-527712D01*
X351950D01*
G01X352850D02*
X353450Y-527312D01*
X353950Y-526646D01*
X354150Y-525846D01*
X353950Y-525046D01*
X353450Y-524379D01*
X352550Y-523979D01*
X351650Y-524112D01*
X350750Y-524646D01*
G01X358350Y-532246D02*
X361950Y-523979D01*
G01X368150D02*
X367350Y-524246D01*
X366750Y-524912D01*
X366350Y-525712D01*
X366050Y-526779D01*
X365950Y-527979D01*
X366050Y-529179D01*
X366350Y-530246D01*
X366750Y-531046D01*
X367350Y-531712D01*
X368150Y-531979D01*
X368950Y-531712D01*
X369550Y-531046D01*
X369950Y-530246D01*
X370250Y-529179D01*
X370350Y-527979D01*
X370250Y-526779D01*
X369950Y-525712D01*
X369550Y-524912D01*
X368950Y-524246D01*
X368150Y-523979D01*
G01X373950Y-530379D02*
X374550Y-531312D01*
X375350Y-531846D01*
X376250Y-531979D01*
X377050Y-531846D01*
X377850Y-531179D01*
X378350Y-530379D01*
X378450Y-529579D01*
X378250Y-528646D01*
X377550Y-527979D01*
X376850Y-527712D01*
X375950D01*
G01X376850D02*
X377450Y-527312D01*
X377950Y-526646D01*
X378150Y-525846D01*
X377950Y-525046D01*
X377450Y-524379D01*
X376550Y-523979D01*
X375650Y-524112D01*
X374750Y-524646D01*
G01X382350Y-532246D02*
X385950Y-523979D01*
G01X390250Y-525312D02*
X390850Y-524512D01*
X391550Y-524112D01*
X392350Y-523979D01*
X393350Y-524246D01*
X394050Y-524912D01*
X394250Y-525712D01*
X394150Y-526513D01*
X393750Y-527179D01*
X391750Y-528512D01*
X390850Y-529446D01*
X390250Y-530779D01*
X390050Y-531979D01*
X394250D01*
G01X401350D02*
Y-523979D01*
X397650Y-529712D01*
X402650D01*
G01X325950Y-506979D02*
Y-498979D01*
X327950D01*
X328750Y-499379D01*
X329350Y-499912D01*
X329850Y-500712D01*
X330250Y-501646D01*
X330350Y-502979D01*
X330250Y-504312D01*
X329850Y-505246D01*
X329350Y-506046D01*
X328750Y-506579D01*
X327950Y-506979D01*
X325950D01*
G01X333650D02*
X336150Y-498979D01*
X338650Y-506979D01*
G01X337750Y-504179D02*
X334550D01*
G01X344150Y-498979D02*
X343350Y-499246D01*
X342750Y-499912D01*
X342350Y-500712D01*
X342050Y-501779D01*
X341950Y-502979D01*
X342050Y-504179D01*
X342350Y-505246D01*
X342750Y-506046D01*
X343350Y-506712D01*
X344150Y-506979D01*
X344950Y-506712D01*
X345550Y-506046D01*
X345950Y-505246D01*
X346250Y-504179D01*
X346350Y-502979D01*
X346250Y-501779D01*
X345950Y-500712D01*
X345550Y-499912D01*
X344950Y-499246D01*
X344150Y-498979D01*
G01X350250Y-506979D02*
Y-498979D01*
X354050D01*
G01X352650Y-502846D02*
X350250D01*
G01X360150Y-498979D02*
X359350Y-499246D01*
X358750Y-499912D01*
X358350Y-500712D01*
X358050Y-501779D01*
X357950Y-502979D01*
X358050Y-504179D01*
X358350Y-505246D01*
X358750Y-506046D01*
X359350Y-506712D01*
X360150Y-506979D01*
X360950Y-506712D01*
X361550Y-506046D01*
X361950Y-505246D01*
X362250Y-504179D01*
X362350Y-502979D01*
X362250Y-501779D01*
X361950Y-500712D01*
X361550Y-499912D01*
X360950Y-499246D01*
X360150Y-498979D01*
G01X368150D02*
Y-506979D01*
G01X365850Y-498979D02*
X370450D01*
G01X373550Y-506979D02*
Y-498979D01*
X376150Y-505646D01*
X378750Y-498979D01*
Y-506979D01*
G01X384950Y-502712D02*
X385350Y-502312D01*
X385650Y-501646D01*
X385850Y-500712D01*
X385650Y-499912D01*
X385250Y-499379D01*
X384550Y-498979D01*
X381850D01*
Y-506979D01*
X385150D01*
X385850Y-506446D01*
X386250Y-505646D01*
X386450Y-504712D01*
X386250Y-503779D01*
X385650Y-502979D01*
X384950Y-502712D01*
X381850D01*
G01X390950Y-498979D02*
X393350D01*
G01X392150D02*
Y-506979D01*
G01X390950D02*
X393350D01*
G01X398150Y-505379D02*
X398650Y-506179D01*
X399250Y-506712D01*
X399950Y-506979D01*
X400750Y-506712D01*
X401350Y-506179D01*
X401950Y-505379D01*
X402150Y-504312D01*
Y-498979D01*
G01X408150D02*
X407350Y-499246D01*
X406750Y-499912D01*
X406350Y-500712D01*
X406050Y-501779D01*
X405950Y-502979D01*
X406050Y-504179D01*
X406350Y-505246D01*
X406750Y-506046D01*
X407350Y-506712D01*
X408150Y-506979D01*
X408950Y-506712D01*
X409550Y-506046D01*
X409950Y-505246D01*
X410250Y-504179D01*
X410350Y-502979D01*
X410250Y-501779D01*
X409950Y-500712D01*
X409550Y-499912D01*
X408950Y-499246D01*
X408150Y-498979D01*
G01X343750Y-481979D02*
Y-473979D01*
X347550D01*
G01X346150Y-477846D02*
X343750D01*
G01X353650Y-473979D02*
X352850Y-474246D01*
X352250Y-474912D01*
X351850Y-475712D01*
X351550Y-476779D01*
X351450Y-477979D01*
X351550Y-479179D01*
X351850Y-480246D01*
X352250Y-481046D01*
X352850Y-481712D01*
X353650Y-481979D01*
X354450Y-481712D01*
X355050Y-481046D01*
X355450Y-480246D01*
X355750Y-479179D01*
X355850Y-477979D01*
X355750Y-476779D01*
X355450Y-475712D01*
X355050Y-474912D01*
X354450Y-474246D01*
X353650Y-473979D01*
G01X361650D02*
Y-481979D01*
G01X359350Y-473979D02*
X363950D01*
G01X366650Y-484646D02*
X372650D01*
G01X375050Y-481979D02*
Y-473979D01*
X377650Y-480646D01*
X380250Y-473979D01*
Y-481979D01*
G01X386450Y-477712D02*
X386850Y-477312D01*
X387150Y-476646D01*
X387350Y-475712D01*
X387150Y-474912D01*
X386750Y-474379D01*
X386050Y-473979D01*
X383350D01*
Y-481979D01*
X386650D01*
X387350Y-481446D01*
X387750Y-480646D01*
X387950Y-479712D01*
X387750Y-478779D01*
X387150Y-477979D01*
X386450Y-477712D01*
X383350D01*
G01X390650Y-484646D02*
X396650D01*
G01X403650Y-481979D02*
X399650D01*
Y-473979D01*
X403650D01*
G01X402050Y-477846D02*
X399650D01*
G01X407050Y-481979D02*
Y-473979D01*
X409650Y-480646D01*
X412250Y-473979D01*
Y-481979D01*
G01X417650D02*
X418350Y-481846D01*
X419150Y-481446D01*
X419650Y-480779D01*
X419850Y-479846D01*
X419650Y-478913D01*
X419050Y-478112D01*
X418150Y-477712D01*
X417150D01*
X416550Y-477446D01*
X416050Y-476779D01*
X415850Y-475846D01*
X416150Y-474912D01*
X416850Y-474246D01*
X417650Y-473979D01*
X418450Y-474246D01*
X419150Y-474912D01*
X419450Y-475846D01*
X419250Y-476779D01*
X418750Y-477446D01*
X418150Y-477712D01*
X417150D01*
X416250Y-478112D01*
X415650Y-478913D01*
X415450Y-479846D01*
X415650Y-480779D01*
X416150Y-481446D01*
X416950Y-481846D01*
X417650Y-481979D01*
G01X423950Y-481046D02*
X424650Y-481712D01*
X425450Y-481979D01*
X426250Y-481712D01*
X426950Y-480913D01*
X427450Y-479712D01*
X427650Y-478512D01*
Y-477046D01*
X427450Y-475846D01*
X426950Y-474779D01*
X426350Y-474246D01*
X425650Y-473979D01*
X424850Y-474246D01*
X424250Y-474779D01*
X423850Y-475579D01*
X423650Y-476646D01*
X423850Y-477579D01*
X424350Y-478512D01*
X424950Y-479046D01*
X425650Y-479179D01*
X426450Y-478913D01*
X427050Y-478246D01*
X427650Y-477046D01*
G01X433650Y-473979D02*
X432850Y-474246D01*
X432250Y-474912D01*
X431850Y-475712D01*
X431550Y-476779D01*
X431450Y-477979D01*
X431550Y-479179D01*
X431850Y-480246D01*
X432250Y-481046D01*
X432850Y-481712D01*
X433650Y-481979D01*
X434450Y-481712D01*
X435050Y-481046D01*
X435450Y-480246D01*
X435750Y-479179D01*
X435850Y-477979D01*
X435750Y-476779D01*
X435450Y-475712D01*
X435050Y-474912D01*
X434450Y-474246D01*
X433650Y-473979D01*
G01X439450Y-481979D02*
Y-473979D01*
G01X443250D02*
X439450Y-478913D01*
G01X443850Y-481979D02*
X441150Y-476646D01*
G01X414650Y-534979D02*
Y-526979D01*
X413450Y-528579D01*
G01Y-534979D02*
X415850D01*
G01X420750Y-531646D02*
X421450Y-530712D01*
X422050Y-530179D01*
X422850Y-529912D01*
X423550Y-530179D01*
X424050Y-530712D01*
X424450Y-531512D01*
X424550Y-532446D01*
X424450Y-533246D01*
X424050Y-534046D01*
X423450Y-534712D01*
X422750Y-534979D01*
X421950Y-534712D01*
X421250Y-533913D01*
X420850Y-532712D01*
X420750Y-531379D01*
X420950Y-529646D01*
X421250Y-528712D01*
X421750Y-527779D01*
X422450Y-527112D01*
X423150Y-526979D01*
X423850Y-527246D01*
X424350Y-527912D01*
G01X430650Y-535246D02*
X430450Y-535112D01*
Y-534846D01*
X430650Y-534712D01*
X430850Y-534846D01*
Y-535112D01*
X430650Y-535246D01*
G01X436750Y-531646D02*
X437450Y-530712D01*
X438050Y-530179D01*
X438850Y-529912D01*
X439550Y-530179D01*
X440050Y-530712D01*
X440450Y-531512D01*
X440550Y-532446D01*
X440450Y-533246D01*
X440050Y-534046D01*
X439450Y-534712D01*
X438750Y-534979D01*
X437950Y-534712D01*
X437250Y-533913D01*
X436850Y-532712D01*
X436750Y-531379D01*
X436950Y-529646D01*
X437250Y-528712D01*
X437750Y-527779D01*
X438450Y-527112D01*
X439150Y-526979D01*
X439850Y-527246D01*
X440350Y-527912D01*
G01X459650Y-534979D02*
Y-526979D01*
X458450Y-528579D01*
G01Y-534979D02*
X460850D01*
G01X467450D02*
X467650Y-533246D01*
X467950Y-531779D01*
X468350Y-530446D01*
X468850Y-528979D01*
X469650Y-526979D01*
X465650D01*
G01X475650Y-535246D02*
X475450Y-535112D01*
Y-534846D01*
X475650Y-534712D01*
X475850Y-534846D01*
Y-535112D01*
X475650Y-535246D01*
G01X481750Y-528312D02*
X482350Y-527512D01*
X483050Y-527112D01*
X483850Y-526979D01*
X484850Y-527246D01*
X485550Y-527912D01*
X485750Y-528712D01*
X485650Y-529513D01*
X485250Y-530179D01*
X483250Y-531512D01*
X482350Y-532446D01*
X481750Y-533779D01*
X481550Y-534979D01*
X485750D01*
G01X479650Y-508379D02*
X480150Y-509179D01*
X480750Y-509712D01*
X481450Y-509979D01*
X482250Y-509712D01*
X482850Y-509179D01*
X483450Y-508379D01*
X483650Y-507312D01*
Y-501979D01*
M02*
